G04 ================== begin FILE IDENTIFICATION RECORD ==================*
G04 Layout Name:  16368-sb.brd*
G04 Film Name:    NOTICE*
G04 File Format:  Gerber RS274X*
G04 File Origin:  Cadence Allegro 16.5-S056*
G04 Origin Date:  Tue Feb 07 09:07:42 2017*
G04 *
G04 Layer:  MANUFACTURING/THERMAL*
G04 *
G04 Offset:    (0.00 0.00)*
G04 Mirror:    No*
G04 Mode:      Positive*
G04 Rotation:  0*
G04 FullContactRelief:  No*
G04 UndefLineWidth:     6.00*
G04 ================== end FILE IDENTIFICATION RECORD ====================*
%FSLAX35Y35*MOIN*%
%IR0*IPPOS*OFA0.00000B0.00000*MIA0B0*SFA1.00000B1.00000*%
%ADD10C,.004*%
%ADD11C,.006*%
%ADD12C,.0033*%
%ADD13C,.008*%
%ADD14C,.0055*%
G75*
%LPD*%
G75*
G36*
G01X301800Y213890D02*
G02X352500Y214150I25558J-40503D01*
G01X341350Y192820D01*
X312850D01*
X301800Y213890D01*
G37*
G36*
G01X298620Y274980D02*
X307300D01*
G03X341410Y274970I17058J11442D01*
G01X348960D01*
X338090Y253970D01*
X309590D01*
X298620Y274980D01*
G37*
G54D10*
G01X770009Y177889D02*
X790009D01*
G01X820009Y167889D02*
X770009D01*
G01D02*
Y177889D01*
G01Y257889D02*
X790009D01*
G01X770009Y247889D02*
Y257889D01*
G01X790009Y247889D02*
X770009D01*
G01Y217889D02*
X790009D01*
G01X770009Y207889D02*
Y217889D01*
G01X790009Y207889D02*
X770009D01*
G01Y297889D02*
X810009D01*
G01X770009Y287889D02*
Y297889D01*
G01X790009Y287889D02*
X770009D01*
G01X852594Y151868D02*
Y155868D01*
G01X840009Y167889D02*
X890009D01*
G01X840009Y225249D02*
Y167889D01*
G01X859454Y153868D02*
X840594D01*
G01X852594Y155868D02*
X840594Y153868D01*
G01Y141868D02*
Y161868D01*
G01Y153868D02*
X852594Y151868D01*
G01X820594Y153868D02*
X808594Y155868D01*
G01X820009Y224740D02*
Y167889D01*
G01X820594Y161868D02*
Y141868D01*
G01X808594Y155868D02*
Y151868D01*
G01D02*
X820594Y153868D01*
G01X790009Y177889D02*
Y207889D01*
G01X796594Y153868D02*
X820594D01*
G01X845009Y225249D02*
X961000D01*
G01X850009Y297889D02*
Y235249D01*
G01D02*
X840009Y225249D01*
G01X810005Y234744D02*
X810009Y234740D01*
G01Y297889D02*
Y234740D01*
G01D02*
X820009Y224740D01*
G01X790009Y257889D02*
Y287889D01*
G01Y217889D02*
Y247889D01*
G01X850514Y319548D02*
Y299548D01*
G01Y307548D02*
X859374D01*
G01X838514Y309548D02*
Y305548D01*
G01X850514Y307548D02*
X838514Y309548D01*
G01Y305548D02*
X850514Y307548D01*
G01X890009Y297889D02*
X850009D01*
G01X810514Y319548D02*
Y299548D01*
G01X822514Y305548D02*
Y309548D01*
G01X810514Y307548D02*
X822514Y305548D01*
G01Y309548D02*
X810514Y307548D01*
G01D02*
X850514D01*
G01X890009Y167889D02*
Y177889D01*
G01X870009D02*
Y207889D01*
G01X890009Y177889D02*
X870009D01*
G01X895009Y217889D02*
X961000D01*
G01X890009Y247889D02*
Y257889D01*
G01Y207889D02*
X890000Y217800D01*
G01X870009Y257889D02*
Y287889D01*
G01X890009Y257889D02*
X870009D01*
G01Y247889D02*
X890009D01*
G01X870009Y217889D02*
Y247889D01*
G01X890009Y217889D02*
X870009D01*
G01Y207889D02*
X890009D01*
G01Y287889D02*
Y297889D01*
G01X870009Y287889D02*
X890009D01*
G01X956000Y193889D02*
Y217889D01*
G01X954000Y237249D02*
X956000Y225249D01*
X958000Y237249D01*
X954000D01*
G01X956000Y249249D02*
Y225249D01*
G01X958000Y205889D02*
X956000Y217889D01*
X954000Y205889D01*
X958000D01*
G01X1101654Y209388D02*
Y179388D01*
G01D02*
X1081654D01*
G01Y169388D02*
X1121654D01*
G01X1081654Y179388D02*
Y169388D01*
G01X1101654Y289388D02*
Y259388D01*
G01Y249388D02*
Y219388D01*
G01X1081654Y249388D02*
X1101654D01*
G01X1081654Y259388D02*
Y249388D01*
G01X1101654Y259388D02*
X1081654D01*
G01Y209388D02*
X1101654D01*
G01X1081654Y219388D02*
Y209388D01*
G01X1101654Y219388D02*
X1081654D01*
G01X1107654Y319388D02*
X1131654D01*
G01Y299388D02*
X1081654D01*
G01Y289388D02*
X1101654D01*
G01X1081654Y299388D02*
Y289388D01*
G01X1181654Y179388D02*
X1201654D01*
G01X1181654Y209388D02*
Y179388D01*
G01X1161654Y169388D02*
Y232537D01*
G01X1201654Y169388D02*
X1161654D01*
G01X1149654Y153388D02*
Y149388D01*
G01X1161654Y151388D02*
X1149654Y153388D01*
G01Y149388D02*
X1161654Y151388D01*
G01D02*
X1170514D01*
G01X1161654Y163388D02*
Y143388D01*
G01X1121654Y169388D02*
Y232028D01*
G01X1133654Y149388D02*
Y153388D01*
G01X1121654Y151388D02*
X1133654Y149388D01*
G01Y153388D02*
X1121654Y151388D01*
G01D02*
X1161654D01*
G01X1121654Y163388D02*
Y143388D01*
G01X1201654Y249388D02*
X1181654D01*
G01Y259388D02*
X1201654D01*
G01X1181654Y289388D02*
Y259388D01*
G01X1201654Y209388D02*
X1181654D01*
G01Y219388D02*
X1201654D01*
G01X1181654Y249388D02*
Y219388D01*
G01X1161658Y232533D02*
X1161654Y232537D01*
G01X1151654Y242537D02*
Y299388D01*
G01X1161654Y232537D02*
X1151654Y242537D01*
G01X1131654Y242028D02*
Y299388D01*
G01X1121654Y232028D02*
X1131654Y242028D01*
G01X1163654Y317388D02*
Y321388D01*
G01X1201654Y289388D02*
X1181654D01*
G01X1170514Y319388D02*
X1151654D01*
G01D02*
X1163654Y317388D01*
G01Y321388D02*
X1151654Y319388D01*
G01Y307388D02*
Y327388D01*
G01Y299388D02*
X1201654D01*
G01X1119654Y321388D02*
Y317388D01*
G01X1131654Y319388D02*
X1119654Y321388D01*
G01Y317388D02*
X1131654Y319388D01*
G01Y327388D02*
Y307388D01*
G01X1201654Y179388D02*
Y169388D01*
G01Y259388D02*
Y249388D01*
G01Y219388D02*
Y209388D01*
G01Y299388D02*
Y289388D01*
G54D11*
G01X4300Y524700D02*
X4250D01*
G01X54300Y770700D02*
X54250D01*
G01X285090Y269970D02*
X280090D01*
Y243970D01*
X285090D01*
G01X283590Y340830D02*
X278590D01*
Y314830D01*
X283590D01*
G01X288350Y208820D02*
X283350D01*
Y182820D01*
X288350D01*
G01Y187820D02*
X307850D01*
X296850Y208820D01*
X288350D01*
Y213820D01*
X301850D01*
X312850Y192820D01*
X341350D01*
X352350Y213820D01*
X365850D01*
Y208820D01*
X357350D01*
X346350Y187820D01*
X365850D01*
G01X288350D02*
Y182820D01*
X365850D01*
Y187820D01*
G01X357370Y214130D02*
X388140D01*
G01X332370Y221310D02*
X388140D01*
G01X329290Y266000D02*
X387990D01*
G01X346210Y275010D02*
X387990D01*
G01X362590Y269970D02*
X367590D01*
Y243970D01*
X362590D01*
G01X285090Y248970D02*
X304590D01*
X293590Y269970D01*
X285090D01*
Y274970D01*
X298590D01*
X309590Y253970D01*
X338090D01*
X349090Y274970D01*
X362590D01*
Y269970D01*
X354090D01*
X343090Y248970D01*
X362590D01*
G01X285090D02*
Y243970D01*
X362590D01*
Y248970D01*
G01X329590Y306830D02*
X341590Y308830D01*
X329590Y310830D01*
Y306830D01*
G01X339890Y308830D02*
X341590D01*
G01X315090Y310830D02*
X303090Y308830D01*
X315090Y306830D01*
Y310830D01*
G01X306290Y308830D02*
X303090D01*
G01X340590Y350830D02*
X352590Y352830D01*
X340590Y354830D01*
Y350830D01*
G01X334890Y352830D02*
X352590D01*
G01X304090Y354830D02*
X292090Y352830D01*
X304090Y350830D01*
Y354830D01*
G01X311290Y352830D02*
X292090D01*
G01X339590Y308830D02*
X304090D01*
G01X361090Y340830D02*
X366090D01*
Y314830D01*
X361090D01*
G01X283590Y319830D02*
Y314830D01*
X361090D01*
Y319830D01*
G01X283590D02*
X303090D01*
X292090Y340830D01*
X283590D01*
Y345830D01*
X297090D01*
X308090Y324830D01*
X336590D01*
X347590Y345830D01*
X361090D01*
Y340830D01*
X352590D01*
X341590Y319830D01*
X361090D01*
G01X365850Y208820D02*
X370850D01*
Y182820D01*
X365850D01*
G01X385140Y233310D02*
X383140Y221310D01*
X381140Y233310D01*
X385140D01*
G01X383140Y237850D02*
Y221310D01*
G01X385140Y202130D02*
X383140Y214130D01*
X381140Y202130D01*
X385140D01*
G01X383140Y197250D02*
Y214130D01*
G01X384990Y287010D02*
X382990Y275010D01*
X380990Y287010D01*
X384990D01*
G01X382990Y275010D02*
Y290150D01*
G01X384990Y254000D02*
X382990Y266000D01*
X380990Y254000D01*
X384990D01*
G01X382990Y250500D02*
Y266000D01*
G01X849500Y-12500D02*
Y59500D01*
X893500D01*
Y-12500D01*
X849500D01*
G01Y-12451D02*
X821000Y-12500D01*
G01X837503Y-14472D02*
X849500Y-12451D01*
X837497Y-10472D01*
X837503Y-14472D01*
G01X864500Y72000D02*
X849500Y69500D01*
X864500Y67000D01*
Y72000D01*
G01X893500Y69500D02*
X849500D01*
G01Y64500D02*
Y79500D01*
G01X830000Y693125D02*
Y725829D01*
G01X827500Y639629D02*
X830000Y624629D01*
X832500Y639629D01*
X827500D01*
G01X830000Y661875D02*
Y624629D01*
G01X931340D02*
X820000D01*
G01X832500Y710829D02*
X830000Y725829D01*
X827500Y710829D01*
X832500D01*
G01X846340Y725829D02*
X820000D01*
G01X932000Y2500D02*
X934500Y-12500D01*
X937000Y2500D01*
X932000D01*
G01X934500Y11875D02*
Y-12500D01*
G01X903500D02*
X944500D01*
G01X937000Y44500D02*
X934500Y59500D01*
X932000Y44500D01*
X937000D01*
G01X934500Y43125D02*
Y59500D01*
G01X903500D02*
X944500D01*
G01X878500Y67000D02*
X893500Y69500D01*
X878500Y72000D01*
Y67000D01*
G01X901475Y69500D02*
X893500D01*
G01Y64500D02*
Y79500D01*
G01X1156654Y242537D02*
X1274500D01*
G01X1114953Y628479D02*
X1131500Y617000D01*
X1132500D01*
G01X1119916Y626861D02*
X1114953Y628479D01*
X1118206Y624397D01*
X1119916Y626861D01*
G01X1267500Y261388D02*
X1269500Y249388D01*
X1271500Y261388D01*
X1267500D01*
G01X1269500Y277200D02*
Y249388D01*
G01X1271500Y230537D02*
X1269500Y242537D01*
X1267500Y230537D01*
X1271500D01*
G01X1269500Y218537D02*
Y242537D01*
G01X1206654Y249388D02*
X1274500D01*
G01X0Y716000D02*
Y-69500D01*
G01D02*
X694500D01*
G01X11750Y-48833D02*
X12417Y-49250D01*
X13167Y-49500D01*
X13833D01*
X14500Y-49250D01*
X15000Y-48833D01*
X15250Y-48250D01*
X15083Y-47667D01*
X14667Y-47167D01*
X13917Y-46833D01*
X12917Y-46667D01*
X12333Y-46333D01*
X12083Y-45750D01*
X12250Y-45167D01*
X12667Y-44750D01*
X13250Y-44500D01*
X13833D01*
X14417Y-44667D01*
X14917Y-45083D01*
G01X19100Y-46167D02*
Y-49500D01*
G01Y-44833D02*
X18933Y-44750D01*
Y-44583D01*
X19100Y-44500D01*
X19267Y-44583D01*
Y-44750D01*
X19100Y-44833D01*
G01X24700Y-49500D02*
Y-44500D01*
G01X28883Y-49500D02*
Y-44500D01*
G01X31550Y-46167D02*
X28883Y-48083D01*
G01X29967Y-47333D02*
X31717Y-49500D01*
G01X34650Y-48917D02*
X35067Y-49250D01*
X35650Y-49500D01*
X36150D01*
X36650Y-49333D01*
X36983Y-49083D01*
X37150Y-48750D01*
X37067Y-48250D01*
X36733Y-48000D01*
X35233Y-47500D01*
X34900Y-46917D01*
X35067Y-46500D01*
X35400Y-46250D01*
X35900Y-46167D01*
X36400Y-46250D01*
X36900Y-46500D01*
G01X42833Y-46583D02*
X42250Y-46250D01*
X41750Y-46167D01*
X41083Y-46333D01*
X40583Y-46667D01*
X40250Y-47250D01*
X40167Y-47833D01*
X40250Y-48417D01*
X40583Y-48917D01*
X41083Y-49333D01*
X41750Y-49500D01*
X42333Y-49333D01*
X42833Y-49000D01*
G01X45933Y-49500D02*
Y-46167D01*
G01Y-46833D02*
X46350Y-46500D01*
X46767Y-46250D01*
X47350Y-46167D01*
X47767Y-46250D01*
X48267Y-46500D01*
G01X51450Y-47250D02*
X54117D01*
X53867Y-46667D01*
X53450Y-46333D01*
X52867Y-46167D01*
X52283Y-46250D01*
X51783Y-46500D01*
X51450Y-47083D01*
X51283Y-47583D01*
Y-48083D01*
X51450Y-48583D01*
X51867Y-49083D01*
X52367Y-49417D01*
X52950Y-49500D01*
X53533Y-49333D01*
X54117Y-48833D01*
G01X57050Y-47250D02*
X59717D01*
X59467Y-46667D01*
X59050Y-46333D01*
X58467Y-46167D01*
X57883Y-46250D01*
X57383Y-46500D01*
X57050Y-47083D01*
X56883Y-47583D01*
Y-48083D01*
X57050Y-48583D01*
X57467Y-49083D01*
X57967Y-49417D01*
X58550Y-49500D01*
X59133Y-49333D01*
X59717Y-48833D01*
G01X62483Y-49500D02*
Y-46167D01*
G01Y-47000D02*
X62817Y-46583D01*
X63317Y-46250D01*
X63983Y-46167D01*
X64567Y-46250D01*
X65067Y-46583D01*
X65317Y-47167D01*
Y-49500D01*
G01X11750Y-3833D02*
X12417Y-4250D01*
X13167Y-4500D01*
X13833D01*
X14500Y-4250D01*
X15000Y-3833D01*
X15250Y-3250D01*
X15083Y-2667D01*
X14667Y-2167D01*
X13917Y-1833D01*
X12917Y-1667D01*
X12333Y-1333D01*
X12083Y-750D01*
X12250Y-167D01*
X12667Y250D01*
X13250Y500D01*
X13833D01*
X14417Y333D01*
X14917Y-83D01*
G01X19100Y-4500D02*
X18600Y-4417D01*
X18100Y-4083D01*
X17767Y-3500D01*
X17600Y-2833D01*
X17767Y-2167D01*
X18100Y-1583D01*
X18600Y-1250D01*
X19100Y-1167D01*
X19600Y-1250D01*
X20100Y-1583D01*
X20433Y-2167D01*
X20517Y-2833D01*
X20433Y-3500D01*
X20100Y-4083D01*
X19600Y-4417D01*
X19100Y-4500D01*
G01X24700D02*
Y500D01*
G01X31800D02*
Y-4500D01*
G01Y-3750D02*
X31467Y-4167D01*
X30967Y-4417D01*
X30383Y-4500D01*
X29717Y-4333D01*
X29217Y-3917D01*
X28883Y-3417D01*
X28800Y-2833D01*
X28883Y-2250D01*
X29217Y-1750D01*
X29717Y-1333D01*
X30383Y-1167D01*
X30967Y-1250D01*
X31383Y-1417D01*
X31800Y-1750D01*
G01X34650Y-2250D02*
X37317D01*
X37067Y-1667D01*
X36650Y-1333D01*
X36067Y-1167D01*
X35483Y-1250D01*
X34983Y-1500D01*
X34650Y-2083D01*
X34483Y-2583D01*
Y-3083D01*
X34650Y-3583D01*
X35067Y-4083D01*
X35567Y-4417D01*
X36150Y-4500D01*
X36733Y-4333D01*
X37317Y-3833D01*
G01X40333Y-4500D02*
Y-1167D01*
G01Y-1833D02*
X40750Y-1500D01*
X41167Y-1250D01*
X41750Y-1167D01*
X42167Y-1250D01*
X42667Y-1500D01*
G01X50200Y-4500D02*
Y-1167D01*
G01Y-2083D02*
X50450Y-1667D01*
X50867Y-1333D01*
X51450Y-1167D01*
X52033Y-1333D01*
X52450Y-1667D01*
X52700Y-2083D01*
Y-4500D01*
G01Y-2083D02*
X52950Y-1667D01*
X53367Y-1333D01*
X53950Y-1167D01*
X54533Y-1333D01*
X54950Y-1667D01*
X55200Y-2167D01*
Y-4500D01*
G01X59800D02*
Y-1167D01*
G01Y-1750D02*
X59467Y-1417D01*
X58967Y-1250D01*
X58383Y-1167D01*
X57800Y-1333D01*
X57300Y-1667D01*
X56967Y-2167D01*
X56800Y-2833D01*
X56967Y-3500D01*
X57300Y-4000D01*
X57800Y-4333D01*
X58383Y-4500D01*
X58967Y-4417D01*
X59467Y-4167D01*
X59800Y-3833D01*
G01X62650Y-3917D02*
X63067Y-4250D01*
X63650Y-4500D01*
X64150D01*
X64650Y-4333D01*
X64983Y-4083D01*
X65150Y-3750D01*
X65067Y-3250D01*
X64733Y-3000D01*
X63233Y-2500D01*
X62900Y-1917D01*
X63067Y-1500D01*
X63400Y-1250D01*
X63900Y-1167D01*
X64400Y-1250D01*
X64900Y-1500D01*
G01X68083Y-4500D02*
Y500D01*
G01X70750Y-1167D02*
X68083Y-3083D01*
G01X69167Y-2333D02*
X70917Y-4500D01*
G01X0Y-24500D02*
X694500D01*
G01X0Y19500D02*
X694500D01*
G01X15167Y64000D02*
X11833D01*
Y69000D01*
X15167D01*
G01X13833Y66583D02*
X11833D01*
G01X19100Y69000D02*
Y64000D01*
G01X17933Y67333D02*
X20267D01*
G01X26033Y66917D02*
X25450Y67250D01*
X24950Y67333D01*
X24283Y67167D01*
X23783Y66833D01*
X23450Y66250D01*
X23367Y65667D01*
X23450Y65083D01*
X23783Y64583D01*
X24283Y64167D01*
X24950Y64000D01*
X25533Y64167D01*
X26033Y64500D01*
G01X28883Y64000D02*
Y69000D01*
G01Y66583D02*
X29300Y67000D01*
X29717Y67250D01*
X30383Y67333D01*
X30883Y67250D01*
X31467Y66917D01*
X31717Y66417D01*
Y64000D01*
G01X15167Y111500D02*
X11833D01*
Y116500D01*
X15167D01*
G01X13833Y114083D02*
X11833D01*
G01X17850Y114833D02*
X20350Y111500D01*
G01Y114833D02*
X17850Y111500D01*
G01X24700Y116500D02*
Y111500D01*
G01X23533Y114833D02*
X25867D01*
G01X29050Y113750D02*
X31717D01*
X31467Y114333D01*
X31050Y114667D01*
X30467Y114833D01*
X29883Y114750D01*
X29383Y114500D01*
X29050Y113917D01*
X28883Y113417D01*
Y112917D01*
X29050Y112417D01*
X29467Y111917D01*
X29967Y111583D01*
X30550Y111500D01*
X31133Y111667D01*
X31717Y112167D01*
G01X34733Y111500D02*
Y114833D01*
G01Y114167D02*
X35150Y114500D01*
X35567Y114750D01*
X36150Y114833D01*
X36567Y114750D01*
X37067Y114500D01*
G01X40083Y111500D02*
Y114833D01*
G01Y114000D02*
X40417Y114417D01*
X40917Y114750D01*
X41583Y114833D01*
X42167Y114750D01*
X42667Y114417D01*
X42917Y113833D01*
Y111500D01*
G01X48600D02*
Y114833D01*
G01Y114250D02*
X48267Y114583D01*
X47767Y114750D01*
X47183Y114833D01*
X46600Y114667D01*
X46100Y114333D01*
X45767Y113833D01*
X45600Y113167D01*
X45767Y112500D01*
X46100Y112000D01*
X46600Y111667D01*
X47183Y111500D01*
X47767Y111583D01*
X48267Y111833D01*
X48600Y112167D01*
G01X52700Y111500D02*
Y116500D01*
G01X63900Y111500D02*
Y116500D01*
G01X71000Y111500D02*
Y114833D01*
G01Y114250D02*
X70667Y114583D01*
X70167Y114750D01*
X69583Y114833D01*
X69000Y114667D01*
X68500Y114333D01*
X68167Y113833D01*
X68000Y113167D01*
X68167Y112500D01*
X68500Y112000D01*
X69000Y111667D01*
X69583Y111500D01*
X70167Y111583D01*
X70667Y111833D01*
X71000Y112167D01*
G01X73350Y110000D02*
X73850Y109833D01*
X74517Y110000D01*
X74933Y110333D01*
X75267Y110750D01*
X75767Y112083D01*
X76850Y114833D01*
G01X74183D02*
X75767Y112083D01*
G01X79450Y113750D02*
X82117D01*
X81867Y114333D01*
X81450Y114667D01*
X80867Y114833D01*
X80283Y114750D01*
X79783Y114500D01*
X79450Y113917D01*
X79283Y113417D01*
Y112917D01*
X79450Y112417D01*
X79867Y111917D01*
X80367Y111583D01*
X80950Y111500D01*
X81533Y111667D01*
X82117Y112167D01*
G01X85133Y111500D02*
Y114833D01*
G01Y114167D02*
X85550Y114500D01*
X85967Y114750D01*
X86550Y114833D01*
X86967Y114750D01*
X87467Y114500D01*
G01X0Y105500D02*
X694500D01*
G01X15333Y146083D02*
X14833Y146333D01*
X14250Y146500D01*
X13583D01*
X12833Y146250D01*
X12250Y145833D01*
X11833Y145333D01*
X11500Y144500D01*
X11417Y143750D01*
X11583Y143000D01*
X11833Y142500D01*
X12333Y142000D01*
X12917Y141667D01*
X13500Y141500D01*
X14083D01*
X14667Y141667D01*
X15167Y141917D01*
X15583Y142250D01*
G01X19100Y141500D02*
X18600Y141583D01*
X18100Y141917D01*
X17767Y142500D01*
X17600Y143167D01*
X17767Y143833D01*
X18100Y144417D01*
X18600Y144750D01*
X19100Y144833D01*
X19600Y144750D01*
X20100Y144417D01*
X20433Y143833D01*
X20517Y143167D01*
X20433Y142500D01*
X20100Y141917D01*
X19600Y141583D01*
X19100Y141500D01*
G01X23200Y139833D02*
Y144833D01*
G01Y144083D02*
X23617Y144500D01*
X24033Y144750D01*
X24700Y144833D01*
X25283Y144750D01*
X25867Y144333D01*
X26117Y143750D01*
X26200Y143167D01*
X26117Y142583D01*
X25867Y142000D01*
X25367Y141667D01*
X24700Y141500D01*
X24117Y141583D01*
X23533Y141833D01*
X23200Y142167D01*
G01X28800Y139833D02*
Y144833D01*
G01Y144083D02*
X29217Y144500D01*
X29633Y144750D01*
X30300Y144833D01*
X30883Y144750D01*
X31467Y144333D01*
X31717Y143750D01*
X31800Y143167D01*
X31717Y142583D01*
X31467Y142000D01*
X30967Y141667D01*
X30300Y141500D01*
X29717Y141583D01*
X29133Y141833D01*
X28800Y142167D01*
G01X34650Y143750D02*
X37317D01*
X37067Y144333D01*
X36650Y144667D01*
X36067Y144833D01*
X35483Y144750D01*
X34983Y144500D01*
X34650Y143917D01*
X34483Y143417D01*
Y142917D01*
X34650Y142417D01*
X35067Y141917D01*
X35567Y141583D01*
X36150Y141500D01*
X36733Y141667D01*
X37317Y142167D01*
G01X40333Y141500D02*
Y144833D01*
G01Y144167D02*
X40750Y144500D01*
X41167Y144750D01*
X41750Y144833D01*
X42167Y144750D01*
X42667Y144500D01*
G01X51033Y141500D02*
Y146500D01*
X53033D01*
X53700Y146250D01*
X54200Y145667D01*
X54367Y145000D01*
X54200Y144333D01*
X53783Y143833D01*
X53033Y143583D01*
X51033D01*
G01X58300Y141500D02*
Y146500D01*
G01X65400Y141500D02*
Y144833D01*
G01Y144250D02*
X65067Y144583D01*
X64567Y144750D01*
X63983Y144833D01*
X63400Y144667D01*
X62900Y144333D01*
X62567Y143833D01*
X62400Y143167D01*
X62567Y142500D01*
X62900Y142000D01*
X63400Y141667D01*
X63983Y141500D01*
X64567Y141583D01*
X65067Y141833D01*
X65400Y142167D01*
G01X69500Y146500D02*
Y141500D01*
G01X68333Y144833D02*
X70667D01*
G01X75100D02*
Y141500D01*
G01Y146167D02*
X74933Y146250D01*
Y146417D01*
X75100Y146500D01*
X75267Y146417D01*
Y146250D01*
X75100Y146167D01*
G01X79283Y141500D02*
Y144833D01*
G01Y144000D02*
X79617Y144417D01*
X80117Y144750D01*
X80783Y144833D01*
X81367Y144750D01*
X81867Y144417D01*
X82117Y143833D01*
Y141500D01*
G01X85133Y140250D02*
X85717Y139917D01*
X86383Y139833D01*
X86967Y139917D01*
X87467Y140333D01*
X87800Y140917D01*
Y144833D01*
G01Y144167D02*
X87467Y144500D01*
X86967Y144750D01*
X86383Y144833D01*
X85717Y144667D01*
X85300Y144333D01*
X84967Y143750D01*
X84800Y143167D01*
X84883Y142667D01*
X85217Y142083D01*
X85717Y141667D01*
X86383Y141500D01*
X86883Y141583D01*
X87467Y141917D01*
X87800Y142250D01*
G01X1500Y175500D02*
X694500D01*
G01X0Y120500D02*
X694500D01*
G01X11667Y459000D02*
Y464000D01*
X13333D01*
X14000Y463750D01*
X14500Y463417D01*
X14917Y462917D01*
X15250Y462333D01*
X15333Y461500D01*
X15250Y460667D01*
X14917Y460083D01*
X14500Y459583D01*
X14000Y459250D01*
X13333Y459000D01*
X11667D01*
G01X17933D02*
Y462333D01*
G01Y461667D02*
X18350Y462000D01*
X18767Y462250D01*
X19350Y462333D01*
X19767Y462250D01*
X20267Y462000D01*
G01X24700Y462333D02*
Y459000D01*
G01Y463667D02*
X24533Y463750D01*
Y463917D01*
X24700Y464000D01*
X24867Y463917D01*
Y463750D01*
X24700Y463667D01*
G01X30300Y459000D02*
Y464000D01*
G01X35900Y459000D02*
Y464000D01*
G01X0Y599000D02*
X694500D01*
G01X9917Y693667D02*
X10417Y694167D01*
X11000Y694417D01*
X11667Y694500D01*
X12500Y694333D01*
X13083Y693917D01*
X13250Y693417D01*
X13167Y692917D01*
X12833Y692500D01*
X11167Y691667D01*
X10417Y691083D01*
X9917Y690250D01*
X9750Y689500D01*
X13250D01*
G01X17100Y689333D02*
X16933Y689417D01*
Y689583D01*
X17100Y689667D01*
X17267Y689583D01*
Y689417D01*
X17100Y689333D01*
G01X22700Y694500D02*
Y689500D01*
G01X20783Y694500D02*
X24617D01*
G01X28300Y689500D02*
X27800Y689583D01*
X27300Y689917D01*
X26967Y690500D01*
X26800Y691167D01*
X26967Y691833D01*
X27300Y692417D01*
X27800Y692750D01*
X28300Y692833D01*
X28800Y692750D01*
X29300Y692417D01*
X29633Y691833D01*
X29717Y691167D01*
X29633Y690500D01*
X29300Y689917D01*
X28800Y689583D01*
X28300Y689500D01*
G01X33900D02*
Y694500D01*
G01X38250Y691750D02*
X40917D01*
X40667Y692333D01*
X40250Y692667D01*
X39667Y692833D01*
X39083Y692750D01*
X38583Y692500D01*
X38250Y691917D01*
X38083Y691417D01*
Y690917D01*
X38250Y690417D01*
X38667Y689917D01*
X39167Y689583D01*
X39750Y689500D01*
X40333Y689667D01*
X40917Y690167D01*
G01X43933Y689500D02*
Y692833D01*
G01Y692167D02*
X44350Y692500D01*
X44767Y692750D01*
X45350Y692833D01*
X45767Y692750D01*
X46267Y692500D01*
G01X52200Y689500D02*
Y692833D01*
G01Y692250D02*
X51867Y692583D01*
X51367Y692750D01*
X50783Y692833D01*
X50200Y692667D01*
X49700Y692333D01*
X49367Y691833D01*
X49200Y691167D01*
X49367Y690500D01*
X49700Y690000D01*
X50200Y689667D01*
X50783Y689500D01*
X51367Y689583D01*
X51867Y689833D01*
X52200Y690167D01*
G01X54883Y689500D02*
Y692833D01*
G01Y692000D02*
X55217Y692417D01*
X55717Y692750D01*
X56383Y692833D01*
X56967Y692750D01*
X57467Y692417D01*
X57717Y691833D01*
Y689500D01*
G01X63233Y692417D02*
X62650Y692750D01*
X62150Y692833D01*
X61483Y692667D01*
X60983Y692333D01*
X60650Y691750D01*
X60567Y691167D01*
X60650Y690583D01*
X60983Y690083D01*
X61483Y689667D01*
X62150Y689500D01*
X62733Y689667D01*
X63233Y690000D01*
G01X66250Y691750D02*
X68917D01*
X68667Y692333D01*
X68250Y692667D01*
X67667Y692833D01*
X67083Y692750D01*
X66583Y692500D01*
X66250Y691917D01*
X66083Y691417D01*
Y690917D01*
X66250Y690417D01*
X66667Y689917D01*
X67167Y689583D01*
X67750Y689500D01*
X68333Y689667D01*
X68917Y690167D01*
G01X78700Y694500D02*
Y689500D01*
G01X77533Y692833D02*
X79867D01*
G01X85800Y689500D02*
Y692833D01*
G01Y692250D02*
X85467Y692583D01*
X84967Y692750D01*
X84383Y692833D01*
X83800Y692667D01*
X83300Y692333D01*
X82967Y691833D01*
X82800Y691167D01*
X82967Y690500D01*
X83300Y690000D01*
X83800Y689667D01*
X84383Y689500D01*
X84967Y689583D01*
X85467Y689833D01*
X85800Y690167D01*
G01X88400Y689500D02*
Y694500D01*
G01Y692000D02*
X88817Y692500D01*
X89317Y692750D01*
X89817Y692833D01*
X90567Y692667D01*
X91067Y692333D01*
X91400Y691750D01*
Y691083D01*
X91233Y690417D01*
X90900Y689917D01*
X90317Y689583D01*
X89817Y689500D01*
X89317Y689583D01*
X88817Y689833D01*
X88400Y690250D01*
G01X95500Y689500D02*
Y694500D01*
G01X99850Y691750D02*
X102517D01*
X102267Y692333D01*
X101850Y692667D01*
X101267Y692833D01*
X100683Y692750D01*
X100183Y692500D01*
X99850Y691917D01*
X99683Y691417D01*
Y690917D01*
X99850Y690417D01*
X100267Y689917D01*
X100767Y689583D01*
X101350Y689500D01*
X101933Y689667D01*
X102517Y690167D01*
G01X106700Y689333D02*
X106533Y689417D01*
Y689583D01*
X106700Y689667D01*
X106867Y689583D01*
Y689417D01*
X106700Y689333D01*
G01Y691583D02*
X106533Y691667D01*
Y691833D01*
X106700Y691917D01*
X106867Y691833D01*
Y691667D01*
X106700Y691583D01*
G01X24960Y626740D02*
X26960D01*
G01X25960D02*
Y621740D01*
G01X24960D02*
X26960D01*
G01X30143D02*
Y625073D01*
G01Y624240D02*
X30477Y624657D01*
X30977Y624990D01*
X31643Y625073D01*
X32227Y624990D01*
X32727Y624657D01*
X32977Y624073D01*
Y621740D01*
G01X35743D02*
Y625073D01*
G01Y624240D02*
X36077Y624657D01*
X36577Y624990D01*
X37243Y625073D01*
X37827Y624990D01*
X38327Y624657D01*
X38577Y624073D01*
Y621740D01*
G01X41510Y623990D02*
X44177D01*
X43927Y624573D01*
X43510Y624907D01*
X42927Y625073D01*
X42343Y624990D01*
X41843Y624740D01*
X41510Y624157D01*
X41343Y623657D01*
Y623157D01*
X41510Y622657D01*
X41927Y622157D01*
X42427Y621823D01*
X43010Y621740D01*
X43593Y621907D01*
X44177Y622407D01*
G01X47193Y621740D02*
Y625073D01*
G01Y624407D02*
X47610Y624740D01*
X48027Y624990D01*
X48610Y625073D01*
X49027Y624990D01*
X49527Y624740D01*
G01X59560Y621740D02*
Y626740D01*
G01X66660Y621740D02*
Y625073D01*
G01Y624490D02*
X66327Y624823D01*
X65827Y624990D01*
X65243Y625073D01*
X64660Y624907D01*
X64160Y624573D01*
X63827Y624073D01*
X63660Y623407D01*
X63827Y622740D01*
X64160Y622240D01*
X64660Y621907D01*
X65243Y621740D01*
X65827Y621823D01*
X66327Y622073D01*
X66660Y622407D01*
G01X69010Y620240D02*
X69510Y620073D01*
X70177Y620240D01*
X70593Y620573D01*
X70927Y620990D01*
X71427Y622323D01*
X72510Y625073D01*
G01X69843D02*
X71427Y622323D01*
G01X75110Y623990D02*
X77777D01*
X77527Y624573D01*
X77110Y624907D01*
X76527Y625073D01*
X75943Y624990D01*
X75443Y624740D01*
X75110Y624157D01*
X74943Y623657D01*
Y623157D01*
X75110Y622657D01*
X75527Y622157D01*
X76027Y621823D01*
X76610Y621740D01*
X77193Y621907D01*
X77777Y622407D01*
G01X80793Y621740D02*
Y625073D01*
G01Y624407D02*
X81210Y624740D01*
X81627Y624990D01*
X82210Y625073D01*
X82627Y624990D01*
X83127Y624740D01*
G01X34000Y663333D02*
Y668333D01*
G01Y667583D02*
X34417Y668000D01*
X34833Y668250D01*
X35500Y668333D01*
X36083Y668250D01*
X36667Y667833D01*
X36917Y667250D01*
X37000Y666667D01*
X36917Y666083D01*
X36667Y665500D01*
X36167Y665167D01*
X35500Y665000D01*
X34917Y665083D01*
X34333Y665333D01*
X34000Y665667D01*
G01X39933Y665000D02*
Y668333D01*
G01Y667667D02*
X40350Y668000D01*
X40767Y668250D01*
X41350Y668333D01*
X41767Y668250D01*
X42267Y668000D01*
G01X46700Y665000D02*
X46200Y665083D01*
X45700Y665417D01*
X45367Y666000D01*
X45200Y666667D01*
X45367Y667333D01*
X45700Y667917D01*
X46200Y668250D01*
X46700Y668333D01*
X47200Y668250D01*
X47700Y667917D01*
X48033Y667333D01*
X48117Y666667D01*
X48033Y666000D01*
X47700Y665417D01*
X47200Y665083D01*
X46700Y665000D01*
G01X53633Y667917D02*
X53050Y668250D01*
X52550Y668333D01*
X51883Y668167D01*
X51383Y667833D01*
X51050Y667250D01*
X50967Y666667D01*
X51050Y666083D01*
X51383Y665583D01*
X51883Y665167D01*
X52550Y665000D01*
X53133Y665167D01*
X53633Y665500D01*
G01X56650Y667250D02*
X59317D01*
X59067Y667833D01*
X58650Y668167D01*
X58067Y668333D01*
X57483Y668250D01*
X56983Y668000D01*
X56650Y667417D01*
X56483Y666917D01*
Y666417D01*
X56650Y665917D01*
X57067Y665417D01*
X57567Y665083D01*
X58150Y665000D01*
X58733Y665167D01*
X59317Y665667D01*
G01X62250Y665583D02*
X62667Y665250D01*
X63250Y665000D01*
X63750D01*
X64250Y665167D01*
X64583Y665417D01*
X64750Y665750D01*
X64667Y666250D01*
X64333Y666500D01*
X62833Y667000D01*
X62500Y667583D01*
X62667Y668000D01*
X63000Y668250D01*
X63500Y668333D01*
X64000Y668250D01*
X64500Y668000D01*
G01X67850Y665583D02*
X68267Y665250D01*
X68850Y665000D01*
X69350D01*
X69850Y665167D01*
X70183Y665417D01*
X70350Y665750D01*
X70267Y666250D01*
X69933Y666500D01*
X68433Y667000D01*
X68100Y667583D01*
X68267Y668000D01*
X68600Y668250D01*
X69100Y668333D01*
X69600Y668250D01*
X70100Y668000D01*
G01X0Y679000D02*
X694500D01*
G01X-1000Y654000D02*
X694500D01*
G01X0Y850500D02*
Y709000D01*
X694500D01*
Y850500D01*
G01X7000Y832500D02*
Y837500D01*
X6000Y836500D01*
G01Y832500D02*
X8000D01*
G01X12600Y832333D02*
X12433Y832417D01*
Y832583D01*
X12600Y832667D01*
X12767Y832583D01*
Y832417D01*
X12600Y832333D01*
G01X16450Y833167D02*
X17117Y832750D01*
X17867Y832500D01*
X18533D01*
X19200Y832750D01*
X19700Y833167D01*
X19950Y833750D01*
X19783Y834333D01*
X19367Y834833D01*
X18617Y835167D01*
X17617Y835333D01*
X17033Y835667D01*
X16783Y836250D01*
X16950Y836833D01*
X17367Y837250D01*
X17950Y837500D01*
X18533D01*
X19117Y837333D01*
X19617Y836917D01*
G01X22300Y830833D02*
Y835833D01*
G01Y835083D02*
X22717Y835500D01*
X23133Y835750D01*
X23800Y835833D01*
X24383Y835750D01*
X24967Y835333D01*
X25217Y834750D01*
X25300Y834167D01*
X25217Y833583D01*
X24967Y833000D01*
X24467Y832667D01*
X23800Y832500D01*
X23217Y832583D01*
X22633Y832833D01*
X22300Y833167D01*
G01X28150Y834750D02*
X30817D01*
X30567Y835333D01*
X30150Y835667D01*
X29567Y835833D01*
X28983Y835750D01*
X28483Y835500D01*
X28150Y834917D01*
X27983Y834417D01*
Y833917D01*
X28150Y833417D01*
X28567Y832917D01*
X29067Y832583D01*
X29650Y832500D01*
X30233Y832667D01*
X30817Y833167D01*
G01X36333Y835417D02*
X35750Y835750D01*
X35250Y835833D01*
X34583Y835667D01*
X34083Y835333D01*
X33750Y834750D01*
X33667Y834167D01*
X33750Y833583D01*
X34083Y833083D01*
X34583Y832667D01*
X35250Y832500D01*
X35833Y832667D01*
X36333Y833000D01*
G01X40600Y835833D02*
Y832500D01*
G01Y837167D02*
X40433Y837250D01*
Y837417D01*
X40600Y837500D01*
X40767Y837417D01*
Y837250D01*
X40600Y837167D01*
G01X45700Y832500D02*
Y836750D01*
X45867Y837167D01*
X46200Y837417D01*
X46700Y837500D01*
X47200Y837333D01*
X47450Y836917D01*
G01X46450Y835500D02*
X44783D01*
G01X51800Y835833D02*
Y832500D01*
G01Y837167D02*
X51633Y837250D01*
Y837417D01*
X51800Y837500D01*
X51967Y837417D01*
Y837250D01*
X51800Y837167D01*
G01X58733Y835417D02*
X58150Y835750D01*
X57650Y835833D01*
X56983Y835667D01*
X56483Y835333D01*
X56150Y834750D01*
X56067Y834167D01*
X56150Y833583D01*
X56483Y833083D01*
X56983Y832667D01*
X57650Y832500D01*
X58233Y832667D01*
X58733Y833000D01*
G01X64500Y832500D02*
Y835833D01*
G01Y835250D02*
X64167Y835583D01*
X63667Y835750D01*
X63083Y835833D01*
X62500Y835667D01*
X62000Y835333D01*
X61667Y834833D01*
X61500Y834167D01*
X61667Y833500D01*
X62000Y833000D01*
X62500Y832667D01*
X63083Y832500D01*
X63667Y832583D01*
X64167Y832833D01*
X64500Y833167D01*
G01X68600Y837500D02*
Y832500D01*
G01X67433Y835833D02*
X69767D01*
G01X74200D02*
Y832500D01*
G01Y837167D02*
X74033Y837250D01*
Y837417D01*
X74200Y837500D01*
X74367Y837417D01*
Y837250D01*
X74200Y837167D01*
G01X79800Y832500D02*
X79300Y832583D01*
X78800Y832917D01*
X78467Y833500D01*
X78300Y834167D01*
X78467Y834833D01*
X78800Y835417D01*
X79300Y835750D01*
X79800Y835833D01*
X80300Y835750D01*
X80800Y835417D01*
X81133Y834833D01*
X81217Y834167D01*
X81133Y833500D01*
X80800Y832917D01*
X80300Y832583D01*
X79800Y832500D01*
G01X83983D02*
Y835833D01*
G01Y835000D02*
X84317Y835417D01*
X84817Y835750D01*
X85483Y835833D01*
X86067Y835750D01*
X86567Y835417D01*
X86817Y834833D01*
Y832500D01*
G01X98100Y837500D02*
Y832500D01*
G01Y833250D02*
X97767Y832833D01*
X97267Y832583D01*
X96683Y832500D01*
X96017Y832667D01*
X95517Y833083D01*
X95183Y833583D01*
X95100Y834167D01*
X95183Y834750D01*
X95517Y835250D01*
X96017Y835667D01*
X96683Y835833D01*
X97267Y835750D01*
X97683Y835583D01*
X98100Y835250D01*
G01X102200Y832500D02*
X101700Y832583D01*
X101200Y832917D01*
X100867Y833500D01*
X100700Y834167D01*
X100867Y834833D01*
X101200Y835417D01*
X101700Y835750D01*
X102200Y835833D01*
X102700Y835750D01*
X103200Y835417D01*
X103533Y834833D01*
X103617Y834167D01*
X103533Y833500D01*
X103200Y832917D01*
X102700Y832583D01*
X102200Y832500D01*
G01X109133Y835417D02*
X108550Y835750D01*
X108050Y835833D01*
X107383Y835667D01*
X106883Y835333D01*
X106550Y834750D01*
X106467Y834167D01*
X106550Y833583D01*
X106883Y833083D01*
X107383Y832667D01*
X108050Y832500D01*
X108633Y832667D01*
X109133Y833000D01*
G01X111983Y835833D02*
Y833500D01*
X112317Y832917D01*
X112817Y832583D01*
X113400Y832500D01*
X113983Y832583D01*
X114483Y832917D01*
X114817Y833500D01*
G01Y832500D02*
Y835833D01*
G01X116500Y832500D02*
Y835833D01*
G01Y834917D02*
X116750Y835333D01*
X117167Y835667D01*
X117750Y835833D01*
X118333Y835667D01*
X118750Y835333D01*
X119000Y834917D01*
Y832500D01*
G01Y834917D02*
X119250Y835333D01*
X119667Y835667D01*
X120250Y835833D01*
X120833Y835667D01*
X121250Y835333D01*
X121500Y834833D01*
Y832500D01*
G01X123350Y834750D02*
X126017D01*
X125767Y835333D01*
X125350Y835667D01*
X124767Y835833D01*
X124183Y835750D01*
X123683Y835500D01*
X123350Y834917D01*
X123183Y834417D01*
Y833917D01*
X123350Y833417D01*
X123767Y832917D01*
X124267Y832583D01*
X124850Y832500D01*
X125433Y832667D01*
X126017Y833167D01*
G01X128783Y832500D02*
Y835833D01*
G01Y835000D02*
X129117Y835417D01*
X129617Y835750D01*
X130283Y835833D01*
X130867Y835750D01*
X131367Y835417D01*
X131617Y834833D01*
Y832500D01*
G01X135800Y837500D02*
Y832500D01*
G01X134633Y835833D02*
X136967D01*
G01X141400Y832333D02*
X141233Y832417D01*
Y832583D01*
X141400Y832667D01*
X141567Y832583D01*
Y832417D01*
X141400Y832333D01*
G01Y834583D02*
X141233Y834667D01*
Y834833D01*
X141400Y834917D01*
X141567Y834833D01*
Y834667D01*
X141400Y834583D01*
G01X0Y820500D02*
X694500D01*
G01X0Y850500D02*
X694500D01*
G01X112333Y-60000D02*
Y-65000D01*
X115667D01*
G01X119600D02*
X119100Y-64917D01*
X118600Y-64583D01*
X118267Y-64000D01*
X118100Y-63333D01*
X118267Y-62667D01*
X118600Y-62083D01*
X119100Y-61750D01*
X119600Y-61667D01*
X120100Y-61750D01*
X120600Y-62083D01*
X120933Y-62667D01*
X121017Y-63333D01*
X120933Y-64000D01*
X120600Y-64583D01*
X120100Y-64917D01*
X119600Y-65000D01*
G01X124033Y-66250D02*
X124617Y-66583D01*
X125283Y-66667D01*
X125867Y-66583D01*
X126367Y-66167D01*
X126700Y-65583D01*
Y-61667D01*
G01Y-62333D02*
X126367Y-62000D01*
X125867Y-61750D01*
X125283Y-61667D01*
X124617Y-61833D01*
X124200Y-62167D01*
X123867Y-62750D01*
X123700Y-63333D01*
X123783Y-63833D01*
X124117Y-64417D01*
X124617Y-64833D01*
X125283Y-65000D01*
X125783Y-64917D01*
X126367Y-64583D01*
X126700Y-64250D01*
G01X130800Y-65000D02*
X130300Y-64917D01*
X129800Y-64583D01*
X129467Y-64000D01*
X129300Y-63333D01*
X129467Y-62667D01*
X129800Y-62083D01*
X130300Y-61750D01*
X130800Y-61667D01*
X131300Y-61750D01*
X131800Y-62083D01*
X132133Y-62667D01*
X132217Y-63333D01*
X132133Y-64000D01*
X131800Y-64583D01*
X131300Y-64917D01*
X130800Y-65000D01*
G01X103500Y679000D02*
Y-69500D01*
G01Y-54500D02*
X694500D01*
G01X112483Y24700D02*
Y29700D01*
X114650Y25533D01*
X116817Y29700D01*
Y24700D01*
G01X121750D02*
Y28033D01*
G01Y27450D02*
X121417Y27783D01*
X120917Y27950D01*
X120333Y28033D01*
X119750Y27867D01*
X119250Y27533D01*
X118917Y27033D01*
X118750Y26367D01*
X118917Y25700D01*
X119250Y25200D01*
X119750Y24867D01*
X120333Y24700D01*
X120917Y24783D01*
X121417Y25033D01*
X121750Y25367D01*
G01X124683Y24700D02*
Y28033D01*
G01Y27367D02*
X125100Y27700D01*
X125517Y27950D01*
X126100Y28033D01*
X126517Y27950D01*
X127017Y27700D01*
G01X130033Y24700D02*
Y29700D01*
G01X132700Y28033D02*
X130033Y26117D01*
G01X131117Y26867D02*
X132867Y24700D01*
G01X137467Y23033D02*
X138300Y23867D01*
X138717Y24700D01*
Y28033D01*
X138300Y28867D01*
X137467Y29700D01*
G01X114000Y-36000D02*
Y-41000D01*
G01X112833Y-37667D02*
X115167D01*
G01X118183Y-41000D02*
Y-36000D01*
G01Y-38417D02*
X118600Y-38000D01*
X119017Y-37750D01*
X119683Y-37667D01*
X120183Y-37750D01*
X120767Y-38083D01*
X121017Y-38583D01*
Y-41000D01*
G01X125200Y-37667D02*
Y-41000D01*
G01Y-36333D02*
X125033Y-36250D01*
Y-36083D01*
X125200Y-36000D01*
X125367Y-36083D01*
Y-36250D01*
X125200Y-36333D01*
G01X132133Y-38083D02*
X131550Y-37750D01*
X131050Y-37667D01*
X130383Y-37833D01*
X129883Y-38167D01*
X129550Y-38750D01*
X129467Y-39333D01*
X129550Y-39917D01*
X129883Y-40417D01*
X130383Y-40833D01*
X131050Y-41000D01*
X131633Y-40833D01*
X132133Y-40500D01*
G01X134983Y-41000D02*
Y-36000D01*
G01X137650Y-37667D02*
X134983Y-39583D01*
G01X136067Y-38833D02*
X137817Y-41000D01*
G01X140583D02*
Y-37667D01*
G01Y-38500D02*
X140917Y-38083D01*
X141417Y-37750D01*
X142083Y-37667D01*
X142667Y-37750D01*
X143167Y-38083D01*
X143417Y-38667D01*
Y-41000D01*
G01X146350Y-38750D02*
X149017D01*
X148767Y-38167D01*
X148350Y-37833D01*
X147767Y-37667D01*
X147183Y-37750D01*
X146683Y-38000D01*
X146350Y-38583D01*
X146183Y-39083D01*
Y-39583D01*
X146350Y-40083D01*
X146767Y-40583D01*
X147267Y-40917D01*
X147850Y-41000D01*
X148433Y-40833D01*
X149017Y-40333D01*
G01X151950Y-40417D02*
X152367Y-40750D01*
X152950Y-41000D01*
X153450D01*
X153950Y-40833D01*
X154283Y-40583D01*
X154450Y-40250D01*
X154367Y-39750D01*
X154033Y-39500D01*
X152533Y-39000D01*
X152200Y-38417D01*
X152367Y-38000D01*
X152700Y-37750D01*
X153200Y-37667D01*
X153700Y-37750D01*
X154200Y-38000D01*
G01X157550Y-40417D02*
X157967Y-40750D01*
X158550Y-41000D01*
X159050D01*
X159550Y-40833D01*
X159883Y-40583D01*
X160050Y-40250D01*
X159967Y-39750D01*
X159633Y-39500D01*
X158133Y-39000D01*
X157800Y-38417D01*
X157967Y-38000D01*
X158300Y-37750D01*
X158800Y-37667D01*
X159300Y-37750D01*
X159800Y-38000D01*
G01X114000Y-15000D02*
Y-20000D01*
G01X112833Y-16667D02*
X115167D01*
G01X118183Y-20000D02*
Y-15000D01*
G01Y-17417D02*
X118600Y-17000D01*
X119017Y-16750D01*
X119683Y-16667D01*
X120183Y-16750D01*
X120767Y-17083D01*
X121017Y-17583D01*
Y-20000D01*
G01X125200Y-16667D02*
Y-20000D01*
G01Y-15333D02*
X125033Y-15250D01*
Y-15083D01*
X125200Y-15000D01*
X125367Y-15083D01*
Y-15250D01*
X125200Y-15333D01*
G01X132133Y-17083D02*
X131550Y-16750D01*
X131050Y-16667D01*
X130383Y-16833D01*
X129883Y-17167D01*
X129550Y-17750D01*
X129467Y-18333D01*
X129550Y-18917D01*
X129883Y-19417D01*
X130383Y-19833D01*
X131050Y-20000D01*
X131633Y-19833D01*
X132133Y-19500D01*
G01X134983Y-20000D02*
Y-15000D01*
G01X137650Y-16667D02*
X134983Y-18583D01*
G01X136067Y-17833D02*
X137817Y-20000D01*
G01X140583D02*
Y-16667D01*
G01Y-17500D02*
X140917Y-17083D01*
X141417Y-16750D01*
X142083Y-16667D01*
X142667Y-16750D01*
X143167Y-17083D01*
X143417Y-17667D01*
Y-20000D01*
G01X146350Y-17750D02*
X149017D01*
X148767Y-17167D01*
X148350Y-16833D01*
X147767Y-16667D01*
X147183Y-16750D01*
X146683Y-17000D01*
X146350Y-17583D01*
X146183Y-18083D01*
Y-18583D01*
X146350Y-19083D01*
X146767Y-19583D01*
X147267Y-19917D01*
X147850Y-20000D01*
X148433Y-19833D01*
X149017Y-19333D01*
G01X151950Y-19417D02*
X152367Y-19750D01*
X152950Y-20000D01*
X153450D01*
X153950Y-19833D01*
X154283Y-19583D01*
X154450Y-19250D01*
X154367Y-18750D01*
X154033Y-18500D01*
X152533Y-18000D01*
X152200Y-17417D01*
X152367Y-17000D01*
X152700Y-16750D01*
X153200Y-16667D01*
X153700Y-16750D01*
X154200Y-17000D01*
G01X157550Y-19417D02*
X157967Y-19750D01*
X158550Y-20000D01*
X159050D01*
X159550Y-19833D01*
X159883Y-19583D01*
X160050Y-19250D01*
X159967Y-18750D01*
X159633Y-18500D01*
X158133Y-18000D01*
X157800Y-17417D01*
X157967Y-17000D01*
X158300Y-16750D01*
X158800Y-16667D01*
X159300Y-16750D01*
X159800Y-17000D01*
G01X119183Y-2167D02*
X118350Y-1333D01*
X117933Y-500D01*
Y2833D01*
X118350Y3667D01*
X119183Y4500D01*
G01X123450Y167D02*
X124117Y-250D01*
X124867Y-500D01*
X125533D01*
X126200Y-250D01*
X126700Y167D01*
X126950Y750D01*
X126783Y1333D01*
X126367Y1833D01*
X125617Y2167D01*
X124617Y2333D01*
X124033Y2667D01*
X123783Y3250D01*
X123950Y3833D01*
X124367Y4250D01*
X124950Y4500D01*
X125533D01*
X126117Y4333D01*
X126617Y3917D01*
G01X128633Y-500D02*
Y4500D01*
X130800Y333D01*
X132967Y4500D01*
Y-500D01*
G01X134567D02*
Y4500D01*
X136233D01*
X136900Y4250D01*
X137400Y3917D01*
X137817Y3417D01*
X138150Y2833D01*
X138233Y2000D01*
X138150Y1167D01*
X137817Y583D01*
X137400Y83D01*
X136900Y-250D01*
X136233Y-500D01*
X134567D01*
G01X142417Y-2167D02*
X143250Y-1333D01*
X143667Y-500D01*
Y2833D01*
X143250Y3667D01*
X142417Y4500D01*
G01X112250Y12167D02*
X112917Y11750D01*
X113667Y11500D01*
X114333D01*
X115000Y11750D01*
X115500Y12167D01*
X115750Y12750D01*
X115583Y13333D01*
X115167Y13833D01*
X114417Y14167D01*
X113417Y14333D01*
X112833Y14667D01*
X112583Y15250D01*
X112750Y15833D01*
X113167Y16250D01*
X113750Y16500D01*
X114333D01*
X114917Y16333D01*
X115417Y15917D01*
G01X119600Y11500D02*
X119100Y11583D01*
X118600Y11917D01*
X118267Y12500D01*
X118100Y13167D01*
X118267Y13833D01*
X118600Y14417D01*
X119100Y14750D01*
X119600Y14833D01*
X120100Y14750D01*
X120600Y14417D01*
X120933Y13833D01*
X121017Y13167D01*
X120933Y12500D01*
X120600Y11917D01*
X120100Y11583D01*
X119600Y11500D01*
G01X125200D02*
Y16500D01*
G01X132300D02*
Y11500D01*
G01Y12250D02*
X131967Y11833D01*
X131467Y11583D01*
X130883Y11500D01*
X130217Y11667D01*
X129717Y12083D01*
X129383Y12583D01*
X129300Y13167D01*
X129383Y13750D01*
X129717Y14250D01*
X130217Y14667D01*
X130883Y14833D01*
X131467Y14750D01*
X131883Y14583D01*
X132300Y14250D01*
G01X135150Y13750D02*
X137817D01*
X137567Y14333D01*
X137150Y14667D01*
X136567Y14833D01*
X135983Y14750D01*
X135483Y14500D01*
X135150Y13917D01*
X134983Y13417D01*
Y12917D01*
X135150Y12417D01*
X135567Y11917D01*
X136067Y11583D01*
X136650Y11500D01*
X137233Y11667D01*
X137817Y12167D01*
G01X140833Y11500D02*
Y14833D01*
G01Y14167D02*
X141250Y14500D01*
X141667Y14750D01*
X142250Y14833D01*
X142667Y14750D01*
X143167Y14500D01*
G01X150700Y11500D02*
Y14833D01*
G01Y13917D02*
X150950Y14333D01*
X151367Y14667D01*
X151950Y14833D01*
X152533Y14667D01*
X152950Y14333D01*
X153200Y13917D01*
Y11500D01*
G01Y13917D02*
X153450Y14333D01*
X153867Y14667D01*
X154450Y14833D01*
X155033Y14667D01*
X155450Y14333D01*
X155700Y13833D01*
Y11500D01*
G01X160300D02*
Y14833D01*
G01Y14250D02*
X159967Y14583D01*
X159467Y14750D01*
X158883Y14833D01*
X158300Y14667D01*
X157800Y14333D01*
X157467Y13833D01*
X157300Y13167D01*
X157467Y12500D01*
X157800Y12000D01*
X158300Y11667D01*
X158883Y11500D01*
X159467Y11583D01*
X159967Y11833D01*
X160300Y12167D01*
G01X163150Y12083D02*
X163567Y11750D01*
X164150Y11500D01*
X164650D01*
X165150Y11667D01*
X165483Y11917D01*
X165650Y12250D01*
X165567Y12750D01*
X165233Y13000D01*
X163733Y13500D01*
X163400Y14083D01*
X163567Y14500D01*
X163900Y14750D01*
X164400Y14833D01*
X164900Y14750D01*
X165400Y14500D01*
G01X168583Y11500D02*
Y16500D01*
G01X171250Y14833D02*
X168583Y12917D01*
G01X169667Y13667D02*
X171417Y11500D01*
G01X182700Y16500D02*
Y11500D01*
G01Y12250D02*
X182367Y11833D01*
X181867Y11583D01*
X181283Y11500D01*
X180617Y11667D01*
X180117Y12083D01*
X179783Y12583D01*
X179700Y13167D01*
X179783Y13750D01*
X180117Y14250D01*
X180617Y14667D01*
X181283Y14833D01*
X181867Y14750D01*
X182283Y14583D01*
X182700Y14250D01*
G01X185550Y13750D02*
X188217D01*
X187967Y14333D01*
X187550Y14667D01*
X186967Y14833D01*
X186383Y14750D01*
X185883Y14500D01*
X185550Y13917D01*
X185383Y13417D01*
Y12917D01*
X185550Y12417D01*
X185967Y11917D01*
X186467Y11583D01*
X187050Y11500D01*
X187633Y11667D01*
X188217Y12167D01*
G01X191900Y11500D02*
Y15750D01*
X192067Y16167D01*
X192400Y16417D01*
X192900Y16500D01*
X193400Y16333D01*
X193650Y15917D01*
G01X192650Y14500D02*
X190983D01*
G01X198000Y14833D02*
Y11500D01*
G01Y16167D02*
X197833Y16250D01*
Y16417D01*
X198000Y16500D01*
X198167Y16417D01*
Y16250D01*
X198000Y16167D01*
G01X202183Y11500D02*
Y14833D01*
G01Y14000D02*
X202517Y14417D01*
X203017Y14750D01*
X203683Y14833D01*
X204267Y14750D01*
X204767Y14417D01*
X205017Y13833D01*
Y11500D01*
G01X207950Y13750D02*
X210617D01*
X210367Y14333D01*
X209950Y14667D01*
X209367Y14833D01*
X208783Y14750D01*
X208283Y14500D01*
X207950Y13917D01*
X207783Y13417D01*
Y12917D01*
X207950Y12417D01*
X208367Y11917D01*
X208867Y11583D01*
X209450Y11500D01*
X210033Y11667D01*
X210617Y12167D01*
G01X218900Y9833D02*
Y14833D01*
G01Y14083D02*
X219317Y14500D01*
X219733Y14750D01*
X220400Y14833D01*
X220983Y14750D01*
X221567Y14333D01*
X221817Y13750D01*
X221900Y13167D01*
X221817Y12583D01*
X221567Y12000D01*
X221067Y11667D01*
X220400Y11500D01*
X219817Y11583D01*
X219233Y11833D01*
X218900Y12167D01*
G01X227500Y11500D02*
Y14833D01*
G01Y14250D02*
X227167Y14583D01*
X226667Y14750D01*
X226083Y14833D01*
X225500Y14667D01*
X225000Y14333D01*
X224667Y13833D01*
X224500Y13167D01*
X224667Y12500D01*
X225000Y12000D01*
X225500Y11667D01*
X226083Y11500D01*
X226667Y11583D01*
X227167Y11833D01*
X227500Y12167D01*
G01X233100Y16500D02*
Y11500D01*
G01Y12250D02*
X232767Y11833D01*
X232267Y11583D01*
X231683Y11500D01*
X231017Y11667D01*
X230517Y12083D01*
X230183Y12583D01*
X230100Y13167D01*
X230183Y13750D01*
X230517Y14250D01*
X231017Y14667D01*
X231683Y14833D01*
X232267Y14750D01*
X232683Y14583D01*
X233100Y14250D01*
G01X103500Y-9500D02*
X694500D01*
G01X113070Y36130D02*
X114737D01*
Y34630D01*
X114237Y34130D01*
X113653Y33797D01*
X112820Y33630D01*
X111987Y33797D01*
X111403Y34130D01*
X110903Y34630D01*
X110570Y35213D01*
X110403Y35880D01*
Y36463D01*
X110570Y36963D01*
X110903Y37547D01*
X111403Y38047D01*
X111903Y38380D01*
X112570Y38630D01*
X113153D01*
X113820Y38463D01*
X114320Y38130D01*
G01X118170Y33630D02*
X117670Y33713D01*
X117170Y34047D01*
X116837Y34630D01*
X116670Y35297D01*
X116837Y35963D01*
X117170Y36547D01*
X117670Y36880D01*
X118170Y36963D01*
X118670Y36880D01*
X119170Y36547D01*
X119503Y35963D01*
X119587Y35297D01*
X119503Y34630D01*
X119170Y34047D01*
X118670Y33713D01*
X118170Y33630D01*
G01X123770D02*
Y38630D01*
G01X130870D02*
Y33630D01*
G01Y34380D02*
X130537Y33963D01*
X130037Y33713D01*
X129453Y33630D01*
X128787Y33797D01*
X128287Y34213D01*
X127953Y34713D01*
X127870Y35297D01*
X127953Y35880D01*
X128287Y36380D01*
X128787Y36797D01*
X129453Y36963D01*
X130037Y36880D01*
X130453Y36713D01*
X130870Y36380D01*
G01X133720Y35880D02*
X136387D01*
X136137Y36463D01*
X135720Y36797D01*
X135137Y36963D01*
X134553Y36880D01*
X134053Y36630D01*
X133720Y36047D01*
X133553Y35547D01*
Y35047D01*
X133720Y34547D01*
X134137Y34047D01*
X134637Y33713D01*
X135220Y33630D01*
X135803Y33797D01*
X136387Y34297D01*
G01X139153Y33630D02*
Y36963D01*
G01Y36130D02*
X139487Y36547D01*
X139987Y36880D01*
X140653Y36963D01*
X141237Y36880D01*
X141737Y36547D01*
X141987Y35963D01*
Y33630D01*
G01X151270D02*
Y37880D01*
X151437Y38297D01*
X151770Y38547D01*
X152270Y38630D01*
X152770Y38463D01*
X153020Y38047D01*
G01X152020Y36630D02*
X150353D01*
G01X157370Y36963D02*
Y33630D01*
G01Y38297D02*
X157203Y38380D01*
Y38547D01*
X157370Y38630D01*
X157537Y38547D01*
Y38380D01*
X157370Y38297D01*
G01X161553Y33630D02*
Y36963D01*
G01Y36130D02*
X161887Y36547D01*
X162387Y36880D01*
X163053Y36963D01*
X163637Y36880D01*
X164137Y36547D01*
X164387Y35963D01*
Y33630D01*
G01X167403Y32380D02*
X167987Y32047D01*
X168653Y31963D01*
X169237Y32047D01*
X169737Y32463D01*
X170070Y33047D01*
Y36963D01*
G01Y36297D02*
X169737Y36630D01*
X169237Y36880D01*
X168653Y36963D01*
X167987Y36797D01*
X167570Y36463D01*
X167237Y35880D01*
X167070Y35297D01*
X167153Y34797D01*
X167487Y34213D01*
X167987Y33797D01*
X168653Y33630D01*
X169153Y33713D01*
X169737Y34047D01*
X170070Y34380D01*
G01X172920Y35880D02*
X175587D01*
X175337Y36463D01*
X174920Y36797D01*
X174337Y36963D01*
X173753Y36880D01*
X173253Y36630D01*
X172920Y36047D01*
X172753Y35547D01*
Y35047D01*
X172920Y34547D01*
X173337Y34047D01*
X173837Y33713D01*
X174420Y33630D01*
X175003Y33797D01*
X175587Y34297D01*
G01X178603Y33630D02*
Y36963D01*
G01Y36297D02*
X179020Y36630D01*
X179437Y36880D01*
X180020Y36963D01*
X180437Y36880D01*
X180937Y36630D01*
G01X189303Y33630D02*
Y38630D01*
X191303D01*
X191970Y38380D01*
X192470Y37797D01*
X192637Y37130D01*
X192470Y36463D01*
X192053Y35963D01*
X191303Y35713D01*
X189303D01*
G01X194487Y33630D02*
X196570Y38630D01*
X198653Y33630D01*
G01X197903Y35380D02*
X195237D01*
G01X200337Y33630D02*
Y38630D01*
X202003D01*
X202670Y38380D01*
X203170Y38047D01*
X203587Y37547D01*
X203920Y36963D01*
X204003Y36130D01*
X203920Y35297D01*
X203587Y34713D01*
X203170Y34213D01*
X202670Y33880D01*
X202003Y33630D01*
X200337D01*
G01X211870Y33463D02*
X214870Y38630D01*
G01X217387Y33630D02*
Y38630D01*
X220553D01*
G01X219387Y36213D02*
X217387D01*
G01X224570Y36963D02*
Y33630D01*
G01Y38297D02*
X224403Y38380D01*
Y38547D01*
X224570Y38630D01*
X224737Y38547D01*
Y38380D01*
X224570Y38297D01*
G01X231670Y38630D02*
Y33630D01*
G01Y34380D02*
X231337Y33963D01*
X230837Y33713D01*
X230253Y33630D01*
X229587Y33797D01*
X229087Y34213D01*
X228753Y34713D01*
X228670Y35297D01*
X228753Y35880D01*
X229087Y36380D01*
X229587Y36797D01*
X230253Y36963D01*
X230837Y36880D01*
X231253Y36713D01*
X231670Y36380D01*
G01X234353Y36963D02*
Y34630D01*
X234687Y34047D01*
X235187Y33713D01*
X235770Y33630D01*
X236353Y33713D01*
X236853Y34047D01*
X237187Y34630D01*
G01Y33630D02*
Y36963D01*
G01X242703Y36547D02*
X242120Y36880D01*
X241620Y36963D01*
X240953Y36797D01*
X240453Y36463D01*
X240120Y35880D01*
X240037Y35297D01*
X240120Y34713D01*
X240453Y34213D01*
X240953Y33797D01*
X241620Y33630D01*
X242203Y33797D01*
X242703Y34130D01*
G01X246970Y36963D02*
Y33630D01*
G01Y38297D02*
X246803Y38380D01*
Y38547D01*
X246970Y38630D01*
X247137Y38547D01*
Y38380D01*
X246970Y38297D01*
G01X254070Y33630D02*
Y36963D01*
G01Y36380D02*
X253737Y36713D01*
X253237Y36880D01*
X252653Y36963D01*
X252070Y36797D01*
X251570Y36463D01*
X251237Y35963D01*
X251070Y35297D01*
X251237Y34630D01*
X251570Y34130D01*
X252070Y33797D01*
X252653Y33630D01*
X253237Y33713D01*
X253737Y33963D01*
X254070Y34297D01*
G01X258170Y33630D02*
Y38630D01*
G01X112743Y42673D02*
X111910Y43507D01*
X111493Y44340D01*
Y47673D01*
X111910Y48507D01*
X112743Y49340D01*
G01X116260Y44340D02*
Y47673D01*
G01Y46757D02*
X116510Y47173D01*
X116927Y47507D01*
X117510Y47673D01*
X118093Y47507D01*
X118510Y47173D01*
X118760Y46757D01*
Y44340D01*
G01Y46757D02*
X119010Y47173D01*
X119427Y47507D01*
X120010Y47673D01*
X120593Y47507D01*
X121010Y47173D01*
X121260Y46673D01*
Y44340D01*
G01X123110Y46590D02*
X125777D01*
X125527Y47173D01*
X125110Y47507D01*
X124527Y47673D01*
X123943Y47590D01*
X123443Y47340D01*
X123110Y46757D01*
X122943Y46257D01*
Y45757D01*
X123110Y45257D01*
X123527Y44757D01*
X124027Y44423D01*
X124610Y44340D01*
X125193Y44507D01*
X125777Y45007D01*
G01X131460Y44340D02*
Y47673D01*
G01Y47090D02*
X131127Y47423D01*
X130627Y47590D01*
X130043Y47673D01*
X129460Y47507D01*
X128960Y47173D01*
X128627Y46673D01*
X128460Y46007D01*
X128627Y45340D01*
X128960Y44840D01*
X129460Y44507D01*
X130043Y44340D01*
X130627Y44423D01*
X131127Y44673D01*
X131460Y45007D01*
G01X134310Y44923D02*
X134727Y44590D01*
X135310Y44340D01*
X135810D01*
X136310Y44507D01*
X136643Y44757D01*
X136810Y45090D01*
X136727Y45590D01*
X136393Y45840D01*
X134893Y46340D01*
X134560Y46923D01*
X134727Y47340D01*
X135060Y47590D01*
X135560Y47673D01*
X136060Y47590D01*
X136560Y47340D01*
G01X139743Y47673D02*
Y45340D01*
X140077Y44757D01*
X140577Y44423D01*
X141160Y44340D01*
X141743Y44423D01*
X142243Y44757D01*
X142577Y45340D01*
G01Y44340D02*
Y47673D01*
G01X145593Y44340D02*
Y47673D01*
G01Y47007D02*
X146010Y47340D01*
X146427Y47590D01*
X147010Y47673D01*
X147427Y47590D01*
X147927Y47340D01*
G01X151110Y46590D02*
X153777D01*
X153527Y47173D01*
X153110Y47507D01*
X152527Y47673D01*
X151943Y47590D01*
X151443Y47340D01*
X151110Y46757D01*
X150943Y46257D01*
Y45757D01*
X151110Y45257D01*
X151527Y44757D01*
X152027Y44423D01*
X152610Y44340D01*
X153193Y44507D01*
X153777Y45007D01*
G01X163560Y49340D02*
Y44340D01*
G01X162393Y47673D02*
X164727D01*
G01X169160Y44340D02*
X168660Y44423D01*
X168160Y44757D01*
X167827Y45340D01*
X167660Y46007D01*
X167827Y46673D01*
X168160Y47257D01*
X168660Y47590D01*
X169160Y47673D01*
X169660Y47590D01*
X170160Y47257D01*
X170493Y46673D01*
X170577Y46007D01*
X170493Y45340D01*
X170160Y44757D01*
X169660Y44423D01*
X169160Y44340D01*
G01X173260Y42673D02*
Y47673D01*
G01Y46923D02*
X173677Y47340D01*
X174093Y47590D01*
X174760Y47673D01*
X175343Y47590D01*
X175927Y47173D01*
X176177Y46590D01*
X176260Y46007D01*
X176177Y45423D01*
X175927Y44840D01*
X175427Y44507D01*
X174760Y44340D01*
X174177Y44423D01*
X173593Y44673D01*
X173260Y45007D01*
G01X184710Y44923D02*
X185127Y44590D01*
X185710Y44340D01*
X186210D01*
X186710Y44507D01*
X187043Y44757D01*
X187210Y45090D01*
X187127Y45590D01*
X186793Y45840D01*
X185293Y46340D01*
X184960Y46923D01*
X185127Y47340D01*
X185460Y47590D01*
X185960Y47673D01*
X186460Y47590D01*
X186960Y47340D01*
G01X191560Y47673D02*
Y44340D01*
G01Y49007D02*
X191393Y49090D01*
Y49257D01*
X191560Y49340D01*
X191727Y49257D01*
Y49090D01*
X191560Y49007D01*
G01X195910Y47673D02*
X198410D01*
X195910Y44340D01*
X198410D01*
G01X201510Y46590D02*
X204177D01*
X203927Y47173D01*
X203510Y47507D01*
X202927Y47673D01*
X202343Y47590D01*
X201843Y47340D01*
X201510Y46757D01*
X201343Y46257D01*
Y45757D01*
X201510Y45257D01*
X201927Y44757D01*
X202427Y44423D01*
X203010Y44340D01*
X203593Y44507D01*
X204177Y45007D01*
G01X213960Y44340D02*
X213460Y44423D01*
X212960Y44757D01*
X212627Y45340D01*
X212460Y46007D01*
X212627Y46673D01*
X212960Y47257D01*
X213460Y47590D01*
X213960Y47673D01*
X214460Y47590D01*
X214960Y47257D01*
X215293Y46673D01*
X215377Y46007D01*
X215293Y45340D01*
X214960Y44757D01*
X214460Y44423D01*
X213960Y44340D01*
G01X219060D02*
Y48590D01*
X219227Y49007D01*
X219560Y49257D01*
X220060Y49340D01*
X220560Y49173D01*
X220810Y48757D01*
G01X219810Y47340D02*
X218143D01*
G01X229093Y44340D02*
Y49340D01*
X231093D01*
X231760Y49090D01*
X232260Y48507D01*
X232427Y47840D01*
X232260Y47173D01*
X231843Y46673D01*
X231093Y46423D01*
X229093D01*
G01X234277Y44340D02*
X236360Y49340D01*
X238443Y44340D01*
G01X237693Y46090D02*
X235027D01*
G01X240127Y44340D02*
Y49340D01*
X241793D01*
X242460Y49090D01*
X242960Y48757D01*
X243377Y48257D01*
X243710Y47673D01*
X243793Y46840D01*
X243710Y46007D01*
X243377Y45423D01*
X242960Y44923D01*
X242460Y44590D01*
X241793Y44340D01*
X240127D01*
G01X251660Y44173D02*
X254660Y49340D01*
G01X112333Y51500D02*
Y56500D01*
X114333D01*
X115000Y56250D01*
X115500Y55667D01*
X115667Y55000D01*
X115500Y54333D01*
X115083Y53833D01*
X114333Y53583D01*
X112333D01*
G01X117517Y51500D02*
X119600Y56500D01*
X121683Y51500D01*
G01X120933Y53250D02*
X118267D01*
G01X123367Y51500D02*
Y56500D01*
X125033D01*
X125700Y56250D01*
X126200Y55917D01*
X126617Y55417D01*
X126950Y54833D01*
X127033Y54000D01*
X126950Y53167D01*
X126617Y52583D01*
X126200Y52083D01*
X125700Y51750D01*
X125033Y51500D01*
X123367D01*
G01X135150Y52083D02*
X135567Y51750D01*
X136150Y51500D01*
X136650D01*
X137150Y51667D01*
X137483Y51917D01*
X137650Y52250D01*
X137567Y52750D01*
X137233Y53000D01*
X135733Y53500D01*
X135400Y54083D01*
X135567Y54500D01*
X135900Y54750D01*
X136400Y54833D01*
X136900Y54750D01*
X137400Y54500D01*
G01X142000Y54833D02*
Y51500D01*
G01Y56167D02*
X141833Y56250D01*
Y56417D01*
X142000Y56500D01*
X142167Y56417D01*
Y56250D01*
X142000Y56167D01*
G01X146350Y54833D02*
X148850D01*
X146350Y51500D01*
X148850D01*
G01X151950Y53750D02*
X154617D01*
X154367Y54333D01*
X153950Y54667D01*
X153367Y54833D01*
X152783Y54750D01*
X152283Y54500D01*
X151950Y53917D01*
X151783Y53417D01*
Y52917D01*
X151950Y52417D01*
X152367Y51917D01*
X152867Y51583D01*
X153450Y51500D01*
X154033Y51667D01*
X154617Y52167D01*
G01X114000Y85000D02*
Y80000D01*
G01X112083Y85000D02*
X115917D01*
G01X118433Y80000D02*
Y83333D01*
G01Y82667D02*
X118850Y83000D01*
X119267Y83250D01*
X119850Y83333D01*
X120267Y83250D01*
X120767Y83000D01*
G01X126700Y80000D02*
Y83333D01*
G01Y82750D02*
X126367Y83083D01*
X125867Y83250D01*
X125283Y83333D01*
X124700Y83167D01*
X124200Y82833D01*
X123867Y82333D01*
X123700Y81667D01*
X123867Y81000D01*
X124200Y80500D01*
X124700Y80167D01*
X125283Y80000D01*
X125867Y80083D01*
X126367Y80333D01*
X126700Y80667D01*
G01X132133Y82917D02*
X131550Y83250D01*
X131050Y83333D01*
X130383Y83167D01*
X129883Y82833D01*
X129550Y82250D01*
X129467Y81667D01*
X129550Y81083D01*
X129883Y80583D01*
X130383Y80167D01*
X131050Y80000D01*
X131633Y80167D01*
X132133Y80500D01*
G01X135150Y82250D02*
X137817D01*
X137567Y82833D01*
X137150Y83167D01*
X136567Y83333D01*
X135983Y83250D01*
X135483Y83000D01*
X135150Y82417D01*
X134983Y81917D01*
Y81417D01*
X135150Y80917D01*
X135567Y80417D01*
X136067Y80083D01*
X136650Y80000D01*
X137233Y80167D01*
X137817Y80667D01*
G01X145517Y83333D02*
X146517Y80000D01*
X147600Y83333D01*
X148683Y80000D01*
X149683Y83333D01*
G01X153200D02*
Y80000D01*
G01Y84667D02*
X153033Y84750D01*
Y84917D01*
X153200Y85000D01*
X153367Y84917D01*
Y84750D01*
X153200Y84667D01*
G01X160300Y85000D02*
Y80000D01*
G01Y80750D02*
X159967Y80333D01*
X159467Y80083D01*
X158883Y80000D01*
X158217Y80167D01*
X157717Y80583D01*
X157383Y81083D01*
X157300Y81667D01*
X157383Y82250D01*
X157717Y82750D01*
X158217Y83167D01*
X158883Y83333D01*
X159467Y83250D01*
X159883Y83083D01*
X160300Y82750D01*
G01X164400Y85000D02*
Y80000D01*
G01X163233Y83333D02*
X165567D01*
G01X168583Y80000D02*
Y85000D01*
G01Y82583D02*
X169000Y83000D01*
X169417Y83250D01*
X170083Y83333D01*
X170583Y83250D01*
X171167Y82917D01*
X171417Y82417D01*
Y80000D01*
G01X112333Y111500D02*
Y116500D01*
X114417D01*
X115083Y116250D01*
X115500Y115917D01*
X115667Y115250D01*
X115500Y114583D01*
X115000Y114167D01*
X114417Y113917D01*
X112333D01*
G01X114417D02*
X115667Y111500D01*
G01X118350Y113750D02*
X121017D01*
X120767Y114333D01*
X120350Y114667D01*
X119767Y114833D01*
X119183Y114750D01*
X118683Y114500D01*
X118350Y113917D01*
X118183Y113417D01*
Y112917D01*
X118350Y112417D01*
X118767Y111917D01*
X119267Y111583D01*
X119850Y111500D01*
X120433Y111667D01*
X121017Y112167D01*
G01X125200Y111500D02*
Y116500D01*
G01X132300Y111500D02*
Y114833D01*
G01Y114250D02*
X131967Y114583D01*
X131467Y114750D01*
X130883Y114833D01*
X130300Y114667D01*
X129800Y114333D01*
X129467Y113833D01*
X129300Y113167D01*
X129467Y112500D01*
X129800Y112000D01*
X130300Y111667D01*
X130883Y111500D01*
X131467Y111583D01*
X131967Y111833D01*
X132300Y112167D01*
G01X136400Y116500D02*
Y111500D01*
G01X135233Y114833D02*
X137567D01*
G01X142000D02*
Y111500D01*
G01Y116167D02*
X141833Y116250D01*
Y116417D01*
X142000Y116500D01*
X142167Y116417D01*
Y116250D01*
X142000Y116167D01*
G01X146100Y114833D02*
X147600Y111500D01*
X149100Y114833D01*
G01X151950Y113750D02*
X154617D01*
X154367Y114333D01*
X153950Y114667D01*
X153367Y114833D01*
X152783Y114750D01*
X152283Y114500D01*
X151950Y113917D01*
X151783Y113417D01*
Y112917D01*
X151950Y112417D01*
X152367Y111917D01*
X152867Y111583D01*
X153450Y111500D01*
X154033Y111667D01*
X154617Y112167D01*
G01X162900Y109833D02*
Y114833D01*
G01Y114083D02*
X163317Y114500D01*
X163733Y114750D01*
X164400Y114833D01*
X164983Y114750D01*
X165567Y114333D01*
X165817Y113750D01*
X165900Y113167D01*
X165817Y112583D01*
X165567Y112000D01*
X165067Y111667D01*
X164400Y111500D01*
X163817Y111583D01*
X163233Y111833D01*
X162900Y112167D01*
G01X170000Y111500D02*
X169500Y111583D01*
X169000Y111917D01*
X168667Y112500D01*
X168500Y113167D01*
X168667Y113833D01*
X169000Y114417D01*
X169500Y114750D01*
X170000Y114833D01*
X170500Y114750D01*
X171000Y114417D01*
X171333Y113833D01*
X171417Y113167D01*
X171333Y112500D01*
X171000Y111917D01*
X170500Y111583D01*
X170000Y111500D01*
G01X174350Y112083D02*
X174767Y111750D01*
X175350Y111500D01*
X175850D01*
X176350Y111667D01*
X176683Y111917D01*
X176850Y112250D01*
X176767Y112750D01*
X176433Y113000D01*
X174933Y113500D01*
X174600Y114083D01*
X174767Y114500D01*
X175100Y114750D01*
X175600Y114833D01*
X176100Y114750D01*
X176600Y114500D01*
G01X181200Y114833D02*
Y111500D01*
G01Y116167D02*
X181033Y116250D01*
Y116417D01*
X181200Y116500D01*
X181367Y116417D01*
Y116250D01*
X181200Y116167D01*
G01X186800Y116500D02*
Y111500D01*
G01X185633Y114833D02*
X187967D01*
G01X192400D02*
Y111500D01*
G01Y116167D02*
X192233Y116250D01*
Y116417D01*
X192400Y116500D01*
X192567Y116417D01*
Y116250D01*
X192400Y116167D01*
G01X198000Y111500D02*
X197500Y111583D01*
X197000Y111917D01*
X196667Y112500D01*
X196500Y113167D01*
X196667Y113833D01*
X197000Y114417D01*
X197500Y114750D01*
X198000Y114833D01*
X198500Y114750D01*
X199000Y114417D01*
X199333Y113833D01*
X199417Y113167D01*
X199333Y112500D01*
X199000Y111917D01*
X198500Y111583D01*
X198000Y111500D01*
G01X202183D02*
Y114833D01*
G01Y114000D02*
X202517Y114417D01*
X203017Y114750D01*
X203683Y114833D01*
X204267Y114750D01*
X204767Y114417D01*
X205017Y113833D01*
Y111500D01*
G01X103500Y60500D02*
X694500D01*
G01X114000Y143500D02*
Y138500D01*
G01X112833Y141833D02*
X115167D01*
G01X118183Y138500D02*
Y143500D01*
G01Y141083D02*
X118600Y141500D01*
X119017Y141750D01*
X119683Y141833D01*
X120183Y141750D01*
X120767Y141417D01*
X121017Y140917D01*
Y138500D01*
G01X125200Y141833D02*
Y138500D01*
G01Y143167D02*
X125033Y143250D01*
Y143417D01*
X125200Y143500D01*
X125367Y143417D01*
Y143250D01*
X125200Y143167D01*
G01X132133Y141417D02*
X131550Y141750D01*
X131050Y141833D01*
X130383Y141667D01*
X129883Y141333D01*
X129550Y140750D01*
X129467Y140167D01*
X129550Y139583D01*
X129883Y139083D01*
X130383Y138667D01*
X131050Y138500D01*
X131633Y138667D01*
X132133Y139000D01*
G01X134983Y138500D02*
Y143500D01*
G01X137650Y141833D02*
X134983Y139917D01*
G01X136067Y140667D02*
X137817Y138500D01*
G01X140583D02*
Y141833D01*
G01Y141000D02*
X140917Y141417D01*
X141417Y141750D01*
X142083Y141833D01*
X142667Y141750D01*
X143167Y141417D01*
X143417Y140833D01*
Y138500D01*
G01X146350Y140750D02*
X149017D01*
X148767Y141333D01*
X148350Y141667D01*
X147767Y141833D01*
X147183Y141750D01*
X146683Y141500D01*
X146350Y140917D01*
X146183Y140417D01*
Y139917D01*
X146350Y139417D01*
X146767Y138917D01*
X147267Y138583D01*
X147850Y138500D01*
X148433Y138667D01*
X149017Y139167D01*
G01X151950Y139083D02*
X152367Y138750D01*
X152950Y138500D01*
X153450D01*
X153950Y138667D01*
X154283Y138917D01*
X154450Y139250D01*
X154367Y139750D01*
X154033Y140000D01*
X152533Y140500D01*
X152200Y141083D01*
X152367Y141500D01*
X152700Y141750D01*
X153200Y141833D01*
X153700Y141750D01*
X154200Y141500D01*
G01X157550Y139083D02*
X157967Y138750D01*
X158550Y138500D01*
X159050D01*
X159550Y138667D01*
X159883Y138917D01*
X160050Y139250D01*
X159967Y139750D01*
X159633Y140000D01*
X158133Y140500D01*
X157800Y141083D01*
X157967Y141500D01*
X158300Y141750D01*
X158800Y141833D01*
X159300Y141750D01*
X159800Y141500D01*
G01X171500Y138500D02*
Y141833D01*
G01Y141250D02*
X171167Y141583D01*
X170667Y141750D01*
X170083Y141833D01*
X169500Y141667D01*
X169000Y141333D01*
X168667Y140833D01*
X168500Y140167D01*
X168667Y139500D01*
X169000Y139000D01*
X169500Y138667D01*
X170083Y138500D01*
X170667Y138583D01*
X171167Y138833D01*
X171500Y139167D01*
G01X175100Y138500D02*
Y142750D01*
X175267Y143167D01*
X175600Y143417D01*
X176100Y143500D01*
X176600Y143333D01*
X176850Y142917D01*
G01X175850Y141500D02*
X174183D01*
G01X181200Y143500D02*
Y138500D01*
G01X180033Y141833D02*
X182367D01*
G01X185550Y140750D02*
X188217D01*
X187967Y141333D01*
X187550Y141667D01*
X186967Y141833D01*
X186383Y141750D01*
X185883Y141500D01*
X185550Y140917D01*
X185383Y140417D01*
Y139917D01*
X185550Y139417D01*
X185967Y138917D01*
X186467Y138583D01*
X187050Y138500D01*
X187633Y138667D01*
X188217Y139167D01*
G01X191233Y138500D02*
Y141833D01*
G01Y141167D02*
X191650Y141500D01*
X192067Y141750D01*
X192650Y141833D01*
X193067Y141750D01*
X193567Y141500D01*
G01X202100Y136833D02*
Y141833D01*
G01Y141083D02*
X202517Y141500D01*
X202933Y141750D01*
X203600Y141833D01*
X204183Y141750D01*
X204767Y141333D01*
X205017Y140750D01*
X205100Y140167D01*
X205017Y139583D01*
X204767Y139000D01*
X204267Y138667D01*
X203600Y138500D01*
X203017Y138583D01*
X202433Y138833D01*
X202100Y139167D01*
G01X209200Y138500D02*
Y143500D01*
G01X216300Y138500D02*
Y141833D01*
G01Y141250D02*
X215967Y141583D01*
X215467Y141750D01*
X214883Y141833D01*
X214300Y141667D01*
X213800Y141333D01*
X213467Y140833D01*
X213300Y140167D01*
X213467Y139500D01*
X213800Y139000D01*
X214300Y138667D01*
X214883Y138500D01*
X215467Y138583D01*
X215967Y138833D01*
X216300Y139167D01*
G01X220400Y143500D02*
Y138500D01*
G01X219233Y141833D02*
X221567D01*
G01X226000D02*
Y138500D01*
G01Y143167D02*
X225833Y143250D01*
Y143417D01*
X226000Y143500D01*
X226167Y143417D01*
Y143250D01*
X226000Y143167D01*
G01X230183Y138500D02*
Y141833D01*
G01Y141000D02*
X230517Y141417D01*
X231017Y141750D01*
X231683Y141833D01*
X232267Y141750D01*
X232767Y141417D01*
X233017Y140833D01*
Y138500D01*
G01X236033Y137250D02*
X236617Y136917D01*
X237283Y136833D01*
X237867Y136917D01*
X238367Y137333D01*
X238700Y137917D01*
Y141833D01*
G01Y141167D02*
X238367Y141500D01*
X237867Y141750D01*
X237283Y141833D01*
X236617Y141667D01*
X236200Y141333D01*
X235867Y140750D01*
X235700Y140167D01*
X235783Y139667D01*
X236117Y139083D01*
X236617Y138667D01*
X237283Y138500D01*
X237783Y138583D01*
X238367Y138917D01*
X238700Y139250D01*
G01X115667Y148500D02*
X112333D01*
Y153500D01*
X115667D01*
G01X114333Y151083D02*
X112333D01*
G01X118350Y151833D02*
X120850Y148500D01*
G01Y151833D02*
X118350Y148500D01*
G01X125200Y153500D02*
Y148500D01*
G01X124033Y151833D02*
X126367D01*
G01X129550Y150750D02*
X132217D01*
X131967Y151333D01*
X131550Y151667D01*
X130967Y151833D01*
X130383Y151750D01*
X129883Y151500D01*
X129550Y150917D01*
X129383Y150417D01*
Y149917D01*
X129550Y149417D01*
X129967Y148917D01*
X130467Y148583D01*
X131050Y148500D01*
X131633Y148667D01*
X132217Y149167D01*
G01X135233Y148500D02*
Y151833D01*
G01Y151167D02*
X135650Y151500D01*
X136067Y151750D01*
X136650Y151833D01*
X137067Y151750D01*
X137567Y151500D01*
G01X140583Y148500D02*
Y151833D01*
G01Y151000D02*
X140917Y151417D01*
X141417Y151750D01*
X142083Y151833D01*
X142667Y151750D01*
X143167Y151417D01*
X143417Y150833D01*
Y148500D01*
G01X149100D02*
Y151833D01*
G01Y151250D02*
X148767Y151583D01*
X148267Y151750D01*
X147683Y151833D01*
X147100Y151667D01*
X146600Y151333D01*
X146267Y150833D01*
X146100Y150167D01*
X146267Y149500D01*
X146600Y149000D01*
X147100Y148667D01*
X147683Y148500D01*
X148267Y148583D01*
X148767Y148833D01*
X149100Y149167D01*
G01X153200Y148500D02*
Y153500D01*
G01X165733Y151417D02*
X165150Y151750D01*
X164650Y151833D01*
X163983Y151667D01*
X163483Y151333D01*
X163150Y150750D01*
X163067Y150167D01*
X163150Y149583D01*
X163483Y149083D01*
X163983Y148667D01*
X164650Y148500D01*
X165233Y148667D01*
X165733Y149000D01*
G01X170000Y148500D02*
X169500Y148583D01*
X169000Y148917D01*
X168667Y149500D01*
X168500Y150167D01*
X168667Y150833D01*
X169000Y151417D01*
X169500Y151750D01*
X170000Y151833D01*
X170500Y151750D01*
X171000Y151417D01*
X171333Y150833D01*
X171417Y150167D01*
X171333Y149500D01*
X171000Y148917D01*
X170500Y148583D01*
X170000Y148500D01*
G01X174183D02*
Y151833D01*
G01Y151000D02*
X174517Y151417D01*
X175017Y151750D01*
X175683Y151833D01*
X176267Y151750D01*
X176767Y151417D01*
X177017Y150833D01*
Y148500D01*
G01X182700Y153500D02*
Y148500D01*
G01Y149250D02*
X182367Y148833D01*
X181867Y148583D01*
X181283Y148500D01*
X180617Y148667D01*
X180117Y149083D01*
X179783Y149583D01*
X179700Y150167D01*
X179783Y150750D01*
X180117Y151250D01*
X180617Y151667D01*
X181283Y151833D01*
X181867Y151750D01*
X182283Y151583D01*
X182700Y151250D01*
G01X185383Y151833D02*
Y149500D01*
X185717Y148917D01*
X186217Y148583D01*
X186800Y148500D01*
X187383Y148583D01*
X187883Y148917D01*
X188217Y149500D01*
G01Y148500D02*
Y151833D01*
G01X193733Y151417D02*
X193150Y151750D01*
X192650Y151833D01*
X191983Y151667D01*
X191483Y151333D01*
X191150Y150750D01*
X191067Y150167D01*
X191150Y149583D01*
X191483Y149083D01*
X191983Y148667D01*
X192650Y148500D01*
X193233Y148667D01*
X193733Y149000D01*
G01X198000Y153500D02*
Y148500D01*
G01X196833Y151833D02*
X199167D01*
G01X203600Y148500D02*
X203100Y148583D01*
X202600Y148917D01*
X202267Y149500D01*
X202100Y150167D01*
X202267Y150833D01*
X202600Y151417D01*
X203100Y151750D01*
X203600Y151833D01*
X204100Y151750D01*
X204600Y151417D01*
X204933Y150833D01*
X205017Y150167D01*
X204933Y149500D01*
X204600Y148917D01*
X204100Y148583D01*
X203600Y148500D01*
G01X208033D02*
Y151833D01*
G01Y151167D02*
X208450Y151500D01*
X208867Y151750D01*
X209450Y151833D01*
X209867Y151750D01*
X210367Y151500D01*
G01X112333Y356500D02*
Y351500D01*
X115667D01*
G01X121100D02*
Y354833D01*
G01Y354250D02*
X120767Y354583D01*
X120267Y354750D01*
X119683Y354833D01*
X119100Y354667D01*
X118600Y354333D01*
X118267Y353833D01*
X118100Y353167D01*
X118267Y352500D01*
X118600Y352000D01*
X119100Y351667D01*
X119683Y351500D01*
X120267Y351583D01*
X120767Y351833D01*
X121100Y352167D01*
G01X123950Y352083D02*
X124367Y351750D01*
X124950Y351500D01*
X125450D01*
X125950Y351667D01*
X126283Y351917D01*
X126450Y352250D01*
X126367Y352750D01*
X126033Y353000D01*
X124533Y353500D01*
X124200Y354083D01*
X124367Y354500D01*
X124700Y354750D01*
X125200Y354833D01*
X125700Y354750D01*
X126200Y354500D01*
G01X129550Y353750D02*
X132217D01*
X131967Y354333D01*
X131550Y354667D01*
X130967Y354833D01*
X130383Y354750D01*
X129883Y354500D01*
X129550Y353917D01*
X129383Y353417D01*
Y352917D01*
X129550Y352417D01*
X129967Y351917D01*
X130467Y351583D01*
X131050Y351500D01*
X131633Y351667D01*
X132217Y352167D01*
G01X135233Y351500D02*
Y354833D01*
G01Y354167D02*
X135650Y354500D01*
X136067Y354750D01*
X136650Y354833D01*
X137067Y354750D01*
X137567Y354500D01*
G01X146100Y354833D02*
X147600Y351500D01*
X149100Y354833D01*
G01X153200D02*
Y351500D01*
G01Y356167D02*
X153033Y356250D01*
Y356417D01*
X153200Y356500D01*
X153367Y356417D01*
Y356250D01*
X153200Y356167D01*
G01X160300Y351500D02*
Y354833D01*
G01Y354250D02*
X159967Y354583D01*
X159467Y354750D01*
X158883Y354833D01*
X158300Y354667D01*
X157800Y354333D01*
X157467Y353833D01*
X157300Y353167D01*
X157467Y352500D01*
X157800Y352000D01*
X158300Y351667D01*
X158883Y351500D01*
X159467Y351583D01*
X159967Y351833D01*
X160300Y352167D01*
G01X168167Y351333D02*
X171833Y355000D01*
G01X170000Y355667D02*
Y350667D01*
G01X171833Y351333D02*
X168167Y355000D01*
G01X167500Y353167D02*
X172500D01*
G01X175183Y349833D02*
X174350Y350667D01*
X173933Y351500D01*
Y354833D01*
X174350Y355667D01*
X175183Y356500D01*
G01X179367Y352250D02*
X179867Y351833D01*
X180450Y351583D01*
X181200Y351500D01*
X181950Y351667D01*
X182533Y352000D01*
X182950Y352583D01*
X183033Y353250D01*
X182867Y353917D01*
X182450Y354333D01*
X181867Y354667D01*
X181283Y354750D01*
X180700Y354667D01*
X179950Y354333D01*
X180200Y356500D01*
X182450D01*
G01X186800Y351333D02*
X186633Y351417D01*
Y351583D01*
X186800Y351667D01*
X186967Y351583D01*
Y351417D01*
X186800Y351333D01*
G01X192400Y351500D02*
Y356500D01*
X191400Y355500D01*
G01Y351500D02*
X193400D01*
G01X198417Y349833D02*
X199250Y350667D01*
X199667Y351500D01*
Y354833D01*
X199250Y355667D01*
X198417Y356500D01*
G01X112333Y406500D02*
Y411500D01*
X114333D01*
X115000Y411250D01*
X115500Y410667D01*
X115667Y410000D01*
X115500Y409333D01*
X115083Y408833D01*
X114333Y408583D01*
X112333D01*
G01X119600Y411500D02*
Y406500D01*
G01X117683Y411500D02*
X121517D01*
G01X123450Y406500D02*
Y411500D01*
G01X126950D02*
Y406500D01*
G01Y409000D02*
X123450D01*
G01X135233Y406500D02*
Y409833D01*
G01Y409167D02*
X135650Y409500D01*
X136067Y409750D01*
X136650Y409833D01*
X137067Y409750D01*
X137567Y409500D01*
G01X140750Y408750D02*
X143417D01*
X143167Y409333D01*
X142750Y409667D01*
X142167Y409833D01*
X141583Y409750D01*
X141083Y409500D01*
X140750Y408917D01*
X140583Y408417D01*
Y407917D01*
X140750Y407417D01*
X141167Y406917D01*
X141667Y406583D01*
X142250Y406500D01*
X142833Y406667D01*
X143417Y407167D01*
G01X146433Y405250D02*
X147017Y404917D01*
X147683Y404833D01*
X148267Y404917D01*
X148767Y405333D01*
X149100Y405917D01*
Y409833D01*
G01Y409167D02*
X148767Y409500D01*
X148267Y409750D01*
X147683Y409833D01*
X147017Y409667D01*
X146600Y409333D01*
X146267Y408750D01*
X146100Y408167D01*
X146183Y407667D01*
X146517Y407083D01*
X147017Y406667D01*
X147683Y406500D01*
X148183Y406583D01*
X148767Y406917D01*
X149100Y407250D01*
G01X153200Y409833D02*
Y406500D01*
G01Y411167D02*
X153033Y411250D01*
Y411417D01*
X153200Y411500D01*
X153367Y411417D01*
Y411250D01*
X153200Y411167D01*
G01X157550Y407083D02*
X157967Y406750D01*
X158550Y406500D01*
X159050D01*
X159550Y406667D01*
X159883Y406917D01*
X160050Y407250D01*
X159967Y407750D01*
X159633Y408000D01*
X158133Y408500D01*
X157800Y409083D01*
X157967Y409500D01*
X158300Y409750D01*
X158800Y409833D01*
X159300Y409750D01*
X159800Y409500D01*
G01X164400Y411500D02*
Y406500D01*
G01X163233Y409833D02*
X165567D01*
G01X168833Y406500D02*
Y409833D01*
G01Y409167D02*
X169250Y409500D01*
X169667Y409750D01*
X170250Y409833D01*
X170667Y409750D01*
X171167Y409500D01*
G01X177100Y406500D02*
Y409833D01*
G01Y409250D02*
X176767Y409583D01*
X176267Y409750D01*
X175683Y409833D01*
X175100Y409667D01*
X174600Y409333D01*
X174267Y408833D01*
X174100Y408167D01*
X174267Y407500D01*
X174600Y407000D01*
X175100Y406667D01*
X175683Y406500D01*
X176267Y406583D01*
X176767Y406833D01*
X177100Y407167D01*
G01X181200Y411500D02*
Y406500D01*
G01X180033Y409833D02*
X182367D01*
G01X186800D02*
Y406500D01*
G01Y411167D02*
X186633Y411250D01*
Y411417D01*
X186800Y411500D01*
X186967Y411417D01*
Y411250D01*
X186800Y411167D01*
G01X192400Y406500D02*
X191900Y406583D01*
X191400Y406917D01*
X191067Y407500D01*
X190900Y408167D01*
X191067Y408833D01*
X191400Y409417D01*
X191900Y409750D01*
X192400Y409833D01*
X192900Y409750D01*
X193400Y409417D01*
X193733Y408833D01*
X193817Y408167D01*
X193733Y407500D01*
X193400Y406917D01*
X192900Y406583D01*
X192400Y406500D01*
G01X196583D02*
Y409833D01*
G01Y409000D02*
X196917Y409417D01*
X197417Y409750D01*
X198083Y409833D01*
X198667Y409750D01*
X199167Y409417D01*
X199417Y408833D01*
Y406500D01*
G01X112167Y433000D02*
Y438000D01*
X113833D01*
X114500Y437750D01*
X115000Y437417D01*
X115417Y436917D01*
X115750Y436333D01*
X115833Y435500D01*
X115750Y434667D01*
X115417Y434083D01*
X115000Y433583D01*
X114500Y433250D01*
X113833Y433000D01*
X112167D01*
G01X118350Y435250D02*
X121017D01*
X120767Y435833D01*
X120350Y436167D01*
X119767Y436333D01*
X119183Y436250D01*
X118683Y436000D01*
X118350Y435417D01*
X118183Y434917D01*
Y434417D01*
X118350Y433917D01*
X118767Y433417D01*
X119267Y433083D01*
X119850Y433000D01*
X120433Y433167D01*
X121017Y433667D01*
G01X123700Y431333D02*
Y436333D01*
G01Y435583D02*
X124117Y436000D01*
X124533Y436250D01*
X125200Y436333D01*
X125783Y436250D01*
X126367Y435833D01*
X126617Y435250D01*
X126700Y434667D01*
X126617Y434083D01*
X126367Y433500D01*
X125867Y433167D01*
X125200Y433000D01*
X124617Y433083D01*
X124033Y433333D01*
X123700Y433667D01*
G01X130800Y438000D02*
Y433000D01*
G01X129633Y436333D02*
X131967D01*
G01X134983Y433000D02*
Y438000D01*
G01Y435583D02*
X135400Y436000D01*
X135817Y436250D01*
X136483Y436333D01*
X136983Y436250D01*
X137567Y435917D01*
X137817Y435417D01*
Y433000D01*
G01X148933Y435917D02*
X148350Y436250D01*
X147850Y436333D01*
X147183Y436167D01*
X146683Y435833D01*
X146350Y435250D01*
X146267Y434667D01*
X146350Y434083D01*
X146683Y433583D01*
X147183Y433167D01*
X147850Y433000D01*
X148433Y433167D01*
X148933Y433500D01*
G01X153200Y433000D02*
X152700Y433083D01*
X152200Y433417D01*
X151867Y434000D01*
X151700Y434667D01*
X151867Y435333D01*
X152200Y435917D01*
X152700Y436250D01*
X153200Y436333D01*
X153700Y436250D01*
X154200Y435917D01*
X154533Y435333D01*
X154617Y434667D01*
X154533Y434000D01*
X154200Y433417D01*
X153700Y433083D01*
X153200Y433000D01*
G01X157383D02*
Y436333D01*
G01Y435500D02*
X157717Y435917D01*
X158217Y436250D01*
X158883Y436333D01*
X159467Y436250D01*
X159967Y435917D01*
X160217Y435333D01*
Y433000D01*
G01X164400Y438000D02*
Y433000D01*
G01X163233Y436333D02*
X165567D01*
G01X168833Y433000D02*
Y436333D01*
G01Y435667D02*
X169250Y436000D01*
X169667Y436250D01*
X170250Y436333D01*
X170667Y436250D01*
X171167Y436000D01*
G01X175600Y433000D02*
X175100Y433083D01*
X174600Y433417D01*
X174267Y434000D01*
X174100Y434667D01*
X174267Y435333D01*
X174600Y435917D01*
X175100Y436250D01*
X175600Y436333D01*
X176100Y436250D01*
X176600Y435917D01*
X176933Y435333D01*
X177017Y434667D01*
X176933Y434000D01*
X176600Y433417D01*
X176100Y433083D01*
X175600Y433000D01*
G01X181200D02*
Y438000D01*
G01X190983Y433000D02*
Y438000D01*
G01Y435583D02*
X191400Y436000D01*
X191817Y436250D01*
X192483Y436333D01*
X192983Y436250D01*
X193567Y435917D01*
X193817Y435417D01*
Y433000D01*
G01X198000D02*
X197500Y433083D01*
X197000Y433417D01*
X196667Y434000D01*
X196500Y434667D01*
X196667Y435333D01*
X197000Y435917D01*
X197500Y436250D01*
X198000Y436333D01*
X198500Y436250D01*
X199000Y435917D01*
X199333Y435333D01*
X199417Y434667D01*
X199333Y434000D01*
X199000Y433417D01*
X198500Y433083D01*
X198000Y433000D01*
G01X203600D02*
Y438000D01*
G01X207950Y435250D02*
X210617D01*
X210367Y435833D01*
X209950Y436167D01*
X209367Y436333D01*
X208783Y436250D01*
X208283Y436000D01*
X207950Y435417D01*
X207783Y434917D01*
Y434417D01*
X207950Y433917D01*
X208367Y433417D01*
X208867Y433083D01*
X209450Y433000D01*
X210033Y433167D01*
X210617Y433667D01*
G01X105000Y364500D02*
X694500D01*
G01X103500Y424000D02*
X694500D01*
G01X112250Y513500D02*
Y518500D01*
G01X115750D02*
Y513500D01*
G01Y516000D02*
X112250D01*
G01X119600Y513500D02*
X119100Y513583D01*
X118600Y513917D01*
X118267Y514500D01*
X118100Y515167D01*
X118267Y515833D01*
X118600Y516417D01*
X119100Y516750D01*
X119600Y516833D01*
X120100Y516750D01*
X120600Y516417D01*
X120933Y515833D01*
X121017Y515167D01*
X120933Y514500D01*
X120600Y513917D01*
X120100Y513583D01*
X119600Y513500D01*
G01X125200D02*
Y518500D01*
G01X129550Y515750D02*
X132217D01*
X131967Y516333D01*
X131550Y516667D01*
X130967Y516833D01*
X130383Y516750D01*
X129883Y516500D01*
X129550Y515917D01*
X129383Y515417D01*
Y514917D01*
X129550Y514417D01*
X129967Y513917D01*
X130467Y513583D01*
X131050Y513500D01*
X131633Y513667D01*
X132217Y514167D01*
G01X140750Y514083D02*
X141167Y513750D01*
X141750Y513500D01*
X142250D01*
X142750Y513667D01*
X143083Y513917D01*
X143250Y514250D01*
X143167Y514750D01*
X142833Y515000D01*
X141333Y515500D01*
X141000Y516083D01*
X141167Y516500D01*
X141500Y516750D01*
X142000Y516833D01*
X142500Y516750D01*
X143000Y516500D01*
G01X147600Y516833D02*
Y513500D01*
G01Y518167D02*
X147433Y518250D01*
Y518417D01*
X147600Y518500D01*
X147767Y518417D01*
Y518250D01*
X147600Y518167D01*
G01X151950Y516833D02*
X154450D01*
X151950Y513500D01*
X154450D01*
G01X157550Y515750D02*
X160217D01*
X159967Y516333D01*
X159550Y516667D01*
X158967Y516833D01*
X158383Y516750D01*
X157883Y516500D01*
X157550Y515917D01*
X157383Y515417D01*
Y514917D01*
X157550Y514417D01*
X157967Y513917D01*
X158467Y513583D01*
X159050Y513500D01*
X159633Y513667D01*
X160217Y514167D01*
G01X112333Y455000D02*
Y460000D01*
X114417D01*
X115083Y459750D01*
X115500Y459417D01*
X115667Y458750D01*
X115500Y458083D01*
X115000Y457667D01*
X114417Y457417D01*
X112333D01*
G01X114417D02*
X115667Y455000D01*
G01X119600D02*
X119100Y455083D01*
X118600Y455417D01*
X118267Y456000D01*
X118100Y456667D01*
X118267Y457333D01*
X118600Y457917D01*
X119100Y458250D01*
X119600Y458333D01*
X120100Y458250D01*
X120600Y457917D01*
X120933Y457333D01*
X121017Y456667D01*
X120933Y456000D01*
X120600Y455417D01*
X120100Y455083D01*
X119600Y455000D01*
G01X123783Y458333D02*
Y456000D01*
X124117Y455417D01*
X124617Y455083D01*
X125200Y455000D01*
X125783Y455083D01*
X126283Y455417D01*
X126617Y456000D01*
G01Y455000D02*
Y458333D01*
G01X129633Y453750D02*
X130217Y453417D01*
X130883Y453333D01*
X131467Y453417D01*
X131967Y453833D01*
X132300Y454417D01*
Y458333D01*
G01Y457667D02*
X131967Y458000D01*
X131467Y458250D01*
X130883Y458333D01*
X130217Y458167D01*
X129800Y457833D01*
X129467Y457250D01*
X129300Y456667D01*
X129383Y456167D01*
X129717Y455583D01*
X130217Y455167D01*
X130883Y455000D01*
X131383Y455083D01*
X131967Y455417D01*
X132300Y455750D01*
G01X134983Y455000D02*
Y460000D01*
G01Y457583D02*
X135400Y458000D01*
X135817Y458250D01*
X136483Y458333D01*
X136983Y458250D01*
X137567Y457917D01*
X137817Y457417D01*
Y455000D01*
G01X140583D02*
Y458333D01*
G01Y457500D02*
X140917Y457917D01*
X141417Y458250D01*
X142083Y458333D01*
X142667Y458250D01*
X143167Y457917D01*
X143417Y457333D01*
Y455000D01*
G01X146350Y457250D02*
X149017D01*
X148767Y457833D01*
X148350Y458167D01*
X147767Y458333D01*
X147183Y458250D01*
X146683Y458000D01*
X146350Y457417D01*
X146183Y456917D01*
Y456417D01*
X146350Y455917D01*
X146767Y455417D01*
X147267Y455083D01*
X147850Y455000D01*
X148433Y455167D01*
X149017Y455667D01*
G01X151950Y455583D02*
X152367Y455250D01*
X152950Y455000D01*
X153450D01*
X153950Y455167D01*
X154283Y455417D01*
X154450Y455750D01*
X154367Y456250D01*
X154033Y456500D01*
X152533Y457000D01*
X152200Y457583D01*
X152367Y458000D01*
X152700Y458250D01*
X153200Y458333D01*
X153700Y458250D01*
X154200Y458000D01*
G01X157550Y455583D02*
X157967Y455250D01*
X158550Y455000D01*
X159050D01*
X159550Y455167D01*
X159883Y455417D01*
X160050Y455750D01*
X159967Y456250D01*
X159633Y456500D01*
X158133Y457000D01*
X157800Y457583D01*
X157967Y458000D01*
X158300Y458250D01*
X158800Y458333D01*
X159300Y458250D01*
X159800Y458000D01*
G01X103500Y449000D02*
X694500D01*
G01X104000Y464000D02*
X694500D01*
G01X111917Y610000D02*
X114000Y605000D01*
X116083Y610000D01*
G01X119600Y608333D02*
Y605000D01*
G01Y609667D02*
X119433Y609750D01*
Y609917D01*
X119600Y610000D01*
X119767Y609917D01*
Y609750D01*
X119600Y609667D01*
G01X126700Y605000D02*
Y608333D01*
G01Y607750D02*
X126367Y608083D01*
X125867Y608250D01*
X125283Y608333D01*
X124700Y608167D01*
X124200Y607833D01*
X123867Y607333D01*
X123700Y606667D01*
X123867Y606000D01*
X124200Y605500D01*
X124700Y605167D01*
X125283Y605000D01*
X125867Y605083D01*
X126367Y605333D01*
X126700Y605667D01*
G01X134983Y605000D02*
Y610000D01*
G01Y607583D02*
X135400Y608000D01*
X135817Y608250D01*
X136483Y608333D01*
X136983Y608250D01*
X137567Y607917D01*
X137817Y607417D01*
Y605000D01*
G01X142000D02*
X141500Y605083D01*
X141000Y605417D01*
X140667Y606000D01*
X140500Y606667D01*
X140667Y607333D01*
X141000Y607917D01*
X141500Y608250D01*
X142000Y608333D01*
X142500Y608250D01*
X143000Y607917D01*
X143333Y607333D01*
X143417Y606667D01*
X143333Y606000D01*
X143000Y605417D01*
X142500Y605083D01*
X142000Y605000D01*
G01X147600D02*
Y610000D01*
G01X151950Y607250D02*
X154617D01*
X154367Y607833D01*
X153950Y608167D01*
X153367Y608333D01*
X152783Y608250D01*
X152283Y608000D01*
X151950Y607417D01*
X151783Y606917D01*
Y606417D01*
X151950Y605917D01*
X152367Y605417D01*
X152867Y605083D01*
X153450Y605000D01*
X154033Y605167D01*
X154617Y605667D01*
G01X164400Y610000D02*
Y605000D01*
G01X163233Y608333D02*
X165567D01*
G01X168583Y605000D02*
Y610000D01*
G01Y607583D02*
X169000Y608000D01*
X169417Y608250D01*
X170083Y608333D01*
X170583Y608250D01*
X171167Y607917D01*
X171417Y607417D01*
Y605000D01*
G01X174350Y607250D02*
X177017D01*
X176767Y607833D01*
X176350Y608167D01*
X175767Y608333D01*
X175183Y608250D01*
X174683Y608000D01*
X174350Y607417D01*
X174183Y606917D01*
Y606417D01*
X174350Y605917D01*
X174767Y605417D01*
X175267Y605083D01*
X175850Y605000D01*
X176433Y605167D01*
X177017Y605667D01*
G01X180033Y605000D02*
Y608333D01*
G01Y607667D02*
X180450Y608000D01*
X180867Y608250D01*
X181450Y608333D01*
X181867Y608250D01*
X182367Y608000D01*
G01X184300Y605000D02*
Y608333D01*
G01Y607417D02*
X184550Y607833D01*
X184967Y608167D01*
X185550Y608333D01*
X186133Y608167D01*
X186550Y607833D01*
X186800Y607417D01*
Y605000D01*
G01Y607417D02*
X187050Y607833D01*
X187467Y608167D01*
X188050Y608333D01*
X188633Y608167D01*
X189050Y607833D01*
X189300Y607333D01*
Y605000D01*
G01X193900D02*
Y608333D01*
G01Y607750D02*
X193567Y608083D01*
X193067Y608250D01*
X192483Y608333D01*
X191900Y608167D01*
X191400Y607833D01*
X191067Y607333D01*
X190900Y606667D01*
X191067Y606000D01*
X191400Y605500D01*
X191900Y605167D01*
X192483Y605000D01*
X193067Y605083D01*
X193567Y605333D01*
X193900Y605667D01*
G01X198000Y605000D02*
Y610000D01*
G01X207700Y603333D02*
Y608333D01*
G01Y607583D02*
X208117Y608000D01*
X208533Y608250D01*
X209200Y608333D01*
X209783Y608250D01*
X210367Y607833D01*
X210617Y607250D01*
X210700Y606667D01*
X210617Y606083D01*
X210367Y605500D01*
X209867Y605167D01*
X209200Y605000D01*
X208617Y605083D01*
X208033Y605333D01*
X207700Y605667D01*
G01X216300Y605000D02*
Y608333D01*
G01Y607750D02*
X215967Y608083D01*
X215467Y608250D01*
X214883Y608333D01*
X214300Y608167D01*
X213800Y607833D01*
X213467Y607333D01*
X213300Y606667D01*
X213467Y606000D01*
X213800Y605500D01*
X214300Y605167D01*
X214883Y605000D01*
X215467Y605083D01*
X215967Y605333D01*
X216300Y605667D01*
G01X221900Y610000D02*
Y605000D01*
G01Y605750D02*
X221567Y605333D01*
X221067Y605083D01*
X220483Y605000D01*
X219817Y605167D01*
X219317Y605583D01*
X218983Y606083D01*
X218900Y606667D01*
X218983Y607250D01*
X219317Y607750D01*
X219817Y608167D01*
X220483Y608333D01*
X221067Y608250D01*
X221483Y608083D01*
X221900Y607750D01*
G01X112250Y588500D02*
Y593500D01*
G01X115750D02*
Y588500D01*
G01Y591000D02*
X112250D01*
G01X119600Y588500D02*
X119100Y588583D01*
X118600Y588917D01*
X118267Y589500D01*
X118100Y590167D01*
X118267Y590833D01*
X118600Y591417D01*
X119100Y591750D01*
X119600Y591833D01*
X120100Y591750D01*
X120600Y591417D01*
X120933Y590833D01*
X121017Y590167D01*
X120933Y589500D01*
X120600Y588917D01*
X120100Y588583D01*
X119600Y588500D01*
G01X125200D02*
Y593500D01*
G01X129550Y590750D02*
X132217D01*
X131967Y591333D01*
X131550Y591667D01*
X130967Y591833D01*
X130383Y591750D01*
X129883Y591500D01*
X129550Y590917D01*
X129383Y590417D01*
Y589917D01*
X129550Y589417D01*
X129967Y588917D01*
X130467Y588583D01*
X131050Y588500D01*
X131633Y588667D01*
X132217Y589167D01*
G01X140500Y586833D02*
Y591833D01*
G01Y591083D02*
X140917Y591500D01*
X141333Y591750D01*
X142000Y591833D01*
X142583Y591750D01*
X143167Y591333D01*
X143417Y590750D01*
X143500Y590167D01*
X143417Y589583D01*
X143167Y589000D01*
X142667Y588667D01*
X142000Y588500D01*
X141417Y588583D01*
X140833Y588833D01*
X140500Y589167D01*
G01X147600Y588500D02*
X147100Y588583D01*
X146600Y588917D01*
X146267Y589500D01*
X146100Y590167D01*
X146267Y590833D01*
X146600Y591417D01*
X147100Y591750D01*
X147600Y591833D01*
X148100Y591750D01*
X148600Y591417D01*
X148933Y590833D01*
X149017Y590167D01*
X148933Y589500D01*
X148600Y588917D01*
X148100Y588583D01*
X147600Y588500D01*
G01X151950Y589083D02*
X152367Y588750D01*
X152950Y588500D01*
X153450D01*
X153950Y588667D01*
X154283Y588917D01*
X154450Y589250D01*
X154367Y589750D01*
X154033Y590000D01*
X152533Y590500D01*
X152200Y591083D01*
X152367Y591500D01*
X152700Y591750D01*
X153200Y591833D01*
X153700Y591750D01*
X154200Y591500D01*
G01X158800Y591833D02*
Y588500D01*
G01Y593167D02*
X158633Y593250D01*
Y593417D01*
X158800Y593500D01*
X158967Y593417D01*
Y593250D01*
X158800Y593167D01*
G01X164400Y593500D02*
Y588500D01*
G01X163233Y591833D02*
X165567D01*
G01X170000D02*
Y588500D01*
G01Y593167D02*
X169833Y593250D01*
Y593417D01*
X170000Y593500D01*
X170167Y593417D01*
Y593250D01*
X170000Y593167D01*
G01X175600Y588500D02*
X175100Y588583D01*
X174600Y588917D01*
X174267Y589500D01*
X174100Y590167D01*
X174267Y590833D01*
X174600Y591417D01*
X175100Y591750D01*
X175600Y591833D01*
X176100Y591750D01*
X176600Y591417D01*
X176933Y590833D01*
X177017Y590167D01*
X176933Y589500D01*
X176600Y588917D01*
X176100Y588583D01*
X175600Y588500D01*
G01X179783D02*
Y591833D01*
G01Y591000D02*
X180117Y591417D01*
X180617Y591750D01*
X181283Y591833D01*
X181867Y591750D01*
X182367Y591417D01*
X182617Y590833D01*
Y588500D01*
G01X192400Y593500D02*
Y588500D01*
G01X191233Y591833D02*
X193567D01*
G01X198000Y588500D02*
X197500Y588583D01*
X197000Y588917D01*
X196667Y589500D01*
X196500Y590167D01*
X196667Y590833D01*
X197000Y591417D01*
X197500Y591750D01*
X198000Y591833D01*
X198500Y591750D01*
X199000Y591417D01*
X199333Y590833D01*
X199417Y590167D01*
X199333Y589500D01*
X199000Y588917D01*
X198500Y588583D01*
X198000Y588500D01*
G01X203600D02*
Y593500D01*
G01X207950Y590750D02*
X210617D01*
X210367Y591333D01*
X209950Y591667D01*
X209367Y591833D01*
X208783Y591750D01*
X208283Y591500D01*
X207950Y590917D01*
X207783Y590417D01*
Y589917D01*
X207950Y589417D01*
X208367Y588917D01*
X208867Y588583D01*
X209450Y588500D01*
X210033Y588667D01*
X210617Y589167D01*
G01X213633Y588500D02*
Y591833D01*
G01Y591167D02*
X214050Y591500D01*
X214467Y591750D01*
X215050Y591833D01*
X215467Y591750D01*
X215967Y591500D01*
G01X221900Y588500D02*
Y591833D01*
G01Y591250D02*
X221567Y591583D01*
X221067Y591750D01*
X220483Y591833D01*
X219900Y591667D01*
X219400Y591333D01*
X219067Y590833D01*
X218900Y590167D01*
X219067Y589500D01*
X219400Y589000D01*
X219900Y588667D01*
X220483Y588500D01*
X221067Y588583D01*
X221567Y588833D01*
X221900Y589167D01*
G01X224583Y588500D02*
Y591833D01*
G01Y591000D02*
X224917Y591417D01*
X225417Y591750D01*
X226083Y591833D01*
X226667Y591750D01*
X227167Y591417D01*
X227417Y590833D01*
Y588500D01*
G01X232933Y591417D02*
X232350Y591750D01*
X231850Y591833D01*
X231183Y591667D01*
X230683Y591333D01*
X230350Y590750D01*
X230267Y590167D01*
X230350Y589583D01*
X230683Y589083D01*
X231183Y588667D01*
X231850Y588500D01*
X232433Y588667D01*
X232933Y589000D01*
G01X235950Y590750D02*
X238617D01*
X238367Y591333D01*
X237950Y591667D01*
X237367Y591833D01*
X236783Y591750D01*
X236283Y591500D01*
X235950Y590917D01*
X235783Y590417D01*
Y589917D01*
X235950Y589417D01*
X236367Y588917D01*
X236867Y588583D01*
X237450Y588500D01*
X238033Y588667D01*
X238617Y589167D01*
G01X103500Y584000D02*
X694500D01*
G01X111917Y620000D02*
X114000Y625000D01*
X116083Y620000D01*
G01X115333Y621750D02*
X112667D01*
G01X118183Y620000D02*
Y623333D01*
G01Y622500D02*
X118517Y622917D01*
X119017Y623250D01*
X119683Y623333D01*
X120267Y623250D01*
X120767Y622917D01*
X121017Y622333D01*
Y620000D01*
G01X125200Y625000D02*
Y620000D01*
G01X124033Y623333D02*
X126367D01*
G01X130800D02*
Y620000D01*
G01Y624667D02*
X130633Y624750D01*
Y624917D01*
X130800Y625000D01*
X130967Y624917D01*
Y624750D01*
X130800Y624667D01*
G01X135317Y621667D02*
X137483D01*
G01X146100Y618333D02*
Y623333D01*
G01Y622583D02*
X146517Y623000D01*
X146933Y623250D01*
X147600Y623333D01*
X148183Y623250D01*
X148767Y622833D01*
X149017Y622250D01*
X149100Y621667D01*
X149017Y621083D01*
X148767Y620500D01*
X148267Y620167D01*
X147600Y620000D01*
X147017Y620083D01*
X146433Y620333D01*
X146100Y620667D01*
G01X154700Y620000D02*
Y623333D01*
G01Y622750D02*
X154367Y623083D01*
X153867Y623250D01*
X153283Y623333D01*
X152700Y623167D01*
X152200Y622833D01*
X151867Y622333D01*
X151700Y621667D01*
X151867Y621000D01*
X152200Y620500D01*
X152700Y620167D01*
X153283Y620000D01*
X153867Y620083D01*
X154367Y620333D01*
X154700Y620667D01*
G01X160300Y625000D02*
Y620000D01*
G01Y620750D02*
X159967Y620333D01*
X159467Y620083D01*
X158883Y620000D01*
X158217Y620167D01*
X157717Y620583D01*
X157383Y621083D01*
X157300Y621667D01*
X157383Y622250D01*
X157717Y622750D01*
X158217Y623167D01*
X158883Y623333D01*
X159467Y623250D01*
X159883Y623083D01*
X160300Y622750D01*
G01X111843Y639590D02*
Y644590D01*
X115677Y639590D01*
Y644590D01*
G01X119360Y639590D02*
X118860Y639673D01*
X118360Y640007D01*
X118027Y640590D01*
X117860Y641257D01*
X118027Y641923D01*
X118360Y642507D01*
X118860Y642840D01*
X119360Y642923D01*
X119860Y642840D01*
X120360Y642507D01*
X120693Y641923D01*
X120777Y641257D01*
X120693Y640590D01*
X120360Y640007D01*
X119860Y639673D01*
X119360Y639590D01*
G01X123543D02*
Y642923D01*
G01Y642090D02*
X123877Y642507D01*
X124377Y642840D01*
X125043Y642923D01*
X125627Y642840D01*
X126127Y642507D01*
X126377Y641923D01*
Y639590D01*
G01X129477Y641257D02*
X131643D01*
G01X135660Y639590D02*
Y643840D01*
X135827Y644257D01*
X136160Y644507D01*
X136660Y644590D01*
X137160Y644423D01*
X137410Y644007D01*
G01X136410Y642590D02*
X134743D01*
G01X140343Y642923D02*
Y640590D01*
X140677Y640007D01*
X141177Y639673D01*
X141760Y639590D01*
X142343Y639673D01*
X142843Y640007D01*
X143177Y640590D01*
G01Y639590D02*
Y642923D01*
G01X145943Y639590D02*
Y642923D01*
G01Y642090D02*
X146277Y642507D01*
X146777Y642840D01*
X147443Y642923D01*
X148027Y642840D01*
X148527Y642507D01*
X148777Y641923D01*
Y639590D01*
G01X154293Y642507D02*
X153710Y642840D01*
X153210Y642923D01*
X152543Y642757D01*
X152043Y642423D01*
X151710Y641840D01*
X151627Y641257D01*
X151710Y640673D01*
X152043Y640173D01*
X152543Y639757D01*
X153210Y639590D01*
X153793Y639757D01*
X154293Y640090D01*
G01X158560Y644590D02*
Y639590D01*
G01X157393Y642923D02*
X159727D01*
G01X164160D02*
Y639590D01*
G01Y644257D02*
X163993Y644340D01*
Y644507D01*
X164160Y644590D01*
X164327Y644507D01*
Y644340D01*
X164160Y644257D01*
G01X169760Y639590D02*
X169260Y639673D01*
X168760Y640007D01*
X168427Y640590D01*
X168260Y641257D01*
X168427Y641923D01*
X168760Y642507D01*
X169260Y642840D01*
X169760Y642923D01*
X170260Y642840D01*
X170760Y642507D01*
X171093Y641923D01*
X171177Y641257D01*
X171093Y640590D01*
X170760Y640007D01*
X170260Y639673D01*
X169760Y639590D01*
G01X173943D02*
Y642923D01*
G01Y642090D02*
X174277Y642507D01*
X174777Y642840D01*
X175443Y642923D01*
X176027Y642840D01*
X176527Y642507D01*
X176777Y641923D01*
Y639590D01*
G01X182460D02*
Y642923D01*
G01Y642340D02*
X182127Y642673D01*
X181627Y642840D01*
X181043Y642923D01*
X180460Y642757D01*
X179960Y642423D01*
X179627Y641923D01*
X179460Y641257D01*
X179627Y640590D01*
X179960Y640090D01*
X180460Y639757D01*
X181043Y639590D01*
X181627Y639673D01*
X182127Y639923D01*
X182460Y640257D01*
G01X186560Y639590D02*
Y644590D01*
G01X196260Y637923D02*
Y642923D01*
G01Y642173D02*
X196677Y642590D01*
X197093Y642840D01*
X197760Y642923D01*
X198343Y642840D01*
X198927Y642423D01*
X199177Y641840D01*
X199260Y641257D01*
X199177Y640673D01*
X198927Y640090D01*
X198427Y639757D01*
X197760Y639590D01*
X197177Y639673D01*
X196593Y639923D01*
X196260Y640257D01*
G01X204860Y639590D02*
Y642923D01*
G01Y642340D02*
X204527Y642673D01*
X204027Y642840D01*
X203443Y642923D01*
X202860Y642757D01*
X202360Y642423D01*
X202027Y641923D01*
X201860Y641257D01*
X202027Y640590D01*
X202360Y640090D01*
X202860Y639757D01*
X203443Y639590D01*
X204027Y639673D01*
X204527Y639923D01*
X204860Y640257D01*
G01X210460Y644590D02*
Y639590D01*
G01Y640340D02*
X210127Y639923D01*
X209627Y639673D01*
X209043Y639590D01*
X208377Y639757D01*
X207877Y640173D01*
X207543Y640673D01*
X207460Y641257D01*
X207543Y641840D01*
X207877Y642340D01*
X208377Y642757D01*
X209043Y642923D01*
X209627Y642840D01*
X210043Y642673D01*
X210460Y642340D01*
G01X103500Y614000D02*
X694500D01*
G01X103500Y629000D02*
X694500D01*
G01X67000Y725433D02*
X66833Y725517D01*
Y725683D01*
X67000Y725767D01*
X67167Y725683D01*
Y725517D01*
X67000Y725433D01*
G01Y734433D02*
X66833Y734517D01*
Y734683D01*
X67000Y734767D01*
X67167Y734683D01*
Y734517D01*
X67000Y734433D01*
G01Y743433D02*
X66833Y743517D01*
Y743683D01*
X67000Y743767D01*
X67167Y743683D01*
Y743517D01*
X67000Y743433D01*
G01Y752433D02*
X66833Y752517D01*
Y752683D01*
X67000Y752767D01*
X67167Y752683D01*
Y752517D01*
X67000Y752433D01*
G01Y761433D02*
X66833Y761517D01*
Y761683D01*
X67000Y761767D01*
X67167Y761683D01*
Y761517D01*
X67000Y761433D01*
G01Y770433D02*
X66833Y770517D01*
Y770683D01*
X67000Y770767D01*
X67167Y770683D01*
Y770517D01*
X67000Y770433D01*
G01X71000Y729600D02*
X73000D01*
G01X72000D02*
Y724600D01*
G01X71000D02*
X73000D01*
G01X75933D02*
Y729600D01*
X77933D01*
X78600Y729350D01*
X79100Y728767D01*
X79267Y728100D01*
X79100Y727433D01*
X78683Y726933D01*
X77933Y726683D01*
X75933D01*
G01X85033Y729183D02*
X84533Y729433D01*
X83950Y729600D01*
X83283D01*
X82533Y729350D01*
X81950Y728933D01*
X81533Y728433D01*
X81200Y727600D01*
X81117Y726850D01*
X81283Y726100D01*
X81533Y725600D01*
X82033Y725100D01*
X82617Y724767D01*
X83200Y724600D01*
X83783D01*
X84367Y724767D01*
X84867Y725017D01*
X85283Y725350D01*
G01X87717Y726267D02*
X89883D01*
G01X92733Y729600D02*
Y724600D01*
X96067D01*
G01X98917Y726267D02*
X101083D01*
G01X105600Y724600D02*
Y729600D01*
X104600Y728600D01*
G01Y724600D02*
X106600D01*
G01X111200Y729600D02*
X110533Y729433D01*
X110033Y729017D01*
X109700Y728517D01*
X109450Y727850D01*
X109367Y727100D01*
X109450Y726350D01*
X109700Y725683D01*
X110033Y725183D01*
X110533Y724767D01*
X111200Y724600D01*
X111867Y724767D01*
X112367Y725183D01*
X112700Y725683D01*
X112950Y726350D01*
X113033Y727100D01*
X112950Y727850D01*
X112700Y728517D01*
X112367Y729017D01*
X111867Y729433D01*
X111200Y729600D01*
G01X115383Y725183D02*
X115967Y724767D01*
X116633Y724600D01*
X117300Y724767D01*
X117883Y725267D01*
X118300Y726017D01*
X118467Y726767D01*
Y727683D01*
X118300Y728433D01*
X117883Y729100D01*
X117383Y729433D01*
X116800Y729600D01*
X116133Y729433D01*
X115633Y729100D01*
X115300Y728600D01*
X115133Y727933D01*
X115300Y727350D01*
X115717Y726767D01*
X116217Y726433D01*
X116800Y726350D01*
X117467Y726517D01*
X117967Y726933D01*
X118467Y727683D01*
G01X126250Y725267D02*
X126917Y724850D01*
X127667Y724600D01*
X128333D01*
X129000Y724850D01*
X129500Y725267D01*
X129750Y725850D01*
X129583Y726433D01*
X129167Y726933D01*
X128417Y727267D01*
X127417Y727433D01*
X126833Y727767D01*
X126583Y728350D01*
X126750Y728933D01*
X127167Y729350D01*
X127750Y729600D01*
X128333D01*
X128917Y729433D01*
X129417Y729017D01*
G01X132100Y722933D02*
Y727933D01*
G01Y727183D02*
X132517Y727600D01*
X132933Y727850D01*
X133600Y727933D01*
X134183Y727850D01*
X134767Y727433D01*
X135017Y726850D01*
X135100Y726267D01*
X135017Y725683D01*
X134767Y725100D01*
X134267Y724767D01*
X133600Y724600D01*
X133017Y724683D01*
X132433Y724933D01*
X132100Y725267D01*
G01X137950Y726850D02*
X140617D01*
X140367Y727433D01*
X139950Y727767D01*
X139367Y727933D01*
X138783Y727850D01*
X138283Y727600D01*
X137950Y727017D01*
X137783Y726517D01*
Y726017D01*
X137950Y725517D01*
X138367Y725017D01*
X138867Y724683D01*
X139450Y724600D01*
X140033Y724767D01*
X140617Y725267D01*
G01X146133Y727517D02*
X145550Y727850D01*
X145050Y727933D01*
X144383Y727767D01*
X143883Y727433D01*
X143550Y726850D01*
X143467Y726267D01*
X143550Y725683D01*
X143883Y725183D01*
X144383Y724767D01*
X145050Y724600D01*
X145633Y724767D01*
X146133Y725100D01*
G01X150400Y727933D02*
Y724600D01*
G01Y729267D02*
X150233Y729350D01*
Y729517D01*
X150400Y729600D01*
X150567Y729517D01*
Y729350D01*
X150400Y729267D01*
G01X155500Y724600D02*
Y728850D01*
X155667Y729267D01*
X156000Y729517D01*
X156500Y729600D01*
X157000Y729433D01*
X157250Y729017D01*
G01X156250Y727600D02*
X154583D01*
G01X161600Y727933D02*
Y724600D01*
G01Y729267D02*
X161433Y729350D01*
Y729517D01*
X161600Y729600D01*
X161767Y729517D01*
Y729350D01*
X161600Y729267D01*
G01X168533Y727517D02*
X167950Y727850D01*
X167450Y727933D01*
X166783Y727767D01*
X166283Y727433D01*
X165950Y726850D01*
X165867Y726267D01*
X165950Y725683D01*
X166283Y725183D01*
X166783Y724767D01*
X167450Y724600D01*
X168033Y724767D01*
X168533Y725100D01*
G01X174300Y724600D02*
Y727933D01*
G01Y727350D02*
X173967Y727683D01*
X173467Y727850D01*
X172883Y727933D01*
X172300Y727767D01*
X171800Y727433D01*
X171467Y726933D01*
X171300Y726267D01*
X171467Y725600D01*
X171800Y725100D01*
X172300Y724767D01*
X172883Y724600D01*
X173467Y724683D01*
X173967Y724933D01*
X174300Y725267D01*
G01X178400Y729600D02*
Y724600D01*
G01X177233Y727933D02*
X179567D01*
G01X184000D02*
Y724600D01*
G01Y729267D02*
X183833Y729350D01*
Y729517D01*
X184000Y729600D01*
X184167Y729517D01*
Y729350D01*
X184000Y729267D01*
G01X189600Y724600D02*
X189100Y724683D01*
X188600Y725017D01*
X188267Y725600D01*
X188100Y726267D01*
X188267Y726933D01*
X188600Y727517D01*
X189100Y727850D01*
X189600Y727933D01*
X190100Y727850D01*
X190600Y727517D01*
X190933Y726933D01*
X191017Y726267D01*
X190933Y725600D01*
X190600Y725017D01*
X190100Y724683D01*
X189600Y724600D01*
G01X193783D02*
Y727933D01*
G01Y727100D02*
X194117Y727517D01*
X194617Y727850D01*
X195283Y727933D01*
X195867Y727850D01*
X196367Y727517D01*
X196617Y726933D01*
Y724600D01*
G01X205900D02*
Y728850D01*
X206067Y729267D01*
X206400Y729517D01*
X206900Y729600D01*
X207400Y729433D01*
X207650Y729017D01*
G01X206650Y727600D02*
X204983D01*
G01X212000Y724600D02*
X211500Y724683D01*
X211000Y725017D01*
X210667Y725600D01*
X210500Y726267D01*
X210667Y726933D01*
X211000Y727517D01*
X211500Y727850D01*
X212000Y727933D01*
X212500Y727850D01*
X213000Y727517D01*
X213333Y726933D01*
X213417Y726267D01*
X213333Y725600D01*
X213000Y725017D01*
X212500Y724683D01*
X212000Y724600D01*
G01X216433D02*
Y727933D01*
G01Y727267D02*
X216850Y727600D01*
X217267Y727850D01*
X217850Y727933D01*
X218267Y727850D01*
X218767Y727600D01*
G01X227133Y724600D02*
Y729600D01*
X229217D01*
X229883Y729350D01*
X230300Y729017D01*
X230467Y728350D01*
X230300Y727683D01*
X229800Y727267D01*
X229217Y727017D01*
X227133D01*
G01X229217D02*
X230467Y724600D01*
G01X233150Y726850D02*
X235817D01*
X235567Y727433D01*
X235150Y727767D01*
X234567Y727933D01*
X233983Y727850D01*
X233483Y727600D01*
X233150Y727017D01*
X232983Y726517D01*
Y726017D01*
X233150Y725517D01*
X233567Y725017D01*
X234067Y724683D01*
X234650Y724600D01*
X235233Y724767D01*
X235817Y725267D01*
G01X238750Y725183D02*
X239167Y724850D01*
X239750Y724600D01*
X240250D01*
X240750Y724767D01*
X241083Y725017D01*
X241250Y725350D01*
X241167Y725850D01*
X240833Y726100D01*
X239333Y726600D01*
X239000Y727183D01*
X239167Y727600D01*
X239500Y727850D01*
X240000Y727933D01*
X240500Y727850D01*
X241000Y727600D01*
G01X245600Y727933D02*
Y724600D01*
G01Y729267D02*
X245433Y729350D01*
Y729517D01*
X245600Y729600D01*
X245767Y729517D01*
Y729350D01*
X245600Y729267D01*
G01X249783Y724600D02*
Y727933D01*
G01Y727100D02*
X250117Y727517D01*
X250617Y727850D01*
X251283Y727933D01*
X251867Y727850D01*
X252367Y727517D01*
X252617Y726933D01*
Y724600D01*
G01X261400Y729600D02*
X263400D01*
G01X262400D02*
Y724600D01*
G01X261400D02*
X263400D01*
G01X265500D02*
Y727933D01*
G01Y727017D02*
X265750Y727433D01*
X266167Y727767D01*
X266750Y727933D01*
X267333Y727767D01*
X267750Y727433D01*
X268000Y727017D01*
Y724600D01*
G01Y727017D02*
X268250Y727433D01*
X268667Y727767D01*
X269250Y727933D01*
X269833Y727767D01*
X270250Y727433D01*
X270500Y726933D01*
Y724600D01*
G01X272100Y722933D02*
Y727933D01*
G01Y727183D02*
X272517Y727600D01*
X272933Y727850D01*
X273600Y727933D01*
X274183Y727850D01*
X274767Y727433D01*
X275017Y726850D01*
X275100Y726267D01*
X275017Y725683D01*
X274767Y725100D01*
X274267Y724767D01*
X273600Y724600D01*
X273017Y724683D01*
X272433Y724933D01*
X272100Y725267D01*
G01X278033Y724600D02*
Y727933D01*
G01Y727267D02*
X278450Y727600D01*
X278867Y727850D01*
X279450Y727933D01*
X279867Y727850D01*
X280367Y727600D01*
G01X283550Y726850D02*
X286217D01*
X285967Y727433D01*
X285550Y727767D01*
X284967Y727933D01*
X284383Y727850D01*
X283883Y727600D01*
X283550Y727017D01*
X283383Y726517D01*
Y726017D01*
X283550Y725517D01*
X283967Y725017D01*
X284467Y724683D01*
X285050Y724600D01*
X285633Y724767D01*
X286217Y725267D01*
G01X289233Y723350D02*
X289817Y723017D01*
X290483Y722933D01*
X291067Y723017D01*
X291567Y723433D01*
X291900Y724017D01*
Y727933D01*
G01Y727267D02*
X291567Y727600D01*
X291067Y727850D01*
X290483Y727933D01*
X289817Y727767D01*
X289400Y727433D01*
X289067Y726850D01*
X288900Y726267D01*
X288983Y725767D01*
X289317Y725183D01*
X289817Y724767D01*
X290483Y724600D01*
X290983Y724683D01*
X291567Y725017D01*
X291900Y725350D01*
G01X294583Y724600D02*
Y727933D01*
G01Y727100D02*
X294917Y727517D01*
X295417Y727850D01*
X296083Y727933D01*
X296667Y727850D01*
X297167Y727517D01*
X297417Y726933D01*
Y724600D01*
G01X303100D02*
Y727933D01*
G01Y727350D02*
X302767Y727683D01*
X302267Y727850D01*
X301683Y727933D01*
X301100Y727767D01*
X300600Y727433D01*
X300267Y726933D01*
X300100Y726267D01*
X300267Y725600D01*
X300600Y725100D01*
X301100Y724767D01*
X301683Y724600D01*
X302267Y724683D01*
X302767Y724933D01*
X303100Y725267D01*
G01X307200Y729600D02*
Y724600D01*
G01X306033Y727933D02*
X308367D01*
G01X311550Y726850D02*
X314217D01*
X313967Y727433D01*
X313550Y727767D01*
X312967Y727933D01*
X312383Y727850D01*
X311883Y727600D01*
X311550Y727017D01*
X311383Y726517D01*
Y726017D01*
X311550Y725517D01*
X311967Y725017D01*
X312467Y724683D01*
X313050Y724600D01*
X313633Y724767D01*
X314217Y725267D01*
G01X319900Y729600D02*
Y724600D01*
G01Y725350D02*
X319567Y724933D01*
X319067Y724683D01*
X318483Y724600D01*
X317817Y724767D01*
X317317Y725183D01*
X316983Y725683D01*
X316900Y726267D01*
X316983Y726850D01*
X317317Y727350D01*
X317817Y727767D01*
X318483Y727933D01*
X319067Y727850D01*
X319483Y727683D01*
X319900Y727350D01*
G01X328017Y724600D02*
Y729600D01*
X331183D01*
G01X330017Y727183D02*
X328017D01*
G01X336700Y724600D02*
Y727933D01*
G01Y727350D02*
X336367Y727683D01*
X335867Y727850D01*
X335283Y727933D01*
X334700Y727767D01*
X334200Y727433D01*
X333867Y726933D01*
X333700Y726267D01*
X333867Y725600D01*
X334200Y725100D01*
X334700Y724767D01*
X335283Y724600D01*
X335867Y724683D01*
X336367Y724933D01*
X336700Y725267D01*
G01X339300Y724600D02*
Y729600D01*
G01Y727100D02*
X339717Y727600D01*
X340217Y727850D01*
X340717Y727933D01*
X341467Y727767D01*
X341967Y727433D01*
X342300Y726850D01*
Y726183D01*
X342133Y725517D01*
X341800Y725017D01*
X341217Y724683D01*
X340717Y724600D01*
X340217Y724683D01*
X339717Y724933D01*
X339300Y725350D01*
G01X345233Y724600D02*
Y727933D01*
G01Y727267D02*
X345650Y727600D01*
X346067Y727850D01*
X346650Y727933D01*
X347067Y727850D01*
X347567Y727600D01*
G01X352000Y727933D02*
Y724600D01*
G01Y729267D02*
X351833Y729350D01*
Y729517D01*
X352000Y729600D01*
X352167Y729517D01*
Y729350D01*
X352000Y729267D01*
G01X358933Y727517D02*
X358350Y727850D01*
X357850Y727933D01*
X357183Y727767D01*
X356683Y727433D01*
X356350Y726850D01*
X356267Y726267D01*
X356350Y725683D01*
X356683Y725183D01*
X357183Y724767D01*
X357850Y724600D01*
X358433Y724767D01*
X358933Y725100D01*
G01X362783Y722933D02*
X361950Y723767D01*
X361533Y724600D01*
Y727933D01*
X361950Y728767D01*
X362783Y729600D01*
G01X367133Y724600D02*
Y729600D01*
X369133D01*
X369800Y729350D01*
X370300Y728767D01*
X370467Y728100D01*
X370300Y727433D01*
X369883Y726933D01*
X369133Y726683D01*
X367133D01*
G01X373233Y724600D02*
Y727933D01*
G01Y727267D02*
X373650Y727600D01*
X374067Y727850D01*
X374650Y727933D01*
X375067Y727850D01*
X375567Y727600D01*
G01X378750Y726850D02*
X381417D01*
X381167Y727433D01*
X380750Y727767D01*
X380167Y727933D01*
X379583Y727850D01*
X379083Y727600D01*
X378750Y727017D01*
X378583Y726517D01*
Y726017D01*
X378750Y725517D01*
X379167Y725017D01*
X379667Y724683D01*
X380250Y724600D01*
X380833Y724767D01*
X381417Y725267D01*
G01X384100Y722933D02*
Y727933D01*
G01Y727183D02*
X384517Y727600D01*
X384933Y727850D01*
X385600Y727933D01*
X386183Y727850D01*
X386767Y727433D01*
X387017Y726850D01*
X387100Y726267D01*
X387017Y725683D01*
X386767Y725100D01*
X386267Y724767D01*
X385600Y724600D01*
X385017Y724683D01*
X384433Y724933D01*
X384100Y725267D01*
G01X390033Y724600D02*
Y727933D01*
G01Y727267D02*
X390450Y727600D01*
X390867Y727850D01*
X391450Y727933D01*
X391867Y727850D01*
X392367Y727600D01*
G01X395550Y726850D02*
X398217D01*
X397967Y727433D01*
X397550Y727767D01*
X396967Y727933D01*
X396383Y727850D01*
X395883Y727600D01*
X395550Y727017D01*
X395383Y726517D01*
Y726017D01*
X395550Y725517D01*
X395967Y725017D01*
X396467Y724683D01*
X397050Y724600D01*
X397633Y724767D01*
X398217Y725267D01*
G01X401233Y723350D02*
X401817Y723017D01*
X402483Y722933D01*
X403067Y723017D01*
X403567Y723433D01*
X403900Y724017D01*
Y727933D01*
G01Y727267D02*
X403567Y727600D01*
X403067Y727850D01*
X402483Y727933D01*
X401817Y727767D01*
X401400Y727433D01*
X401067Y726850D01*
X400900Y726267D01*
X400983Y725767D01*
X401317Y725183D01*
X401817Y724767D01*
X402483Y724600D01*
X402983Y724683D01*
X403567Y725017D01*
X403900Y725350D01*
G01X408417Y722933D02*
X409250Y723767D01*
X409667Y724600D01*
Y727933D01*
X409250Y728767D01*
X408417Y729600D01*
G01X418700Y724600D02*
Y728850D01*
X418867Y729267D01*
X419200Y729517D01*
X419700Y729600D01*
X420200Y729433D01*
X420450Y729017D01*
G01X419450Y727600D02*
X417783D01*
G01X424800Y724600D02*
X424300Y724683D01*
X423800Y725017D01*
X423467Y725600D01*
X423300Y726267D01*
X423467Y726933D01*
X423800Y727517D01*
X424300Y727850D01*
X424800Y727933D01*
X425300Y727850D01*
X425800Y727517D01*
X426133Y726933D01*
X426217Y726267D01*
X426133Y725600D01*
X425800Y725017D01*
X425300Y724683D01*
X424800Y724600D01*
G01X429233D02*
Y727933D01*
G01Y727267D02*
X429650Y727600D01*
X430067Y727850D01*
X430650Y727933D01*
X431067Y727850D01*
X431567Y727600D01*
G01X439433Y724600D02*
Y729600D01*
X441600Y725433D01*
X443767Y729600D01*
Y724600D01*
G01X445783Y727933D02*
Y725600D01*
X446117Y725017D01*
X446617Y724683D01*
X447200Y724600D01*
X447783Y724683D01*
X448283Y725017D01*
X448617Y725600D01*
G01Y724600D02*
Y727933D01*
G01X452800Y724600D02*
Y729600D01*
G01X458400D02*
Y724600D01*
G01X457233Y727933D02*
X459567D01*
G01X464000D02*
Y724600D01*
G01Y729267D02*
X463833Y729350D01*
Y729517D01*
X464000Y729600D01*
X464167Y729517D01*
Y729350D01*
X464000Y729267D01*
G01X469600Y724600D02*
Y729600D01*
G01X476700Y724600D02*
Y727933D01*
G01Y727350D02*
X476367Y727683D01*
X475867Y727850D01*
X475283Y727933D01*
X474700Y727767D01*
X474200Y727433D01*
X473867Y726933D01*
X473700Y726267D01*
X473867Y725600D01*
X474200Y725100D01*
X474700Y724767D01*
X475283Y724600D01*
X475867Y724683D01*
X476367Y724933D01*
X476700Y725267D01*
G01X479050Y723100D02*
X479550Y722933D01*
X480217Y723100D01*
X480633Y723433D01*
X480967Y723850D01*
X481467Y725183D01*
X482550Y727933D01*
G01X479883D02*
X481467Y725183D01*
G01X485150Y726850D02*
X487817D01*
X487567Y727433D01*
X487150Y727767D01*
X486567Y727933D01*
X485983Y727850D01*
X485483Y727600D01*
X485150Y727017D01*
X484983Y726517D01*
Y726017D01*
X485150Y725517D01*
X485567Y725017D01*
X486067Y724683D01*
X486650Y724600D01*
X487233Y724767D01*
X487817Y725267D01*
G01X490833Y724600D02*
Y727933D01*
G01Y727267D02*
X491250Y727600D01*
X491667Y727850D01*
X492250Y727933D01*
X492667Y727850D01*
X493167Y727600D01*
G01X501533Y724600D02*
Y729600D01*
X503533D01*
X504200Y729350D01*
X504700Y728767D01*
X504867Y728100D01*
X504700Y727433D01*
X504283Y726933D01*
X503533Y726683D01*
X501533D01*
G01X507633Y724600D02*
Y727933D01*
G01Y727267D02*
X508050Y727600D01*
X508467Y727850D01*
X509050Y727933D01*
X509467Y727850D01*
X509967Y727600D01*
G01X514400Y727933D02*
Y724600D01*
G01Y729267D02*
X514233Y729350D01*
Y729517D01*
X514400Y729600D01*
X514567Y729517D01*
Y729350D01*
X514400Y729267D01*
G01X518583Y724600D02*
Y727933D01*
G01Y727100D02*
X518917Y727517D01*
X519417Y727850D01*
X520083Y727933D01*
X520667Y727850D01*
X521167Y727517D01*
X521417Y726933D01*
Y724600D01*
G01X525600Y729600D02*
Y724600D01*
G01X524433Y727933D02*
X526767D01*
G01X529950Y726850D02*
X532617D01*
X532367Y727433D01*
X531950Y727767D01*
X531367Y727933D01*
X530783Y727850D01*
X530283Y727600D01*
X529950Y727017D01*
X529783Y726517D01*
Y726017D01*
X529950Y725517D01*
X530367Y725017D01*
X530867Y724683D01*
X531450Y724600D01*
X532033Y724767D01*
X532617Y725267D01*
G01X538300Y729600D02*
Y724600D01*
G01Y725350D02*
X537967Y724933D01*
X537467Y724683D01*
X536883Y724600D01*
X536217Y724767D01*
X535717Y725183D01*
X535383Y725683D01*
X535300Y726267D01*
X535383Y726850D01*
X535717Y727350D01*
X536217Y727767D01*
X536883Y727933D01*
X537467Y727850D01*
X537883Y727683D01*
X538300Y727350D01*
G01X548667Y727267D02*
X549000Y727517D01*
X549250Y727933D01*
X549417Y728517D01*
X549250Y729017D01*
X548917Y729350D01*
X548333Y729600D01*
X546083D01*
Y724600D01*
X548833D01*
X549417Y724933D01*
X549750Y725433D01*
X549917Y726017D01*
X549750Y726600D01*
X549250Y727100D01*
X548667Y727267D01*
X546083D01*
G01X553600Y724600D02*
X553100Y724683D01*
X552600Y725017D01*
X552267Y725600D01*
X552100Y726267D01*
X552267Y726933D01*
X552600Y727517D01*
X553100Y727850D01*
X553600Y727933D01*
X554100Y727850D01*
X554600Y727517D01*
X554933Y726933D01*
X555017Y726267D01*
X554933Y725600D01*
X554600Y725017D01*
X554100Y724683D01*
X553600Y724600D01*
G01X560700D02*
Y727933D01*
G01Y727350D02*
X560367Y727683D01*
X559867Y727850D01*
X559283Y727933D01*
X558700Y727767D01*
X558200Y727433D01*
X557867Y726933D01*
X557700Y726267D01*
X557867Y725600D01*
X558200Y725100D01*
X558700Y724767D01*
X559283Y724600D01*
X559867Y724683D01*
X560367Y724933D01*
X560700Y725267D01*
G01X563633Y724600D02*
Y727933D01*
G01Y727267D02*
X564050Y727600D01*
X564467Y727850D01*
X565050Y727933D01*
X565467Y727850D01*
X565967Y727600D01*
G01X571900Y729600D02*
Y724600D01*
G01Y725350D02*
X571567Y724933D01*
X571067Y724683D01*
X570483Y724600D01*
X569817Y724767D01*
X569317Y725183D01*
X568983Y725683D01*
X568900Y726267D01*
X568983Y726850D01*
X569317Y727350D01*
X569817Y727767D01*
X570483Y727933D01*
X571067Y727850D01*
X571483Y727683D01*
X571900Y727350D01*
G01X574750Y725183D02*
X575167Y724850D01*
X575750Y724600D01*
X576250D01*
X576750Y724767D01*
X577083Y725017D01*
X577250Y725350D01*
X577167Y725850D01*
X576833Y726100D01*
X575333Y726600D01*
X575000Y727183D01*
X575167Y727600D01*
X575500Y727850D01*
X576000Y727933D01*
X576500Y727850D01*
X577000Y727600D01*
G01X71000Y738600D02*
X73000D01*
G01X72000D02*
Y733600D01*
G01X71000D02*
X73000D01*
G01X75933D02*
Y738600D01*
X77933D01*
X78600Y738350D01*
X79100Y737767D01*
X79267Y737100D01*
X79100Y736433D01*
X78683Y735933D01*
X77933Y735683D01*
X75933D01*
G01X85033Y738183D02*
X84533Y738433D01*
X83950Y738600D01*
X83283D01*
X82533Y738350D01*
X81950Y737933D01*
X81533Y737433D01*
X81200Y736600D01*
X81117Y735850D01*
X81283Y735100D01*
X81533Y734600D01*
X82033Y734100D01*
X82617Y733767D01*
X83200Y733600D01*
X83783D01*
X84367Y733767D01*
X84867Y734017D01*
X85283Y734350D01*
G01X87717Y735267D02*
X89883D01*
G01X92233Y733600D02*
Y738600D01*
X94400Y734433D01*
X96567Y738600D01*
Y733600D01*
G01X98417D02*
Y738600D01*
X101583D01*
G01X100417Y736183D02*
X98417D01*
G01X104517Y735267D02*
X106683D01*
G01X111200Y733600D02*
Y738600D01*
X110200Y737600D01*
G01Y733600D02*
X112200D01*
G01X114967Y734350D02*
X115467Y733933D01*
X116050Y733683D01*
X116800Y733600D01*
X117550Y733767D01*
X118133Y734100D01*
X118550Y734683D01*
X118633Y735350D01*
X118467Y736017D01*
X118050Y736433D01*
X117467Y736767D01*
X116883Y736850D01*
X116300Y736767D01*
X115550Y736433D01*
X115800Y738600D01*
X118050D01*
G01X122400D02*
X121733Y738433D01*
X121233Y738017D01*
X120900Y737517D01*
X120650Y736850D01*
X120567Y736100D01*
X120650Y735350D01*
X120900Y734683D01*
X121233Y734183D01*
X121733Y733767D01*
X122400Y733600D01*
X123067Y733767D01*
X123567Y734183D01*
X123900Y734683D01*
X124150Y735350D01*
X124233Y736100D01*
X124150Y736850D01*
X123900Y737517D01*
X123567Y738017D01*
X123067Y738433D01*
X122400Y738600D01*
G01X131433Y733600D02*
Y738600D01*
X133600Y734433D01*
X135767Y738600D01*
Y733600D01*
G01X137950Y735850D02*
X140617D01*
X140367Y736433D01*
X139950Y736767D01*
X139367Y736933D01*
X138783Y736850D01*
X138283Y736600D01*
X137950Y736017D01*
X137783Y735517D01*
Y735017D01*
X137950Y734517D01*
X138367Y734017D01*
X138867Y733683D01*
X139450Y733600D01*
X140033Y733767D01*
X140617Y734267D01*
G01X144800Y738600D02*
Y733600D01*
G01X143633Y736933D02*
X145967D01*
G01X151900Y733600D02*
Y736933D01*
G01Y736350D02*
X151567Y736683D01*
X151067Y736850D01*
X150483Y736933D01*
X149900Y736767D01*
X149400Y736433D01*
X149067Y735933D01*
X148900Y735267D01*
X149067Y734600D01*
X149400Y734100D01*
X149900Y733767D01*
X150483Y733600D01*
X151067Y733683D01*
X151567Y733933D01*
X151900Y734267D01*
G01X156000Y733600D02*
Y738600D01*
G01X165617Y733600D02*
Y738600D01*
X168783D01*
G01X167617Y736183D02*
X165617D01*
G01X172800Y733600D02*
X172300Y733683D01*
X171800Y734017D01*
X171467Y734600D01*
X171300Y735267D01*
X171467Y735933D01*
X171800Y736517D01*
X172300Y736850D01*
X172800Y736933D01*
X173300Y736850D01*
X173800Y736517D01*
X174133Y735933D01*
X174217Y735267D01*
X174133Y734600D01*
X173800Y734017D01*
X173300Y733683D01*
X172800Y733600D01*
G01X178400Y736933D02*
Y733600D01*
G01Y738267D02*
X178233Y738350D01*
Y738517D01*
X178400Y738600D01*
X178567Y738517D01*
Y738350D01*
X178400Y738267D01*
G01X184000Y733600D02*
Y738600D01*
G01X194700Y733600D02*
Y737850D01*
X194867Y738267D01*
X195200Y738517D01*
X195700Y738600D01*
X196200Y738433D01*
X196450Y738017D01*
G01X195450Y736600D02*
X193783D01*
G01X200800Y733600D02*
X200300Y733683D01*
X199800Y734017D01*
X199467Y734600D01*
X199300Y735267D01*
X199467Y735933D01*
X199800Y736517D01*
X200300Y736850D01*
X200800Y736933D01*
X201300Y736850D01*
X201800Y736517D01*
X202133Y735933D01*
X202217Y735267D01*
X202133Y734600D01*
X201800Y734017D01*
X201300Y733683D01*
X200800Y733600D01*
G01X205233D02*
Y736933D01*
G01Y736267D02*
X205650Y736600D01*
X206067Y736850D01*
X206650Y736933D01*
X207067Y736850D01*
X207567Y736600D01*
G01X215933Y733600D02*
Y738600D01*
X217933D01*
X218600Y738350D01*
X219100Y737767D01*
X219267Y737100D01*
X219100Y736433D01*
X218683Y735933D01*
X217933Y735683D01*
X215933D01*
G01X222033Y733600D02*
Y736933D01*
G01Y736267D02*
X222450Y736600D01*
X222867Y736850D01*
X223450Y736933D01*
X223867Y736850D01*
X224367Y736600D01*
G01X228800Y736933D02*
Y733600D01*
G01Y738267D02*
X228633Y738350D01*
Y738517D01*
X228800Y738600D01*
X228967Y738517D01*
Y738350D01*
X228800Y738267D01*
G01X232983Y733600D02*
Y736933D01*
G01Y736100D02*
X233317Y736517D01*
X233817Y736850D01*
X234483Y736933D01*
X235067Y736850D01*
X235567Y736517D01*
X235817Y735933D01*
Y733600D01*
G01X240000Y738600D02*
Y733600D01*
G01X238833Y736933D02*
X241167D01*
G01X244350Y735850D02*
X247017D01*
X246767Y736433D01*
X246350Y736767D01*
X245767Y736933D01*
X245183Y736850D01*
X244683Y736600D01*
X244350Y736017D01*
X244183Y735517D01*
Y735017D01*
X244350Y734517D01*
X244767Y734017D01*
X245267Y733683D01*
X245850Y733600D01*
X246433Y733767D01*
X247017Y734267D01*
G01X252700Y738600D02*
Y733600D01*
G01Y734350D02*
X252367Y733933D01*
X251867Y733683D01*
X251283Y733600D01*
X250617Y733767D01*
X250117Y734183D01*
X249783Y734683D01*
X249700Y735267D01*
X249783Y735850D01*
X250117Y736350D01*
X250617Y736767D01*
X251283Y736933D01*
X251867Y736850D01*
X252283Y736683D01*
X252700Y736350D01*
G01X259900Y738600D02*
X261067Y733600D01*
X262400Y738600D01*
X263733Y733600D01*
X264900Y738600D01*
G01X268000Y736933D02*
Y733600D01*
G01Y738267D02*
X267833Y738350D01*
Y738517D01*
X268000Y738600D01*
X268167Y738517D01*
Y738350D01*
X268000Y738267D01*
G01X272433Y733600D02*
Y736933D01*
G01Y736267D02*
X272850Y736600D01*
X273267Y736850D01*
X273850Y736933D01*
X274267Y736850D01*
X274767Y736600D01*
G01X279200Y736933D02*
Y733600D01*
G01Y738267D02*
X279033Y738350D01*
Y738517D01*
X279200Y738600D01*
X279367Y738517D01*
Y738350D01*
X279200Y738267D01*
G01X283383Y733600D02*
Y736933D01*
G01Y736100D02*
X283717Y736517D01*
X284217Y736850D01*
X284883Y736933D01*
X285467Y736850D01*
X285967Y736517D01*
X286217Y735933D01*
Y733600D01*
G01X289233Y732350D02*
X289817Y732017D01*
X290483Y731933D01*
X291067Y732017D01*
X291567Y732433D01*
X291900Y733017D01*
Y736933D01*
G01Y736267D02*
X291567Y736600D01*
X291067Y736850D01*
X290483Y736933D01*
X289817Y736767D01*
X289400Y736433D01*
X289067Y735850D01*
X288900Y735267D01*
X288983Y734767D01*
X289317Y734183D01*
X289817Y733767D01*
X290483Y733600D01*
X290983Y733683D01*
X291567Y734017D01*
X291900Y734350D01*
G01X299517Y733600D02*
X301600Y738600D01*
X303683Y733600D01*
G01X302933Y735350D02*
X300267D01*
G01X305700Y731933D02*
Y736933D01*
G01Y736183D02*
X306117Y736600D01*
X306533Y736850D01*
X307200Y736933D01*
X307783Y736850D01*
X308367Y736433D01*
X308617Y735850D01*
X308700Y735267D01*
X308617Y734683D01*
X308367Y734100D01*
X307867Y733767D01*
X307200Y733600D01*
X306617Y733683D01*
X306033Y733933D01*
X305700Y734267D01*
G01X311300Y731933D02*
Y736933D01*
G01Y736183D02*
X311717Y736600D01*
X312133Y736850D01*
X312800Y736933D01*
X313383Y736850D01*
X313967Y736433D01*
X314217Y735850D01*
X314300Y735267D01*
X314217Y734683D01*
X313967Y734100D01*
X313467Y733767D01*
X312800Y733600D01*
X312217Y733683D01*
X311633Y733933D01*
X311300Y734267D01*
G01X318400Y733600D02*
Y738600D01*
G01X324000Y736933D02*
Y733600D01*
G01Y738267D02*
X323833Y738350D01*
Y738517D01*
X324000Y738600D01*
X324167Y738517D01*
Y738350D01*
X324000Y738267D01*
G01X330933Y736517D02*
X330350Y736850D01*
X329850Y736933D01*
X329183Y736767D01*
X328683Y736433D01*
X328350Y735850D01*
X328267Y735267D01*
X328350Y734683D01*
X328683Y734183D01*
X329183Y733767D01*
X329850Y733600D01*
X330433Y733767D01*
X330933Y734100D01*
G01X336700Y733600D02*
Y736933D01*
G01Y736350D02*
X336367Y736683D01*
X335867Y736850D01*
X335283Y736933D01*
X334700Y736767D01*
X334200Y736433D01*
X333867Y735933D01*
X333700Y735267D01*
X333867Y734600D01*
X334200Y734100D01*
X334700Y733767D01*
X335283Y733600D01*
X335867Y733683D01*
X336367Y733933D01*
X336700Y734267D01*
G01X340800Y738600D02*
Y733600D01*
G01X339633Y736933D02*
X341967D01*
G01X346400D02*
Y733600D01*
G01Y738267D02*
X346233Y738350D01*
Y738517D01*
X346400Y738600D01*
X346567Y738517D01*
Y738350D01*
X346400Y738267D01*
G01X352000Y733600D02*
X351500Y733683D01*
X351000Y734017D01*
X350667Y734600D01*
X350500Y735267D01*
X350667Y735933D01*
X351000Y736517D01*
X351500Y736850D01*
X352000Y736933D01*
X352500Y736850D01*
X353000Y736517D01*
X353333Y735933D01*
X353417Y735267D01*
X353333Y734600D01*
X353000Y734017D01*
X352500Y733683D01*
X352000Y733600D01*
G01X356183D02*
Y736933D01*
G01Y736100D02*
X356517Y736517D01*
X357017Y736850D01*
X357683Y736933D01*
X358267Y736850D01*
X358767Y736517D01*
X359017Y735933D01*
Y733600D01*
G01X361950Y734183D02*
X362367Y733850D01*
X362950Y733600D01*
X363450D01*
X363950Y733767D01*
X364283Y734017D01*
X364450Y734350D01*
X364367Y734850D01*
X364033Y735100D01*
X362533Y735600D01*
X362200Y736183D01*
X362367Y736600D01*
X362700Y736850D01*
X363200Y736933D01*
X363700Y736850D01*
X364200Y736600D01*
G01X71000Y747600D02*
X73000D01*
G01X72000D02*
Y742600D01*
G01X71000D02*
X73000D01*
G01X75933D02*
Y747600D01*
X77933D01*
X78600Y747350D01*
X79100Y746767D01*
X79267Y746100D01*
X79100Y745433D01*
X78683Y744933D01*
X77933Y744683D01*
X75933D01*
G01X85033Y747183D02*
X84533Y747433D01*
X83950Y747600D01*
X83283D01*
X82533Y747350D01*
X81950Y746933D01*
X81533Y746433D01*
X81200Y745600D01*
X81117Y744850D01*
X81283Y744100D01*
X81533Y743600D01*
X82033Y743100D01*
X82617Y742767D01*
X83200Y742600D01*
X83783D01*
X84367Y742767D01*
X84867Y743017D01*
X85283Y743350D01*
G01X87717Y744267D02*
X89883D01*
G01X95400Y742600D02*
Y747600D01*
X92317Y744017D01*
X96483D01*
G01X100000Y742600D02*
Y747600D01*
X99000Y746600D01*
G01Y742600D02*
X101000D01*
G01X105600Y747600D02*
X104933Y747433D01*
X104433Y747017D01*
X104100Y746517D01*
X103850Y745850D01*
X103767Y745100D01*
X103850Y744350D01*
X104100Y743683D01*
X104433Y743183D01*
X104933Y742767D01*
X105600Y742600D01*
X106267Y742767D01*
X106767Y743183D01*
X107100Y743683D01*
X107350Y744350D01*
X107433Y745100D01*
X107350Y745850D01*
X107100Y746517D01*
X106767Y747017D01*
X106267Y747433D01*
X105600Y747600D01*
G01X111200Y742600D02*
Y747600D01*
X110200Y746600D01*
G01Y742600D02*
X112200D01*
G01X120650Y743267D02*
X121317Y742850D01*
X122067Y742600D01*
X122733D01*
X123400Y742850D01*
X123900Y743267D01*
X124150Y743850D01*
X123983Y744433D01*
X123567Y744933D01*
X122817Y745267D01*
X121817Y745433D01*
X121233Y745767D01*
X120983Y746350D01*
X121150Y746933D01*
X121567Y747350D01*
X122150Y747600D01*
X122733D01*
X123317Y747433D01*
X123817Y747017D01*
G01X126500Y740933D02*
Y745933D01*
G01Y745183D02*
X126917Y745600D01*
X127333Y745850D01*
X128000Y745933D01*
X128583Y745850D01*
X129167Y745433D01*
X129417Y744850D01*
X129500Y744267D01*
X129417Y743683D01*
X129167Y743100D01*
X128667Y742767D01*
X128000Y742600D01*
X127417Y742683D01*
X126833Y742933D01*
X126500Y743267D01*
G01X132350Y744850D02*
X135017D01*
X134767Y745433D01*
X134350Y745767D01*
X133767Y745933D01*
X133183Y745850D01*
X132683Y745600D01*
X132350Y745017D01*
X132183Y744517D01*
Y744017D01*
X132350Y743517D01*
X132767Y743017D01*
X133267Y742683D01*
X133850Y742600D01*
X134433Y742767D01*
X135017Y743267D01*
G01X140533Y745517D02*
X139950Y745850D01*
X139450Y745933D01*
X138783Y745767D01*
X138283Y745433D01*
X137950Y744850D01*
X137867Y744267D01*
X137950Y743683D01*
X138283Y743183D01*
X138783Y742767D01*
X139450Y742600D01*
X140033Y742767D01*
X140533Y743100D01*
G01X144800Y745933D02*
Y742600D01*
G01Y747267D02*
X144633Y747350D01*
Y747517D01*
X144800Y747600D01*
X144967Y747517D01*
Y747350D01*
X144800Y747267D01*
G01X149900Y742600D02*
Y746850D01*
X150067Y747267D01*
X150400Y747517D01*
X150900Y747600D01*
X151400Y747433D01*
X151650Y747017D01*
G01X150650Y745600D02*
X148983D01*
G01X156000Y745933D02*
Y742600D01*
G01Y747267D02*
X155833Y747350D01*
Y747517D01*
X156000Y747600D01*
X156167Y747517D01*
Y747350D01*
X156000Y747267D01*
G01X162933Y745517D02*
X162350Y745850D01*
X161850Y745933D01*
X161183Y745767D01*
X160683Y745433D01*
X160350Y744850D01*
X160267Y744267D01*
X160350Y743683D01*
X160683Y743183D01*
X161183Y742767D01*
X161850Y742600D01*
X162433Y742767D01*
X162933Y743100D01*
G01X168700Y742600D02*
Y745933D01*
G01Y745350D02*
X168367Y745683D01*
X167867Y745850D01*
X167283Y745933D01*
X166700Y745767D01*
X166200Y745433D01*
X165867Y744933D01*
X165700Y744267D01*
X165867Y743600D01*
X166200Y743100D01*
X166700Y742767D01*
X167283Y742600D01*
X167867Y742683D01*
X168367Y742933D01*
X168700Y743267D01*
G01X172800Y747600D02*
Y742600D01*
G01X171633Y745933D02*
X173967D01*
G01X178400D02*
Y742600D01*
G01Y747267D02*
X178233Y747350D01*
Y747517D01*
X178400Y747600D01*
X178567Y747517D01*
Y747350D01*
X178400Y747267D01*
G01X184000Y742600D02*
X183500Y742683D01*
X183000Y743017D01*
X182667Y743600D01*
X182500Y744267D01*
X182667Y744933D01*
X183000Y745517D01*
X183500Y745850D01*
X184000Y745933D01*
X184500Y745850D01*
X185000Y745517D01*
X185333Y744933D01*
X185417Y744267D01*
X185333Y743600D01*
X185000Y743017D01*
X184500Y742683D01*
X184000Y742600D01*
G01X188183D02*
Y745933D01*
G01Y745100D02*
X188517Y745517D01*
X189017Y745850D01*
X189683Y745933D01*
X190267Y745850D01*
X190767Y745517D01*
X191017Y744933D01*
Y742600D01*
G01X200300D02*
Y746850D01*
X200467Y747267D01*
X200800Y747517D01*
X201300Y747600D01*
X201800Y747433D01*
X202050Y747017D01*
G01X201050Y745600D02*
X199383D01*
G01X206400Y742600D02*
X205900Y742683D01*
X205400Y743017D01*
X205067Y743600D01*
X204900Y744267D01*
X205067Y744933D01*
X205400Y745517D01*
X205900Y745850D01*
X206400Y745933D01*
X206900Y745850D01*
X207400Y745517D01*
X207733Y744933D01*
X207817Y744267D01*
X207733Y743600D01*
X207400Y743017D01*
X206900Y742683D01*
X206400Y742600D01*
G01X210833D02*
Y745933D01*
G01Y745267D02*
X211250Y745600D01*
X211667Y745850D01*
X212250Y745933D01*
X212667Y745850D01*
X213167Y745600D01*
G01X223867Y745267D02*
X224200Y745517D01*
X224450Y745933D01*
X224617Y746517D01*
X224450Y747017D01*
X224117Y747350D01*
X223533Y747600D01*
X221283D01*
Y742600D01*
X224033D01*
X224617Y742933D01*
X224950Y743433D01*
X225117Y744017D01*
X224950Y744600D01*
X224450Y745100D01*
X223867Y745267D01*
X221283D01*
G01X230300Y742600D02*
Y745933D01*
G01Y745350D02*
X229967Y745683D01*
X229467Y745850D01*
X228883Y745933D01*
X228300Y745767D01*
X227800Y745433D01*
X227467Y744933D01*
X227300Y744267D01*
X227467Y743600D01*
X227800Y743100D01*
X228300Y742767D01*
X228883Y742600D01*
X229467Y742683D01*
X229967Y742933D01*
X230300Y743267D01*
G01X233150Y743183D02*
X233567Y742850D01*
X234150Y742600D01*
X234650D01*
X235150Y742767D01*
X235483Y743017D01*
X235650Y743350D01*
X235567Y743850D01*
X235233Y744100D01*
X233733Y744600D01*
X233400Y745183D01*
X233567Y745600D01*
X233900Y745850D01*
X234400Y745933D01*
X234900Y745850D01*
X235400Y745600D01*
G01X238750Y744850D02*
X241417D01*
X241167Y745433D01*
X240750Y745767D01*
X240167Y745933D01*
X239583Y745850D01*
X239083Y745600D01*
X238750Y745017D01*
X238583Y744517D01*
Y744017D01*
X238750Y743517D01*
X239167Y743017D01*
X239667Y742683D01*
X240250Y742600D01*
X240833Y742767D01*
X241417Y743267D01*
G01X249033Y742600D02*
Y747600D01*
X251200Y743433D01*
X253367Y747600D01*
Y742600D01*
G01X258300D02*
Y745933D01*
G01Y745350D02*
X257967Y745683D01*
X257467Y745850D01*
X256883Y745933D01*
X256300Y745767D01*
X255800Y745433D01*
X255467Y744933D01*
X255300Y744267D01*
X255467Y743600D01*
X255800Y743100D01*
X256300Y742767D01*
X256883Y742600D01*
X257467Y742683D01*
X257967Y742933D01*
X258300Y743267D01*
G01X262400Y747600D02*
Y742600D01*
G01X261233Y745933D02*
X263567D01*
G01X266750Y744850D02*
X269417D01*
X269167Y745433D01*
X268750Y745767D01*
X268167Y745933D01*
X267583Y745850D01*
X267083Y745600D01*
X266750Y745017D01*
X266583Y744517D01*
Y744017D01*
X266750Y743517D01*
X267167Y743017D01*
X267667Y742683D01*
X268250Y742600D01*
X268833Y742767D01*
X269417Y743267D01*
G01X272433Y742600D02*
Y745933D01*
G01Y745267D02*
X272850Y745600D01*
X273267Y745850D01*
X273850Y745933D01*
X274267Y745850D01*
X274767Y745600D01*
G01X279200Y745933D02*
Y742600D01*
G01Y747267D02*
X279033Y747350D01*
Y747517D01*
X279200Y747600D01*
X279367Y747517D01*
Y747350D01*
X279200Y747267D01*
G01X286300Y742600D02*
Y745933D01*
G01Y745350D02*
X285967Y745683D01*
X285467Y745850D01*
X284883Y745933D01*
X284300Y745767D01*
X283800Y745433D01*
X283467Y744933D01*
X283300Y744267D01*
X283467Y743600D01*
X283800Y743100D01*
X284300Y742767D01*
X284883Y742600D01*
X285467Y742683D01*
X285967Y742933D01*
X286300Y743267D01*
G01X290400Y742600D02*
Y747600D01*
G01X294750Y743183D02*
X295167Y742850D01*
X295750Y742600D01*
X296250D01*
X296750Y742767D01*
X297083Y743017D01*
X297250Y743350D01*
X297167Y743850D01*
X296833Y744100D01*
X295333Y744600D01*
X295000Y745183D01*
X295167Y745600D01*
X295500Y745850D01*
X296000Y745933D01*
X296500Y745850D01*
X297000Y745600D01*
G01X306700Y742600D02*
Y746850D01*
X306867Y747267D01*
X307200Y747517D01*
X307700Y747600D01*
X308200Y747433D01*
X308450Y747017D01*
G01X307450Y745600D02*
X305783D01*
G01X312800Y742600D02*
X312300Y742683D01*
X311800Y743017D01*
X311467Y743600D01*
X311300Y744267D01*
X311467Y744933D01*
X311800Y745517D01*
X312300Y745850D01*
X312800Y745933D01*
X313300Y745850D01*
X313800Y745517D01*
X314133Y744933D01*
X314217Y744267D01*
X314133Y743600D01*
X313800Y743017D01*
X313300Y742683D01*
X312800Y742600D01*
G01X317233D02*
Y745933D01*
G01Y745267D02*
X317650Y745600D01*
X318067Y745850D01*
X318650Y745933D01*
X319067Y745850D01*
X319567Y745600D01*
G01X327933Y742600D02*
Y747600D01*
X330017D01*
X330683Y747350D01*
X331100Y747017D01*
X331267Y746350D01*
X331100Y745683D01*
X330600Y745267D01*
X330017Y745017D01*
X327933D01*
G01X330017D02*
X331267Y742600D01*
G01X335200Y745933D02*
Y742600D01*
G01Y747267D02*
X335033Y747350D01*
Y747517D01*
X335200Y747600D01*
X335367Y747517D01*
Y747350D01*
X335200Y747267D01*
G01X339633Y741350D02*
X340217Y741017D01*
X340883Y740933D01*
X341467Y741017D01*
X341967Y741433D01*
X342300Y742017D01*
Y745933D01*
G01Y745267D02*
X341967Y745600D01*
X341467Y745850D01*
X340883Y745933D01*
X340217Y745767D01*
X339800Y745433D01*
X339467Y744850D01*
X339300Y744267D01*
X339383Y743767D01*
X339717Y743183D01*
X340217Y742767D01*
X340883Y742600D01*
X341383Y742683D01*
X341967Y743017D01*
X342300Y743350D01*
G01X346400Y745933D02*
Y742600D01*
G01Y747267D02*
X346233Y747350D01*
Y747517D01*
X346400Y747600D01*
X346567Y747517D01*
Y747350D01*
X346400Y747267D01*
G01X353500Y747600D02*
Y742600D01*
G01Y743350D02*
X353167Y742933D01*
X352667Y742683D01*
X352083Y742600D01*
X351417Y742767D01*
X350917Y743183D01*
X350583Y743683D01*
X350500Y744267D01*
X350583Y744850D01*
X350917Y745350D01*
X351417Y745767D01*
X352083Y745933D01*
X352667Y745850D01*
X353083Y745683D01*
X353500Y745350D01*
G01X364700Y742600D02*
Y745933D01*
G01Y745350D02*
X364367Y745683D01*
X363867Y745850D01*
X363283Y745933D01*
X362700Y745767D01*
X362200Y745433D01*
X361867Y744933D01*
X361700Y744267D01*
X361867Y743600D01*
X362200Y743100D01*
X362700Y742767D01*
X363283Y742600D01*
X363867Y742683D01*
X364367Y742933D01*
X364700Y743267D01*
G01X367383Y742600D02*
Y745933D01*
G01Y745100D02*
X367717Y745517D01*
X368217Y745850D01*
X368883Y745933D01*
X369467Y745850D01*
X369967Y745517D01*
X370217Y744933D01*
Y742600D01*
G01X375900Y747600D02*
Y742600D01*
G01Y743350D02*
X375567Y742933D01*
X375067Y742683D01*
X374483Y742600D01*
X373817Y742767D01*
X373317Y743183D01*
X372983Y743683D01*
X372900Y744267D01*
X372983Y744850D01*
X373317Y745350D01*
X373817Y745767D01*
X374483Y745933D01*
X375067Y745850D01*
X375483Y745683D01*
X375900Y745350D01*
G01X383433Y742600D02*
Y747600D01*
X385600Y743433D01*
X387767Y747600D01*
Y742600D01*
G01X389783Y745933D02*
Y743600D01*
X390117Y743017D01*
X390617Y742683D01*
X391200Y742600D01*
X391783Y742683D01*
X392283Y743017D01*
X392617Y743600D01*
G01Y742600D02*
Y745933D01*
G01X396800Y742600D02*
Y747600D01*
G01X402400D02*
Y742600D01*
G01X401233Y745933D02*
X403567D01*
G01X408000D02*
Y742600D01*
G01Y747267D02*
X407833Y747350D01*
Y747517D01*
X408000Y747600D01*
X408167Y747517D01*
Y747350D01*
X408000Y747267D01*
G01X413600Y742600D02*
Y747600D01*
G01X420700Y742600D02*
Y745933D01*
G01Y745350D02*
X420367Y745683D01*
X419867Y745850D01*
X419283Y745933D01*
X418700Y745767D01*
X418200Y745433D01*
X417867Y744933D01*
X417700Y744267D01*
X417867Y743600D01*
X418200Y743100D01*
X418700Y742767D01*
X419283Y742600D01*
X419867Y742683D01*
X420367Y742933D01*
X420700Y743267D01*
G01X423050Y741100D02*
X423550Y740933D01*
X424217Y741100D01*
X424633Y741433D01*
X424967Y741850D01*
X425467Y743183D01*
X426550Y745933D01*
G01X423883D02*
X425467Y743183D01*
G01X429150Y744850D02*
X431817D01*
X431567Y745433D01*
X431150Y745767D01*
X430567Y745933D01*
X429983Y745850D01*
X429483Y745600D01*
X429150Y745017D01*
X428983Y744517D01*
Y744017D01*
X429150Y743517D01*
X429567Y743017D01*
X430067Y742683D01*
X430650Y742600D01*
X431233Y742767D01*
X431817Y743267D01*
G01X434833Y742600D02*
Y745933D01*
G01Y745267D02*
X435250Y745600D01*
X435667Y745850D01*
X436250Y745933D01*
X436667Y745850D01*
X437167Y745600D01*
G01X445533Y742600D02*
Y747600D01*
X447533D01*
X448200Y747350D01*
X448700Y746767D01*
X448867Y746100D01*
X448700Y745433D01*
X448283Y744933D01*
X447533Y744683D01*
X445533D01*
G01X451633Y742600D02*
Y745933D01*
G01Y745267D02*
X452050Y745600D01*
X452467Y745850D01*
X453050Y745933D01*
X453467Y745850D01*
X453967Y745600D01*
G01X458400Y745933D02*
Y742600D01*
G01Y747267D02*
X458233Y747350D01*
Y747517D01*
X458400Y747600D01*
X458567Y747517D01*
Y747350D01*
X458400Y747267D01*
G01X462583Y742600D02*
Y745933D01*
G01Y745100D02*
X462917Y745517D01*
X463417Y745850D01*
X464083Y745933D01*
X464667Y745850D01*
X465167Y745517D01*
X465417Y744933D01*
Y742600D01*
G01X469600Y747600D02*
Y742600D01*
G01X468433Y745933D02*
X470767D01*
G01X473950Y744850D02*
X476617D01*
X476367Y745433D01*
X475950Y745767D01*
X475367Y745933D01*
X474783Y745850D01*
X474283Y745600D01*
X473950Y745017D01*
X473783Y744517D01*
Y744017D01*
X473950Y743517D01*
X474367Y743017D01*
X474867Y742683D01*
X475450Y742600D01*
X476033Y742767D01*
X476617Y743267D01*
G01X482300Y747600D02*
Y742600D01*
G01Y743350D02*
X481967Y742933D01*
X481467Y742683D01*
X480883Y742600D01*
X480217Y742767D01*
X479717Y743183D01*
X479383Y743683D01*
X479300Y744267D01*
X479383Y744850D01*
X479717Y745350D01*
X480217Y745767D01*
X480883Y745933D01*
X481467Y745850D01*
X481883Y745683D01*
X482300Y745350D01*
G01X492667Y745267D02*
X493000Y745517D01*
X493250Y745933D01*
X493417Y746517D01*
X493250Y747017D01*
X492917Y747350D01*
X492333Y747600D01*
X490083D01*
Y742600D01*
X492833D01*
X493417Y742933D01*
X493750Y743433D01*
X493917Y744017D01*
X493750Y744600D01*
X493250Y745100D01*
X492667Y745267D01*
X490083D01*
G01X497600Y742600D02*
X497100Y742683D01*
X496600Y743017D01*
X496267Y743600D01*
X496100Y744267D01*
X496267Y744933D01*
X496600Y745517D01*
X497100Y745850D01*
X497600Y745933D01*
X498100Y745850D01*
X498600Y745517D01*
X498933Y744933D01*
X499017Y744267D01*
X498933Y743600D01*
X498600Y743017D01*
X498100Y742683D01*
X497600Y742600D01*
G01X504700D02*
Y745933D01*
G01Y745350D02*
X504367Y745683D01*
X503867Y745850D01*
X503283Y745933D01*
X502700Y745767D01*
X502200Y745433D01*
X501867Y744933D01*
X501700Y744267D01*
X501867Y743600D01*
X502200Y743100D01*
X502700Y742767D01*
X503283Y742600D01*
X503867Y742683D01*
X504367Y742933D01*
X504700Y743267D01*
G01X507633Y742600D02*
Y745933D01*
G01Y745267D02*
X508050Y745600D01*
X508467Y745850D01*
X509050Y745933D01*
X509467Y745850D01*
X509967Y745600D01*
G01X515900Y747600D02*
Y742600D01*
G01Y743350D02*
X515567Y742933D01*
X515067Y742683D01*
X514483Y742600D01*
X513817Y742767D01*
X513317Y743183D01*
X512983Y743683D01*
X512900Y744267D01*
X512983Y744850D01*
X513317Y745350D01*
X513817Y745767D01*
X514483Y745933D01*
X515067Y745850D01*
X515483Y745683D01*
X515900Y745350D01*
G01X518750Y743183D02*
X519167Y742850D01*
X519750Y742600D01*
X520250D01*
X520750Y742767D01*
X521083Y743017D01*
X521250Y743350D01*
X521167Y743850D01*
X520833Y744100D01*
X519333Y744600D01*
X519000Y745183D01*
X519167Y745600D01*
X519500Y745850D01*
X520000Y745933D01*
X520500Y745850D01*
X521000Y745600D01*
G01X71000Y756600D02*
X73000D01*
G01X72000D02*
Y751600D01*
G01X71000D02*
X73000D01*
G01X75933D02*
Y756600D01*
X77933D01*
X78600Y756350D01*
X79100Y755767D01*
X79267Y755100D01*
X79100Y754433D01*
X78683Y753933D01*
X77933Y753683D01*
X75933D01*
G01X85033Y756183D02*
X84533Y756433D01*
X83950Y756600D01*
X83283D01*
X82533Y756350D01*
X81950Y755933D01*
X81533Y755433D01*
X81200Y754600D01*
X81117Y753850D01*
X81283Y753100D01*
X81533Y752600D01*
X82033Y752100D01*
X82617Y751767D01*
X83200Y751600D01*
X83783D01*
X84367Y751767D01*
X84867Y752017D01*
X85283Y752350D01*
G01X87717Y753267D02*
X89883D01*
G01X94400Y756600D02*
Y751600D01*
G01X92483Y756600D02*
X96317D01*
G01X97833Y751600D02*
Y756600D01*
X100000Y752433D01*
X102167Y756600D01*
Y751600D01*
G01X104517Y753267D02*
X106683D01*
G01X109617Y753683D02*
X110200Y754267D01*
X110700Y754600D01*
X111367Y754767D01*
X111950Y754600D01*
X112367Y754267D01*
X112700Y753767D01*
X112783Y753183D01*
X112700Y752683D01*
X112367Y752183D01*
X111867Y751767D01*
X111283Y751600D01*
X110617Y751767D01*
X110033Y752267D01*
X109700Y753017D01*
X109617Y753850D01*
X109783Y754933D01*
X110033Y755517D01*
X110450Y756100D01*
X111033Y756517D01*
X111617Y756600D01*
X112200Y756433D01*
X112617Y756017D01*
G01X114967Y752350D02*
X115467Y751933D01*
X116050Y751683D01*
X116800Y751600D01*
X117550Y751767D01*
X118133Y752100D01*
X118550Y752683D01*
X118633Y753350D01*
X118467Y754017D01*
X118050Y754433D01*
X117467Y754767D01*
X116883Y754850D01*
X116300Y754767D01*
X115550Y754433D01*
X115800Y756600D01*
X118050D01*
G01X122400D02*
X121733Y756433D01*
X121233Y756017D01*
X120900Y755517D01*
X120650Y754850D01*
X120567Y754100D01*
X120650Y753350D01*
X120900Y752683D01*
X121233Y752183D01*
X121733Y751767D01*
X122400Y751600D01*
X123067Y751767D01*
X123567Y752183D01*
X123900Y752683D01*
X124150Y753350D01*
X124233Y754100D01*
X124150Y754850D01*
X123900Y755517D01*
X123567Y756017D01*
X123067Y756433D01*
X122400Y756600D01*
G01X133600D02*
Y751600D01*
G01X131683Y756600D02*
X135517D01*
G01X137950Y753850D02*
X140617D01*
X140367Y754433D01*
X139950Y754767D01*
X139367Y754933D01*
X138783Y754850D01*
X138283Y754600D01*
X137950Y754017D01*
X137783Y753517D01*
Y753017D01*
X137950Y752517D01*
X138367Y752017D01*
X138867Y751683D01*
X139450Y751600D01*
X140033Y751767D01*
X140617Y752267D01*
G01X143550Y752183D02*
X143967Y751850D01*
X144550Y751600D01*
X145050D01*
X145550Y751767D01*
X145883Y752017D01*
X146050Y752350D01*
X145967Y752850D01*
X145633Y753100D01*
X144133Y753600D01*
X143800Y754183D01*
X143967Y754600D01*
X144300Y754850D01*
X144800Y754933D01*
X145300Y754850D01*
X145800Y754600D01*
G01X150400Y756600D02*
Y751600D01*
G01X149233Y754933D02*
X151567D01*
G01X159433Y751600D02*
Y756600D01*
X161600Y752433D01*
X163767Y756600D01*
Y751600D01*
G01X165950Y753850D02*
X168617D01*
X168367Y754433D01*
X167950Y754767D01*
X167367Y754933D01*
X166783Y754850D01*
X166283Y754600D01*
X165950Y754017D01*
X165783Y753517D01*
Y753017D01*
X165950Y752517D01*
X166367Y752017D01*
X166867Y751683D01*
X167450Y751600D01*
X168033Y751767D01*
X168617Y752267D01*
G01X172800Y756600D02*
Y751600D01*
G01X171633Y754933D02*
X173967D01*
G01X176983Y751600D02*
Y756600D01*
G01Y754183D02*
X177400Y754600D01*
X177817Y754850D01*
X178483Y754933D01*
X178983Y754850D01*
X179567Y754517D01*
X179817Y754017D01*
Y751600D01*
G01X184000D02*
X183500Y751683D01*
X183000Y752017D01*
X182667Y752600D01*
X182500Y753267D01*
X182667Y753933D01*
X183000Y754517D01*
X183500Y754850D01*
X184000Y754933D01*
X184500Y754850D01*
X185000Y754517D01*
X185333Y753933D01*
X185417Y753267D01*
X185333Y752600D01*
X185000Y752017D01*
X184500Y751683D01*
X184000Y751600D01*
G01X191100Y756600D02*
Y751600D01*
G01Y752350D02*
X190767Y751933D01*
X190267Y751683D01*
X189683Y751600D01*
X189017Y751767D01*
X188517Y752183D01*
X188183Y752683D01*
X188100Y753267D01*
X188183Y753850D01*
X188517Y754350D01*
X189017Y754767D01*
X189683Y754933D01*
X190267Y754850D01*
X190683Y754683D01*
X191100Y754350D01*
G01X193950Y752183D02*
X194367Y751850D01*
X194950Y751600D01*
X195450D01*
X195950Y751767D01*
X196283Y752017D01*
X196450Y752350D01*
X196367Y752850D01*
X196033Y753100D01*
X194533Y753600D01*
X194200Y754183D01*
X194367Y754600D01*
X194700Y754850D01*
X195200Y754933D01*
X195700Y754850D01*
X196200Y754600D01*
G01X204233Y751600D02*
Y756600D01*
X206400Y752433D01*
X208567Y756600D01*
Y751600D01*
G01X213500D02*
Y754933D01*
G01Y754350D02*
X213167Y754683D01*
X212667Y754850D01*
X212083Y754933D01*
X211500Y754767D01*
X211000Y754433D01*
X210667Y753933D01*
X210500Y753267D01*
X210667Y752600D01*
X211000Y752100D01*
X211500Y751767D01*
X212083Y751600D01*
X212667Y751683D01*
X213167Y751933D01*
X213500Y752267D01*
G01X216183Y751600D02*
Y754933D01*
G01Y754100D02*
X216517Y754517D01*
X217017Y754850D01*
X217683Y754933D01*
X218267Y754850D01*
X218767Y754517D01*
X219017Y753933D01*
Y751600D01*
G01X221783Y754933D02*
Y752600D01*
X222117Y752017D01*
X222617Y751683D01*
X223200Y751600D01*
X223783Y751683D01*
X224283Y752017D01*
X224617Y752600D01*
G01Y751600D02*
Y754933D01*
G01X230300Y751600D02*
Y754933D01*
G01Y754350D02*
X229967Y754683D01*
X229467Y754850D01*
X228883Y754933D01*
X228300Y754767D01*
X227800Y754433D01*
X227467Y753933D01*
X227300Y753267D01*
X227467Y752600D01*
X227800Y752100D01*
X228300Y751767D01*
X228883Y751600D01*
X229467Y751683D01*
X229967Y751933D01*
X230300Y752267D01*
G01X234400Y751600D02*
Y756600D01*
G01X71000Y765600D02*
X73000D01*
G01X72000D02*
Y760600D01*
G01X71000D02*
X73000D01*
G01X75933D02*
Y765600D01*
X77933D01*
X78600Y765350D01*
X79100Y764767D01*
X79267Y764100D01*
X79100Y763433D01*
X78683Y762933D01*
X77933Y762683D01*
X75933D01*
G01X85033Y765183D02*
X84533Y765433D01*
X83950Y765600D01*
X83283D01*
X82533Y765350D01*
X81950Y764933D01*
X81533Y764433D01*
X81200Y763600D01*
X81117Y762850D01*
X81283Y762100D01*
X81533Y761600D01*
X82033Y761100D01*
X82617Y760767D01*
X83200Y760600D01*
X83783D01*
X84367Y760767D01*
X84867Y761017D01*
X85283Y761350D01*
G01X87717Y762267D02*
X89883D01*
G01X92817Y762683D02*
X93400Y763267D01*
X93900Y763600D01*
X94567Y763767D01*
X95150Y763600D01*
X95567Y763267D01*
X95900Y762767D01*
X95983Y762183D01*
X95900Y761683D01*
X95567Y761183D01*
X95067Y760767D01*
X94483Y760600D01*
X93817Y760767D01*
X93233Y761267D01*
X92900Y762017D01*
X92817Y762850D01*
X92983Y763933D01*
X93233Y764517D01*
X93650Y765100D01*
X94233Y765517D01*
X94817Y765600D01*
X95400Y765433D01*
X95817Y765017D01*
G01X100000Y765600D02*
X99333Y765433D01*
X98833Y765017D01*
X98500Y764517D01*
X98250Y763850D01*
X98167Y763100D01*
X98250Y762350D01*
X98500Y761683D01*
X98833Y761183D01*
X99333Y760767D01*
X100000Y760600D01*
X100667Y760767D01*
X101167Y761183D01*
X101500Y761683D01*
X101750Y762350D01*
X101833Y763100D01*
X101750Y763850D01*
X101500Y764517D01*
X101167Y765017D01*
X100667Y765433D01*
X100000Y765600D01*
G01X105600Y760600D02*
Y765600D01*
X104600Y764600D01*
G01Y760600D02*
X106600D01*
G01X109617Y762683D02*
X110200Y763267D01*
X110700Y763600D01*
X111367Y763767D01*
X111950Y763600D01*
X112367Y763267D01*
X112700Y762767D01*
X112783Y762183D01*
X112700Y761683D01*
X112367Y761183D01*
X111867Y760767D01*
X111283Y760600D01*
X110617Y760767D01*
X110033Y761267D01*
X109700Y762017D01*
X109617Y762850D01*
X109783Y763933D01*
X110033Y764517D01*
X110450Y765100D01*
X111033Y765517D01*
X111617Y765600D01*
X112200Y765433D01*
X112617Y765017D01*
G01X122400Y760600D02*
X121733Y760683D01*
X121150Y761017D01*
X120650Y761517D01*
X120317Y762100D01*
X120150Y762767D01*
Y763433D01*
X120317Y764100D01*
X120650Y764683D01*
X121150Y765183D01*
X121733Y765517D01*
X122400Y765600D01*
X123067Y765517D01*
X123650Y765183D01*
X124150Y764683D01*
X124483Y764100D01*
X124650Y763433D01*
Y762767D01*
X124483Y762100D01*
X124150Y761517D01*
X123650Y761017D01*
X123067Y760683D01*
X122400Y760600D01*
G01X123067Y761933D02*
X124067Y760600D01*
G01X126583Y763933D02*
Y761600D01*
X126917Y761017D01*
X127417Y760683D01*
X128000Y760600D01*
X128583Y760683D01*
X129083Y761017D01*
X129417Y761600D01*
G01Y760600D02*
Y763933D01*
G01X135100Y760600D02*
Y763933D01*
G01Y763350D02*
X134767Y763683D01*
X134267Y763850D01*
X133683Y763933D01*
X133100Y763767D01*
X132600Y763433D01*
X132267Y762933D01*
X132100Y762267D01*
X132267Y761600D01*
X132600Y761100D01*
X133100Y760767D01*
X133683Y760600D01*
X134267Y760683D01*
X134767Y760933D01*
X135100Y761267D01*
G01X139200Y760600D02*
Y765600D01*
G01X144800Y763933D02*
Y760600D01*
G01Y765267D02*
X144633Y765350D01*
Y765517D01*
X144800Y765600D01*
X144967Y765517D01*
Y765350D01*
X144800Y765267D01*
G01X149900Y760600D02*
Y764850D01*
X150067Y765267D01*
X150400Y765517D01*
X150900Y765600D01*
X151400Y765433D01*
X151650Y765017D01*
G01X150650Y763600D02*
X148983D01*
G01X156000Y763933D02*
Y760600D01*
G01Y765267D02*
X155833Y765350D01*
Y765517D01*
X156000Y765600D01*
X156167Y765517D01*
Y765350D01*
X156000Y765267D01*
G01X162933Y763517D02*
X162350Y763850D01*
X161850Y763933D01*
X161183Y763767D01*
X160683Y763433D01*
X160350Y762850D01*
X160267Y762267D01*
X160350Y761683D01*
X160683Y761183D01*
X161183Y760767D01*
X161850Y760600D01*
X162433Y760767D01*
X162933Y761100D01*
G01X168700Y760600D02*
Y763933D01*
G01Y763350D02*
X168367Y763683D01*
X167867Y763850D01*
X167283Y763933D01*
X166700Y763767D01*
X166200Y763433D01*
X165867Y762933D01*
X165700Y762267D01*
X165867Y761600D01*
X166200Y761100D01*
X166700Y760767D01*
X167283Y760600D01*
X167867Y760683D01*
X168367Y760933D01*
X168700Y761267D01*
G01X172800Y765600D02*
Y760600D01*
G01X171633Y763933D02*
X173967D01*
G01X178400D02*
Y760600D01*
G01Y765267D02*
X178233Y765350D01*
Y765517D01*
X178400Y765600D01*
X178567Y765517D01*
Y765350D01*
X178400Y765267D01*
G01X184000Y760600D02*
X183500Y760683D01*
X183000Y761017D01*
X182667Y761600D01*
X182500Y762267D01*
X182667Y762933D01*
X183000Y763517D01*
X183500Y763850D01*
X184000Y763933D01*
X184500Y763850D01*
X185000Y763517D01*
X185333Y762933D01*
X185417Y762267D01*
X185333Y761600D01*
X185000Y761017D01*
X184500Y760683D01*
X184000Y760600D01*
G01X188183D02*
Y763933D01*
G01Y763100D02*
X188517Y763517D01*
X189017Y763850D01*
X189683Y763933D01*
X190267Y763850D01*
X190767Y763517D01*
X191017Y762933D01*
Y760600D01*
G01X203300Y758933D02*
X199133Y763933D01*
Y764767D01*
X199967Y765600D01*
X200800D01*
X201633Y764767D01*
Y763933D01*
X200800Y763100D01*
X199133Y762267D01*
X198300Y761433D01*
Y759767D01*
X199133Y758933D01*
X201633D01*
X203300Y760600D01*
G01X210333D02*
Y765600D01*
X212333D01*
X213000Y765350D01*
X213500Y764767D01*
X213667Y764100D01*
X213500Y763433D01*
X213083Y762933D01*
X212333Y762683D01*
X210333D01*
G01X216350Y762850D02*
X219017D01*
X218767Y763433D01*
X218350Y763767D01*
X217767Y763933D01*
X217183Y763850D01*
X216683Y763600D01*
X216350Y763017D01*
X216183Y762517D01*
Y762017D01*
X216350Y761517D01*
X216767Y761017D01*
X217267Y760683D01*
X217850Y760600D01*
X218433Y760767D01*
X219017Y761267D01*
G01X222033Y760600D02*
Y763933D01*
G01Y763267D02*
X222450Y763600D01*
X222867Y763850D01*
X223450Y763933D01*
X223867Y763850D01*
X224367Y763600D01*
G01X228300Y760600D02*
Y764850D01*
X228467Y765267D01*
X228800Y765517D01*
X229300Y765600D01*
X229800Y765433D01*
X230050Y765017D01*
G01X229050Y763600D02*
X227383D01*
G01X234400Y760600D02*
X233900Y760683D01*
X233400Y761017D01*
X233067Y761600D01*
X232900Y762267D01*
X233067Y762933D01*
X233400Y763517D01*
X233900Y763850D01*
X234400Y763933D01*
X234900Y763850D01*
X235400Y763517D01*
X235733Y762933D01*
X235817Y762267D01*
X235733Y761600D01*
X235400Y761017D01*
X234900Y760683D01*
X234400Y760600D01*
G01X238833D02*
Y763933D01*
G01Y763267D02*
X239250Y763600D01*
X239667Y763850D01*
X240250Y763933D01*
X240667Y763850D01*
X241167Y763600D01*
G01X243100Y760600D02*
Y763933D01*
G01Y763017D02*
X243350Y763433D01*
X243767Y763767D01*
X244350Y763933D01*
X244933Y763767D01*
X245350Y763433D01*
X245600Y763017D01*
Y760600D01*
G01Y763017D02*
X245850Y763433D01*
X246267Y763767D01*
X246850Y763933D01*
X247433Y763767D01*
X247850Y763433D01*
X248100Y762933D01*
Y760600D01*
G01X252700D02*
Y763933D01*
G01Y763350D02*
X252367Y763683D01*
X251867Y763850D01*
X251283Y763933D01*
X250700Y763767D01*
X250200Y763433D01*
X249867Y762933D01*
X249700Y762267D01*
X249867Y761600D01*
X250200Y761100D01*
X250700Y760767D01*
X251283Y760600D01*
X251867Y760683D01*
X252367Y760933D01*
X252700Y761267D01*
G01X255383Y760600D02*
Y763933D01*
G01Y763100D02*
X255717Y763517D01*
X256217Y763850D01*
X256883Y763933D01*
X257467Y763850D01*
X257967Y763517D01*
X258217Y762933D01*
Y760600D01*
G01X263733Y763517D02*
X263150Y763850D01*
X262650Y763933D01*
X261983Y763767D01*
X261483Y763433D01*
X261150Y762850D01*
X261067Y762267D01*
X261150Y761683D01*
X261483Y761183D01*
X261983Y760767D01*
X262650Y760600D01*
X263233Y760767D01*
X263733Y761100D01*
G01X266750Y762850D02*
X269417D01*
X269167Y763433D01*
X268750Y763767D01*
X268167Y763933D01*
X267583Y763850D01*
X267083Y763600D01*
X266750Y763017D01*
X266583Y762517D01*
Y762017D01*
X266750Y761517D01*
X267167Y761017D01*
X267667Y760683D01*
X268250Y760600D01*
X268833Y760767D01*
X269417Y761267D01*
G01X277450D02*
X278117Y760850D01*
X278867Y760600D01*
X279533D01*
X280200Y760850D01*
X280700Y761267D01*
X280950Y761850D01*
X280783Y762433D01*
X280367Y762933D01*
X279617Y763267D01*
X278617Y763433D01*
X278033Y763767D01*
X277783Y764350D01*
X277950Y764933D01*
X278367Y765350D01*
X278950Y765600D01*
X279533D01*
X280117Y765433D01*
X280617Y765017D01*
G01X283300Y758933D02*
Y763933D01*
G01Y763183D02*
X283717Y763600D01*
X284133Y763850D01*
X284800Y763933D01*
X285383Y763850D01*
X285967Y763433D01*
X286217Y762850D01*
X286300Y762267D01*
X286217Y761683D01*
X285967Y761100D01*
X285467Y760767D01*
X284800Y760600D01*
X284217Y760683D01*
X283633Y760933D01*
X283300Y761267D01*
G01X289150Y762850D02*
X291817D01*
X291567Y763433D01*
X291150Y763767D01*
X290567Y763933D01*
X289983Y763850D01*
X289483Y763600D01*
X289150Y763017D01*
X288983Y762517D01*
Y762017D01*
X289150Y761517D01*
X289567Y761017D01*
X290067Y760683D01*
X290650Y760600D01*
X291233Y760767D01*
X291817Y761267D01*
G01X297333Y763517D02*
X296750Y763850D01*
X296250Y763933D01*
X295583Y763767D01*
X295083Y763433D01*
X294750Y762850D01*
X294667Y762267D01*
X294750Y761683D01*
X295083Y761183D01*
X295583Y760767D01*
X296250Y760600D01*
X296833Y760767D01*
X297333Y761100D01*
G01X301600Y763933D02*
Y760600D01*
G01Y765267D02*
X301433Y765350D01*
Y765517D01*
X301600Y765600D01*
X301767Y765517D01*
Y765350D01*
X301600Y765267D01*
G01X306700Y760600D02*
Y764850D01*
X306867Y765267D01*
X307200Y765517D01*
X307700Y765600D01*
X308200Y765433D01*
X308450Y765017D01*
G01X307450Y763600D02*
X305783D01*
G01X312800Y763933D02*
Y760600D01*
G01Y765267D02*
X312633Y765350D01*
Y765517D01*
X312800Y765600D01*
X312967Y765517D01*
Y765350D01*
X312800Y765267D01*
G01X319733Y763517D02*
X319150Y763850D01*
X318650Y763933D01*
X317983Y763767D01*
X317483Y763433D01*
X317150Y762850D01*
X317067Y762267D01*
X317150Y761683D01*
X317483Y761183D01*
X317983Y760767D01*
X318650Y760600D01*
X319233Y760767D01*
X319733Y761100D01*
G01X325500Y760600D02*
Y763933D01*
G01Y763350D02*
X325167Y763683D01*
X324667Y763850D01*
X324083Y763933D01*
X323500Y763767D01*
X323000Y763433D01*
X322667Y762933D01*
X322500Y762267D01*
X322667Y761600D01*
X323000Y761100D01*
X323500Y760767D01*
X324083Y760600D01*
X324667Y760683D01*
X325167Y760933D01*
X325500Y761267D01*
G01X329600Y765600D02*
Y760600D01*
G01X328433Y763933D02*
X330767D01*
G01X335200D02*
Y760600D01*
G01Y765267D02*
X335033Y765350D01*
Y765517D01*
X335200Y765600D01*
X335367Y765517D01*
Y765350D01*
X335200Y765267D01*
G01X340800Y760600D02*
X340300Y760683D01*
X339800Y761017D01*
X339467Y761600D01*
X339300Y762267D01*
X339467Y762933D01*
X339800Y763517D01*
X340300Y763850D01*
X340800Y763933D01*
X341300Y763850D01*
X341800Y763517D01*
X342133Y762933D01*
X342217Y762267D01*
X342133Y761600D01*
X341800Y761017D01*
X341300Y760683D01*
X340800Y760600D01*
G01X344983D02*
Y763933D01*
G01Y763100D02*
X345317Y763517D01*
X345817Y763850D01*
X346483Y763933D01*
X347067Y763850D01*
X347567Y763517D01*
X347817Y762933D01*
Y760600D01*
G01X357100D02*
Y764850D01*
X357267Y765267D01*
X357600Y765517D01*
X358100Y765600D01*
X358600Y765433D01*
X358850Y765017D01*
G01X357850Y763600D02*
X356183D01*
G01X363200Y760600D02*
X362700Y760683D01*
X362200Y761017D01*
X361867Y761600D01*
X361700Y762267D01*
X361867Y762933D01*
X362200Y763517D01*
X362700Y763850D01*
X363200Y763933D01*
X363700Y763850D01*
X364200Y763517D01*
X364533Y762933D01*
X364617Y762267D01*
X364533Y761600D01*
X364200Y761017D01*
X363700Y760683D01*
X363200Y760600D01*
G01X367633D02*
Y763933D01*
G01Y763267D02*
X368050Y763600D01*
X368467Y763850D01*
X369050Y763933D01*
X369467Y763850D01*
X369967Y763600D01*
G01X378250Y760600D02*
Y765600D01*
G01X381750D02*
Y760600D01*
G01Y763100D02*
X378250D01*
G01X385600Y763933D02*
Y760600D01*
G01Y765267D02*
X385433Y765350D01*
Y765517D01*
X385600Y765600D01*
X385767Y765517D01*
Y765350D01*
X385600Y765267D01*
G01X390033Y759350D02*
X390617Y759017D01*
X391283Y758933D01*
X391867Y759017D01*
X392367Y759433D01*
X392700Y760017D01*
Y763933D01*
G01Y763267D02*
X392367Y763600D01*
X391867Y763850D01*
X391283Y763933D01*
X390617Y763767D01*
X390200Y763433D01*
X389867Y762850D01*
X389700Y762267D01*
X389783Y761767D01*
X390117Y761183D01*
X390617Y760767D01*
X391283Y760600D01*
X391783Y760683D01*
X392367Y761017D01*
X392700Y761350D01*
G01X395383Y760600D02*
Y765600D01*
G01Y763183D02*
X395800Y763600D01*
X396217Y763850D01*
X396883Y763933D01*
X397383Y763850D01*
X397967Y763517D01*
X398217Y763017D01*
Y760600D01*
G01X406167D02*
Y765600D01*
X407833D01*
X408500Y765350D01*
X409000Y765017D01*
X409417Y764517D01*
X409750Y763933D01*
X409833Y763100D01*
X409750Y762267D01*
X409417Y761683D01*
X409000Y761183D01*
X408500Y760850D01*
X407833Y760600D01*
X406167D01*
G01X412350Y762850D02*
X415017D01*
X414767Y763433D01*
X414350Y763767D01*
X413767Y763933D01*
X413183Y763850D01*
X412683Y763600D01*
X412350Y763017D01*
X412183Y762517D01*
Y762017D01*
X412350Y761517D01*
X412767Y761017D01*
X413267Y760683D01*
X413850Y760600D01*
X414433Y760767D01*
X415017Y761267D01*
G01X417783Y760600D02*
Y763933D01*
G01Y763100D02*
X418117Y763517D01*
X418617Y763850D01*
X419283Y763933D01*
X419867Y763850D01*
X420367Y763517D01*
X420617Y762933D01*
Y760600D01*
G01X423550Y761183D02*
X423967Y760850D01*
X424550Y760600D01*
X425050D01*
X425550Y760767D01*
X425883Y761017D01*
X426050Y761350D01*
X425967Y761850D01*
X425633Y762100D01*
X424133Y762600D01*
X423800Y763183D01*
X423967Y763600D01*
X424300Y763850D01*
X424800Y763933D01*
X425300Y763850D01*
X425800Y763600D01*
G01X430400Y763933D02*
Y760600D01*
G01Y765267D02*
X430233Y765350D01*
Y765517D01*
X430400Y765600D01*
X430567Y765517D01*
Y765350D01*
X430400Y765267D01*
G01X436000Y765600D02*
Y760600D01*
G01X434833Y763933D02*
X437167D01*
G01X439850Y759100D02*
X440350Y758933D01*
X441017Y759100D01*
X441433Y759433D01*
X441767Y759850D01*
X442267Y761183D01*
X443350Y763933D01*
G01X440683D02*
X442267Y761183D01*
G01X451800Y765600D02*
X453800D01*
G01X452800D02*
Y760600D01*
G01X451800D02*
X453800D01*
G01X456983D02*
Y763933D01*
G01Y763100D02*
X457317Y763517D01*
X457817Y763850D01*
X458483Y763933D01*
X459067Y763850D01*
X459567Y763517D01*
X459817Y762933D01*
Y760600D01*
G01X464000Y765600D02*
Y760600D01*
G01X462833Y763933D02*
X465167D01*
G01X468350Y762850D02*
X471017D01*
X470767Y763433D01*
X470350Y763767D01*
X469767Y763933D01*
X469183Y763850D01*
X468683Y763600D01*
X468350Y763017D01*
X468183Y762517D01*
Y762017D01*
X468350Y761517D01*
X468767Y761017D01*
X469267Y760683D01*
X469850Y760600D01*
X470433Y760767D01*
X471017Y761267D01*
G01X474033Y760600D02*
Y763933D01*
G01Y763267D02*
X474450Y763600D01*
X474867Y763850D01*
X475450Y763933D01*
X475867Y763850D01*
X476367Y763600D01*
G01X482133Y763517D02*
X481550Y763850D01*
X481050Y763933D01*
X480383Y763767D01*
X479883Y763433D01*
X479550Y762850D01*
X479467Y762267D01*
X479550Y761683D01*
X479883Y761183D01*
X480383Y760767D01*
X481050Y760600D01*
X481633Y760767D01*
X482133Y761100D01*
G01X486400Y760600D02*
X485900Y760683D01*
X485400Y761017D01*
X485067Y761600D01*
X484900Y762267D01*
X485067Y762933D01*
X485400Y763517D01*
X485900Y763850D01*
X486400Y763933D01*
X486900Y763850D01*
X487400Y763517D01*
X487733Y762933D01*
X487817Y762267D01*
X487733Y761600D01*
X487400Y761017D01*
X486900Y760683D01*
X486400Y760600D01*
G01X490583D02*
Y763933D01*
G01Y763100D02*
X490917Y763517D01*
X491417Y763850D01*
X492083Y763933D01*
X492667Y763850D01*
X493167Y763517D01*
X493417Y762933D01*
Y760600D01*
G01X496183D02*
Y763933D01*
G01Y763100D02*
X496517Y763517D01*
X497017Y763850D01*
X497683Y763933D01*
X498267Y763850D01*
X498767Y763517D01*
X499017Y762933D01*
Y760600D01*
G01X501950Y762850D02*
X504617D01*
X504367Y763433D01*
X503950Y763767D01*
X503367Y763933D01*
X502783Y763850D01*
X502283Y763600D01*
X501950Y763017D01*
X501783Y762517D01*
Y762017D01*
X501950Y761517D01*
X502367Y761017D01*
X502867Y760683D01*
X503450Y760600D01*
X504033Y760767D01*
X504617Y761267D01*
G01X510133Y763517D02*
X509550Y763850D01*
X509050Y763933D01*
X508383Y763767D01*
X507883Y763433D01*
X507550Y762850D01*
X507467Y762267D01*
X507550Y761683D01*
X507883Y761183D01*
X508383Y760767D01*
X509050Y760600D01*
X509633Y760767D01*
X510133Y761100D01*
G01X514400Y765600D02*
Y760600D01*
G01X513233Y763933D02*
X515567D01*
G01X519583Y758933D02*
X518750Y759767D01*
X518333Y760600D01*
Y763933D01*
X518750Y764767D01*
X519583Y765600D01*
G01X523850Y760600D02*
Y765600D01*
G01X527350D02*
Y760600D01*
G01Y763100D02*
X523850D01*
G01X529367Y760600D02*
Y765600D01*
X531033D01*
X531700Y765350D01*
X532200Y765017D01*
X532617Y764517D01*
X532950Y763933D01*
X533033Y763100D01*
X532950Y762267D01*
X532617Y761683D01*
X532200Y761183D01*
X531700Y760850D01*
X531033Y760600D01*
X529367D01*
G01X535800Y765600D02*
X537800D01*
G01X536800D02*
Y760600D01*
G01X535800D02*
X537800D01*
G01X542817Y758933D02*
X543650Y759767D01*
X544067Y760600D01*
Y763933D01*
X543650Y764767D01*
X542817Y765600D01*
G01X551933D02*
Y760600D01*
X555267D01*
G01X560700D02*
Y763933D01*
G01Y763350D02*
X560367Y763683D01*
X559867Y763850D01*
X559283Y763933D01*
X558700Y763767D01*
X558200Y763433D01*
X557867Y762933D01*
X557700Y762267D01*
X557867Y761600D01*
X558200Y761100D01*
X558700Y760767D01*
X559283Y760600D01*
X559867Y760683D01*
X560367Y760933D01*
X560700Y761267D01*
G01X563050Y759100D02*
X563550Y758933D01*
X564217Y759100D01*
X564633Y759433D01*
X564967Y759850D01*
X565467Y761183D01*
X566550Y763933D01*
G01X563883D02*
X565467Y761183D01*
G01X569150Y762850D02*
X571817D01*
X571567Y763433D01*
X571150Y763767D01*
X570567Y763933D01*
X569983Y763850D01*
X569483Y763600D01*
X569150Y763017D01*
X568983Y762517D01*
Y762017D01*
X569150Y761517D01*
X569567Y761017D01*
X570067Y760683D01*
X570650Y760600D01*
X571233Y760767D01*
X571817Y761267D01*
G01X574833Y760600D02*
Y763933D01*
G01Y763267D02*
X575250Y763600D01*
X575667Y763850D01*
X576250Y763933D01*
X576667Y763850D01*
X577167Y763600D01*
G01X580350Y761183D02*
X580767Y760850D01*
X581350Y760600D01*
X581850D01*
X582350Y760767D01*
X582683Y761017D01*
X582850Y761350D01*
X582767Y761850D01*
X582433Y762100D01*
X580933Y762600D01*
X580600Y763183D01*
X580767Y763600D01*
X581100Y763850D01*
X581600Y763933D01*
X582100Y763850D01*
X582600Y763600D01*
G01X592800Y760600D02*
X592300Y760683D01*
X591800Y761017D01*
X591467Y761600D01*
X591300Y762267D01*
X591467Y762933D01*
X591800Y763517D01*
X592300Y763850D01*
X592800Y763933D01*
X593300Y763850D01*
X593800Y763517D01*
X594133Y762933D01*
X594217Y762267D01*
X594133Y761600D01*
X593800Y761017D01*
X593300Y760683D01*
X592800Y760600D01*
G01X597233D02*
Y763933D01*
G01Y763267D02*
X597650Y763600D01*
X598067Y763850D01*
X598650Y763933D01*
X599067Y763850D01*
X599567Y763600D01*
G01X610267Y763267D02*
X610600Y763517D01*
X610850Y763933D01*
X611017Y764517D01*
X610850Y765017D01*
X610517Y765350D01*
X609933Y765600D01*
X607683D01*
Y760600D01*
X610433D01*
X611017Y760933D01*
X611350Y761433D01*
X611517Y762017D01*
X611350Y762600D01*
X610850Y763100D01*
X610267Y763267D01*
X607683D01*
G01X615200Y760600D02*
X614700Y760683D01*
X614200Y761017D01*
X613867Y761600D01*
X613700Y762267D01*
X613867Y762933D01*
X614200Y763517D01*
X614700Y763850D01*
X615200Y763933D01*
X615700Y763850D01*
X616200Y763517D01*
X616533Y762933D01*
X616617Y762267D01*
X616533Y761600D01*
X616200Y761017D01*
X615700Y760683D01*
X615200Y760600D01*
G01X622300D02*
Y763933D01*
G01Y763350D02*
X621967Y763683D01*
X621467Y763850D01*
X620883Y763933D01*
X620300Y763767D01*
X619800Y763433D01*
X619467Y762933D01*
X619300Y762267D01*
X619467Y761600D01*
X619800Y761100D01*
X620300Y760767D01*
X620883Y760600D01*
X621467Y760683D01*
X621967Y760933D01*
X622300Y761267D01*
G01X625233Y760600D02*
Y763933D01*
G01Y763267D02*
X625650Y763600D01*
X626067Y763850D01*
X626650Y763933D01*
X627067Y763850D01*
X627567Y763600D01*
G01X633500Y765600D02*
Y760600D01*
G01Y761350D02*
X633167Y760933D01*
X632667Y760683D01*
X632083Y760600D01*
X631417Y760767D01*
X630917Y761183D01*
X630583Y761683D01*
X630500Y762267D01*
X630583Y762850D01*
X630917Y763350D01*
X631417Y763767D01*
X632083Y763933D01*
X632667Y763850D01*
X633083Y763683D01*
X633500Y763350D01*
G01X636350Y761183D02*
X636767Y760850D01*
X637350Y760600D01*
X637850D01*
X638350Y760767D01*
X638683Y761017D01*
X638850Y761350D01*
X638767Y761850D01*
X638433Y762100D01*
X636933Y762600D01*
X636600Y763183D01*
X636767Y763600D01*
X637100Y763850D01*
X637600Y763933D01*
X638100Y763850D01*
X638600Y763600D01*
G01X643617Y758933D02*
X644450Y759767D01*
X644867Y760600D01*
Y763933D01*
X644450Y764767D01*
X643617Y765600D01*
G01X71000Y774600D02*
X73000D01*
G01X72000D02*
Y769600D01*
G01X71000D02*
X73000D01*
G01X75933D02*
Y774600D01*
X77933D01*
X78600Y774350D01*
X79100Y773767D01*
X79267Y773100D01*
X79100Y772433D01*
X78683Y771933D01*
X77933Y771683D01*
X75933D01*
G01X85033Y774183D02*
X84533Y774433D01*
X83950Y774600D01*
X83283D01*
X82533Y774350D01*
X81950Y773933D01*
X81533Y773433D01*
X81200Y772600D01*
X81117Y771850D01*
X81283Y771100D01*
X81533Y770600D01*
X82033Y770100D01*
X82617Y769767D01*
X83200Y769600D01*
X83783D01*
X84367Y769767D01*
X84867Y770017D01*
X85283Y770350D01*
G01X87717Y771267D02*
X89883D01*
G01X92817Y771683D02*
X93400Y772267D01*
X93900Y772600D01*
X94567Y772767D01*
X95150Y772600D01*
X95567Y772267D01*
X95900Y771767D01*
X95983Y771183D01*
X95900Y770683D01*
X95567Y770183D01*
X95067Y769767D01*
X94483Y769600D01*
X93817Y769767D01*
X93233Y770267D01*
X92900Y771017D01*
X92817Y771850D01*
X92983Y772933D01*
X93233Y773517D01*
X93650Y774100D01*
X94233Y774517D01*
X94817Y774600D01*
X95400Y774433D01*
X95817Y774017D01*
G01X100000Y774600D02*
X99333Y774433D01*
X98833Y774017D01*
X98500Y773517D01*
X98250Y772850D01*
X98167Y772100D01*
X98250Y771350D01*
X98500Y770683D01*
X98833Y770183D01*
X99333Y769767D01*
X100000Y769600D01*
X100667Y769767D01*
X101167Y770183D01*
X101500Y770683D01*
X101750Y771350D01*
X101833Y772100D01*
X101750Y772850D01*
X101500Y773517D01*
X101167Y774017D01*
X100667Y774433D01*
X100000Y774600D01*
G01X105600Y769600D02*
Y774600D01*
X104600Y773600D01*
G01Y769600D02*
X106600D01*
G01X109617Y773767D02*
X110117Y774267D01*
X110700Y774517D01*
X111367Y774600D01*
X112200Y774433D01*
X112783Y774017D01*
X112950Y773517D01*
X112867Y773017D01*
X112533Y772600D01*
X110867Y771767D01*
X110117Y771183D01*
X109617Y770350D01*
X109450Y769600D01*
X112950D01*
G01X122400D02*
X121733Y769683D01*
X121150Y770017D01*
X120650Y770517D01*
X120317Y771100D01*
X120150Y771767D01*
Y772433D01*
X120317Y773100D01*
X120650Y773683D01*
X121150Y774183D01*
X121733Y774517D01*
X122400Y774600D01*
X123067Y774517D01*
X123650Y774183D01*
X124150Y773683D01*
X124483Y773100D01*
X124650Y772433D01*
Y771767D01*
X124483Y771100D01*
X124150Y770517D01*
X123650Y770017D01*
X123067Y769683D01*
X122400Y769600D01*
G01X123067Y770933D02*
X124067Y769600D01*
G01X126583Y772933D02*
Y770600D01*
X126917Y770017D01*
X127417Y769683D01*
X128000Y769600D01*
X128583Y769683D01*
X129083Y770017D01*
X129417Y770600D01*
G01Y769600D02*
Y772933D01*
G01X135100Y769600D02*
Y772933D01*
G01Y772350D02*
X134767Y772683D01*
X134267Y772850D01*
X133683Y772933D01*
X133100Y772767D01*
X132600Y772433D01*
X132267Y771933D01*
X132100Y771267D01*
X132267Y770600D01*
X132600Y770100D01*
X133100Y769767D01*
X133683Y769600D01*
X134267Y769683D01*
X134767Y769933D01*
X135100Y770267D01*
G01X139200Y769600D02*
Y774600D01*
G01X144800Y772933D02*
Y769600D01*
G01Y774267D02*
X144633Y774350D01*
Y774517D01*
X144800Y774600D01*
X144967Y774517D01*
Y774350D01*
X144800Y774267D01*
G01X149900Y769600D02*
Y773850D01*
X150067Y774267D01*
X150400Y774517D01*
X150900Y774600D01*
X151400Y774433D01*
X151650Y774017D01*
G01X150650Y772600D02*
X148983D01*
G01X156000Y772933D02*
Y769600D01*
G01Y774267D02*
X155833Y774350D01*
Y774517D01*
X156000Y774600D01*
X156167Y774517D01*
Y774350D01*
X156000Y774267D01*
G01X162933Y772517D02*
X162350Y772850D01*
X161850Y772933D01*
X161183Y772767D01*
X160683Y772433D01*
X160350Y771850D01*
X160267Y771267D01*
X160350Y770683D01*
X160683Y770183D01*
X161183Y769767D01*
X161850Y769600D01*
X162433Y769767D01*
X162933Y770100D01*
G01X168700Y769600D02*
Y772933D01*
G01Y772350D02*
X168367Y772683D01*
X167867Y772850D01*
X167283Y772933D01*
X166700Y772767D01*
X166200Y772433D01*
X165867Y771933D01*
X165700Y771267D01*
X165867Y770600D01*
X166200Y770100D01*
X166700Y769767D01*
X167283Y769600D01*
X167867Y769683D01*
X168367Y769933D01*
X168700Y770267D01*
G01X172800Y774600D02*
Y769600D01*
G01X171633Y772933D02*
X173967D01*
G01X178400D02*
Y769600D01*
G01Y774267D02*
X178233Y774350D01*
Y774517D01*
X178400Y774600D01*
X178567Y774517D01*
Y774350D01*
X178400Y774267D01*
G01X184000Y769600D02*
X183500Y769683D01*
X183000Y770017D01*
X182667Y770600D01*
X182500Y771267D01*
X182667Y771933D01*
X183000Y772517D01*
X183500Y772850D01*
X184000Y772933D01*
X184500Y772850D01*
X185000Y772517D01*
X185333Y771933D01*
X185417Y771267D01*
X185333Y770600D01*
X185000Y770017D01*
X184500Y769683D01*
X184000Y769600D01*
G01X188183D02*
Y772933D01*
G01Y772100D02*
X188517Y772517D01*
X189017Y772850D01*
X189683Y772933D01*
X190267Y772850D01*
X190767Y772517D01*
X191017Y771933D01*
Y769600D01*
G01X202300D02*
Y772933D01*
G01Y772350D02*
X201967Y772683D01*
X201467Y772850D01*
X200883Y772933D01*
X200300Y772767D01*
X199800Y772433D01*
X199467Y771933D01*
X199300Y771267D01*
X199467Y770600D01*
X199800Y770100D01*
X200300Y769767D01*
X200883Y769600D01*
X201467Y769683D01*
X201967Y769933D01*
X202300Y770267D01*
G01X204983Y769600D02*
Y772933D01*
G01Y772100D02*
X205317Y772517D01*
X205817Y772850D01*
X206483Y772933D01*
X207067Y772850D01*
X207567Y772517D01*
X207817Y771933D01*
Y769600D01*
G01X213500Y774600D02*
Y769600D01*
G01Y770350D02*
X213167Y769933D01*
X212667Y769683D01*
X212083Y769600D01*
X211417Y769767D01*
X210917Y770183D01*
X210583Y770683D01*
X210500Y771267D01*
X210583Y771850D01*
X210917Y772350D01*
X211417Y772767D01*
X212083Y772933D01*
X212667Y772850D01*
X213083Y772683D01*
X213500Y772350D01*
G01X221533Y769600D02*
Y774600D01*
X223533D01*
X224200Y774350D01*
X224700Y773767D01*
X224867Y773100D01*
X224700Y772433D01*
X224283Y771933D01*
X223533Y771683D01*
X221533D01*
G01X227550Y771850D02*
X230217D01*
X229967Y772433D01*
X229550Y772767D01*
X228967Y772933D01*
X228383Y772850D01*
X227883Y772600D01*
X227550Y772017D01*
X227383Y771517D01*
Y771017D01*
X227550Y770517D01*
X227967Y770017D01*
X228467Y769683D01*
X229050Y769600D01*
X229633Y769767D01*
X230217Y770267D01*
G01X233233Y769600D02*
Y772933D01*
G01Y772267D02*
X233650Y772600D01*
X234067Y772850D01*
X234650Y772933D01*
X235067Y772850D01*
X235567Y772600D01*
G01X239500Y769600D02*
Y773850D01*
X239667Y774267D01*
X240000Y774517D01*
X240500Y774600D01*
X241000Y774433D01*
X241250Y774017D01*
G01X240250Y772600D02*
X238583D01*
G01X245600Y769600D02*
X245100Y769683D01*
X244600Y770017D01*
X244267Y770600D01*
X244100Y771267D01*
X244267Y771933D01*
X244600Y772517D01*
X245100Y772850D01*
X245600Y772933D01*
X246100Y772850D01*
X246600Y772517D01*
X246933Y771933D01*
X247017Y771267D01*
X246933Y770600D01*
X246600Y770017D01*
X246100Y769683D01*
X245600Y769600D01*
G01X250033D02*
Y772933D01*
G01Y772267D02*
X250450Y772600D01*
X250867Y772850D01*
X251450Y772933D01*
X251867Y772850D01*
X252367Y772600D01*
G01X254300Y769600D02*
Y772933D01*
G01Y772017D02*
X254550Y772433D01*
X254967Y772767D01*
X255550Y772933D01*
X256133Y772767D01*
X256550Y772433D01*
X256800Y772017D01*
Y769600D01*
G01Y772017D02*
X257050Y772433D01*
X257467Y772767D01*
X258050Y772933D01*
X258633Y772767D01*
X259050Y772433D01*
X259300Y771933D01*
Y769600D01*
G01X263900D02*
Y772933D01*
G01Y772350D02*
X263567Y772683D01*
X263067Y772850D01*
X262483Y772933D01*
X261900Y772767D01*
X261400Y772433D01*
X261067Y771933D01*
X260900Y771267D01*
X261067Y770600D01*
X261400Y770100D01*
X261900Y769767D01*
X262483Y769600D01*
X263067Y769683D01*
X263567Y769933D01*
X263900Y770267D01*
G01X266583Y769600D02*
Y772933D01*
G01Y772100D02*
X266917Y772517D01*
X267417Y772850D01*
X268083Y772933D01*
X268667Y772850D01*
X269167Y772517D01*
X269417Y771933D01*
Y769600D01*
G01X274933Y772517D02*
X274350Y772850D01*
X273850Y772933D01*
X273183Y772767D01*
X272683Y772433D01*
X272350Y771850D01*
X272267Y771267D01*
X272350Y770683D01*
X272683Y770183D01*
X273183Y769767D01*
X273850Y769600D01*
X274433Y769767D01*
X274933Y770100D01*
G01X277950Y771850D02*
X280617D01*
X280367Y772433D01*
X279950Y772767D01*
X279367Y772933D01*
X278783Y772850D01*
X278283Y772600D01*
X277950Y772017D01*
X277783Y771517D01*
Y771017D01*
X277950Y770517D01*
X278367Y770017D01*
X278867Y769683D01*
X279450Y769600D01*
X280033Y769767D01*
X280617Y770267D01*
G01X288650D02*
X289317Y769850D01*
X290067Y769600D01*
X290733D01*
X291400Y769850D01*
X291900Y770267D01*
X292150Y770850D01*
X291983Y771433D01*
X291567Y771933D01*
X290817Y772267D01*
X289817Y772433D01*
X289233Y772767D01*
X288983Y773350D01*
X289150Y773933D01*
X289567Y774350D01*
X290150Y774600D01*
X290733D01*
X291317Y774433D01*
X291817Y774017D01*
G01X294500Y767933D02*
Y772933D01*
G01Y772183D02*
X294917Y772600D01*
X295333Y772850D01*
X296000Y772933D01*
X296583Y772850D01*
X297167Y772433D01*
X297417Y771850D01*
X297500Y771267D01*
X297417Y770683D01*
X297167Y770100D01*
X296667Y769767D01*
X296000Y769600D01*
X295417Y769683D01*
X294833Y769933D01*
X294500Y770267D01*
G01X300350Y771850D02*
X303017D01*
X302767Y772433D01*
X302350Y772767D01*
X301767Y772933D01*
X301183Y772850D01*
X300683Y772600D01*
X300350Y772017D01*
X300183Y771517D01*
Y771017D01*
X300350Y770517D01*
X300767Y770017D01*
X301267Y769683D01*
X301850Y769600D01*
X302433Y769767D01*
X303017Y770267D01*
G01X308533Y772517D02*
X307950Y772850D01*
X307450Y772933D01*
X306783Y772767D01*
X306283Y772433D01*
X305950Y771850D01*
X305867Y771267D01*
X305950Y770683D01*
X306283Y770183D01*
X306783Y769767D01*
X307450Y769600D01*
X308033Y769767D01*
X308533Y770100D01*
G01X312800Y772933D02*
Y769600D01*
G01Y774267D02*
X312633Y774350D01*
Y774517D01*
X312800Y774600D01*
X312967Y774517D01*
Y774350D01*
X312800Y774267D01*
G01X317900Y769600D02*
Y773850D01*
X318067Y774267D01*
X318400Y774517D01*
X318900Y774600D01*
X319400Y774433D01*
X319650Y774017D01*
G01X318650Y772600D02*
X316983D01*
G01X324000Y772933D02*
Y769600D01*
G01Y774267D02*
X323833Y774350D01*
Y774517D01*
X324000Y774600D01*
X324167Y774517D01*
Y774350D01*
X324000Y774267D01*
G01X330933Y772517D02*
X330350Y772850D01*
X329850Y772933D01*
X329183Y772767D01*
X328683Y772433D01*
X328350Y771850D01*
X328267Y771267D01*
X328350Y770683D01*
X328683Y770183D01*
X329183Y769767D01*
X329850Y769600D01*
X330433Y769767D01*
X330933Y770100D01*
G01X336700Y769600D02*
Y772933D01*
G01Y772350D02*
X336367Y772683D01*
X335867Y772850D01*
X335283Y772933D01*
X334700Y772767D01*
X334200Y772433D01*
X333867Y771933D01*
X333700Y771267D01*
X333867Y770600D01*
X334200Y770100D01*
X334700Y769767D01*
X335283Y769600D01*
X335867Y769683D01*
X336367Y769933D01*
X336700Y770267D01*
G01X340800Y774600D02*
Y769600D01*
G01X339633Y772933D02*
X341967D01*
G01X346400D02*
Y769600D01*
G01Y774267D02*
X346233Y774350D01*
Y774517D01*
X346400Y774600D01*
X346567Y774517D01*
Y774350D01*
X346400Y774267D01*
G01X352000Y769600D02*
X351500Y769683D01*
X351000Y770017D01*
X350667Y770600D01*
X350500Y771267D01*
X350667Y771933D01*
X351000Y772517D01*
X351500Y772850D01*
X352000Y772933D01*
X352500Y772850D01*
X353000Y772517D01*
X353333Y771933D01*
X353417Y771267D01*
X353333Y770600D01*
X353000Y770017D01*
X352500Y769683D01*
X352000Y769600D01*
G01X356183D02*
Y772933D01*
G01Y772100D02*
X356517Y772517D01*
X357017Y772850D01*
X357683Y772933D01*
X358267Y772850D01*
X358767Y772517D01*
X359017Y771933D01*
Y769600D01*
G01X368300D02*
Y773850D01*
X368467Y774267D01*
X368800Y774517D01*
X369300Y774600D01*
X369800Y774433D01*
X370050Y774017D01*
G01X369050Y772600D02*
X367383D01*
G01X374400Y769600D02*
X373900Y769683D01*
X373400Y770017D01*
X373067Y770600D01*
X372900Y771267D01*
X373067Y771933D01*
X373400Y772517D01*
X373900Y772850D01*
X374400Y772933D01*
X374900Y772850D01*
X375400Y772517D01*
X375733Y771933D01*
X375817Y771267D01*
X375733Y770600D01*
X375400Y770017D01*
X374900Y769683D01*
X374400Y769600D01*
G01X378833D02*
Y772933D01*
G01Y772267D02*
X379250Y772600D01*
X379667Y772850D01*
X380250Y772933D01*
X380667Y772850D01*
X381167Y772600D01*
G01X389533Y769600D02*
Y774600D01*
X391617D01*
X392283Y774350D01*
X392700Y774017D01*
X392867Y773350D01*
X392700Y772683D01*
X392200Y772267D01*
X391617Y772017D01*
X389533D01*
G01X391617D02*
X392867Y769600D01*
G01X396800Y772933D02*
Y769600D01*
G01Y774267D02*
X396633Y774350D01*
Y774517D01*
X396800Y774600D01*
X396967Y774517D01*
Y774350D01*
X396800Y774267D01*
G01X401233Y768350D02*
X401817Y768017D01*
X402483Y767933D01*
X403067Y768017D01*
X403567Y768433D01*
X403900Y769017D01*
Y772933D01*
G01Y772267D02*
X403567Y772600D01*
X403067Y772850D01*
X402483Y772933D01*
X401817Y772767D01*
X401400Y772433D01*
X401067Y771850D01*
X400900Y771267D01*
X400983Y770767D01*
X401317Y770183D01*
X401817Y769767D01*
X402483Y769600D01*
X402983Y769683D01*
X403567Y770017D01*
X403900Y770350D01*
G01X408000Y772933D02*
Y769600D01*
G01Y774267D02*
X407833Y774350D01*
Y774517D01*
X408000Y774600D01*
X408167Y774517D01*
Y774350D01*
X408000Y774267D01*
G01X415100Y774600D02*
Y769600D01*
G01Y770350D02*
X414767Y769933D01*
X414267Y769683D01*
X413683Y769600D01*
X413017Y769767D01*
X412517Y770183D01*
X412183Y770683D01*
X412100Y771267D01*
X412183Y771850D01*
X412517Y772350D01*
X413017Y772767D01*
X413683Y772933D01*
X414267Y772850D01*
X414683Y772683D01*
X415100Y772350D01*
G01X423133Y769600D02*
Y774600D01*
X425133D01*
X425800Y774350D01*
X426300Y773767D01*
X426467Y773100D01*
X426300Y772433D01*
X425883Y771933D01*
X425133Y771683D01*
X423133D01*
G01X429233Y769600D02*
Y772933D01*
G01Y772267D02*
X429650Y772600D01*
X430067Y772850D01*
X430650Y772933D01*
X431067Y772850D01*
X431567Y772600D01*
G01X436000Y772933D02*
Y769600D01*
G01Y774267D02*
X435833Y774350D01*
Y774517D01*
X436000Y774600D01*
X436167Y774517D01*
Y774350D01*
X436000Y774267D01*
G01X440183Y769600D02*
Y772933D01*
G01Y772100D02*
X440517Y772517D01*
X441017Y772850D01*
X441683Y772933D01*
X442267Y772850D01*
X442767Y772517D01*
X443017Y771933D01*
Y769600D01*
G01X447200Y774600D02*
Y769600D01*
G01X446033Y772933D02*
X448367D01*
G01X451550Y771850D02*
X454217D01*
X453967Y772433D01*
X453550Y772767D01*
X452967Y772933D01*
X452383Y772850D01*
X451883Y772600D01*
X451550Y772017D01*
X451383Y771517D01*
Y771017D01*
X451550Y770517D01*
X451967Y770017D01*
X452467Y769683D01*
X453050Y769600D01*
X453633Y769767D01*
X454217Y770267D01*
G01X459900Y774600D02*
Y769600D01*
G01Y770350D02*
X459567Y769933D01*
X459067Y769683D01*
X458483Y769600D01*
X457817Y769767D01*
X457317Y770183D01*
X456983Y770683D01*
X456900Y771267D01*
X456983Y771850D01*
X457317Y772350D01*
X457817Y772767D01*
X458483Y772933D01*
X459067Y772850D01*
X459483Y772683D01*
X459900Y772350D01*
G01X470267Y772267D02*
X470600Y772517D01*
X470850Y772933D01*
X471017Y773517D01*
X470850Y774017D01*
X470517Y774350D01*
X469933Y774600D01*
X467683D01*
Y769600D01*
X470433D01*
X471017Y769933D01*
X471350Y770433D01*
X471517Y771017D01*
X471350Y771600D01*
X470850Y772100D01*
X470267Y772267D01*
X467683D01*
G01X475200Y769600D02*
X474700Y769683D01*
X474200Y770017D01*
X473867Y770600D01*
X473700Y771267D01*
X473867Y771933D01*
X474200Y772517D01*
X474700Y772850D01*
X475200Y772933D01*
X475700Y772850D01*
X476200Y772517D01*
X476533Y771933D01*
X476617Y771267D01*
X476533Y770600D01*
X476200Y770017D01*
X475700Y769683D01*
X475200Y769600D01*
G01X482300D02*
Y772933D01*
G01Y772350D02*
X481967Y772683D01*
X481467Y772850D01*
X480883Y772933D01*
X480300Y772767D01*
X479800Y772433D01*
X479467Y771933D01*
X479300Y771267D01*
X479467Y770600D01*
X479800Y770100D01*
X480300Y769767D01*
X480883Y769600D01*
X481467Y769683D01*
X481967Y769933D01*
X482300Y770267D01*
G01X485233Y769600D02*
Y772933D01*
G01Y772267D02*
X485650Y772600D01*
X486067Y772850D01*
X486650Y772933D01*
X487067Y772850D01*
X487567Y772600D01*
G01X493500Y774600D02*
Y769600D01*
G01Y770350D02*
X493167Y769933D01*
X492667Y769683D01*
X492083Y769600D01*
X491417Y769767D01*
X490917Y770183D01*
X490583Y770683D01*
X490500Y771267D01*
X490583Y771850D01*
X490917Y772350D01*
X491417Y772767D01*
X492083Y772933D01*
X492667Y772850D01*
X493083Y772683D01*
X493500Y772350D01*
G01X496350Y770183D02*
X496767Y769850D01*
X497350Y769600D01*
X497850D01*
X498350Y769767D01*
X498683Y770017D01*
X498850Y770350D01*
X498767Y770850D01*
X498433Y771100D01*
X496933Y771600D01*
X496600Y772183D01*
X496767Y772600D01*
X497100Y772850D01*
X497600Y772933D01*
X498100Y772850D01*
X498600Y772600D01*
G01X57000Y802500D02*
X59000D01*
G01X58000D02*
Y797500D01*
G01X57000D02*
X59000D01*
G01X63100D02*
Y801750D01*
X63267Y802167D01*
X63600Y802417D01*
X64100Y802500D01*
X64600Y802333D01*
X64850Y801917D01*
G01X63850Y800500D02*
X62183D01*
G01X74800Y802500D02*
Y797500D01*
G01X73633Y800833D02*
X75967D01*
G01X78983Y797500D02*
Y802500D01*
G01Y800083D02*
X79400Y800500D01*
X79817Y800750D01*
X80483Y800833D01*
X80983Y800750D01*
X81567Y800417D01*
X81817Y799917D01*
Y797500D01*
G01X84750Y799750D02*
X87417D01*
X87167Y800333D01*
X86750Y800667D01*
X86167Y800833D01*
X85583Y800750D01*
X85083Y800500D01*
X84750Y799917D01*
X84583Y799417D01*
Y798917D01*
X84750Y798417D01*
X85167Y797917D01*
X85667Y797583D01*
X86250Y797500D01*
X86833Y797667D01*
X87417Y798167D01*
G01X98533Y800417D02*
X97950Y800750D01*
X97450Y800833D01*
X96783Y800667D01*
X96283Y800333D01*
X95950Y799750D01*
X95867Y799167D01*
X95950Y798583D01*
X96283Y798083D01*
X96783Y797667D01*
X97450Y797500D01*
X98033Y797667D01*
X98533Y798000D01*
G01X101633Y797500D02*
Y800833D01*
G01Y800167D02*
X102050Y800500D01*
X102467Y800750D01*
X103050Y800833D01*
X103467Y800750D01*
X103967Y800500D01*
G01X108400Y800833D02*
Y797500D01*
G01Y802167D02*
X108233Y802250D01*
Y802417D01*
X108400Y802500D01*
X108567Y802417D01*
Y802250D01*
X108400Y802167D01*
G01X114000Y802500D02*
Y797500D01*
G01X112833Y800833D02*
X115167D01*
G01X118350Y799750D02*
X121017D01*
X120767Y800333D01*
X120350Y800667D01*
X119767Y800833D01*
X119183Y800750D01*
X118683Y800500D01*
X118350Y799917D01*
X118183Y799417D01*
Y798917D01*
X118350Y798417D01*
X118767Y797917D01*
X119267Y797583D01*
X119850Y797500D01*
X120433Y797667D01*
X121017Y798167D01*
G01X124033Y797500D02*
Y800833D01*
G01Y800167D02*
X124450Y800500D01*
X124867Y800750D01*
X125450Y800833D01*
X125867Y800750D01*
X126367Y800500D01*
G01X130800Y800833D02*
Y797500D01*
G01Y802167D02*
X130633Y802250D01*
Y802417D01*
X130800Y802500D01*
X130967Y802417D01*
Y802250D01*
X130800Y802167D01*
G01X137900Y797500D02*
Y800833D01*
G01Y800250D02*
X137567Y800583D01*
X137067Y800750D01*
X136483Y800833D01*
X135900Y800667D01*
X135400Y800333D01*
X135067Y799833D01*
X134900Y799167D01*
X135067Y798500D01*
X135400Y798000D01*
X135900Y797667D01*
X136483Y797500D01*
X137067Y797583D01*
X137567Y797833D01*
X137900Y798167D01*
G01X147600Y800833D02*
Y797500D01*
G01Y802167D02*
X147433Y802250D01*
Y802417D01*
X147600Y802500D01*
X147767Y802417D01*
Y802250D01*
X147600Y802167D01*
G01X151950Y798083D02*
X152367Y797750D01*
X152950Y797500D01*
X153450D01*
X153950Y797667D01*
X154283Y797917D01*
X154450Y798250D01*
X154367Y798750D01*
X154033Y799000D01*
X152533Y799500D01*
X152200Y800083D01*
X152367Y800500D01*
X152700Y800750D01*
X153200Y800833D01*
X153700Y800750D01*
X154200Y800500D01*
G01X162983Y797500D02*
Y800833D01*
G01Y800000D02*
X163317Y800417D01*
X163817Y800750D01*
X164483Y800833D01*
X165067Y800750D01*
X165567Y800417D01*
X165817Y799833D01*
Y797500D01*
G01X170000D02*
X169500Y797583D01*
X169000Y797917D01*
X168667Y798500D01*
X168500Y799167D01*
X168667Y799833D01*
X169000Y800417D01*
X169500Y800750D01*
X170000Y800833D01*
X170500Y800750D01*
X171000Y800417D01*
X171333Y799833D01*
X171417Y799167D01*
X171333Y798500D01*
X171000Y797917D01*
X170500Y797583D01*
X170000Y797500D01*
G01X175600Y802500D02*
Y797500D01*
G01X174433Y800833D02*
X176767D01*
G01X185550Y798083D02*
X185967Y797750D01*
X186550Y797500D01*
X187050D01*
X187550Y797667D01*
X187883Y797917D01*
X188050Y798250D01*
X187967Y798750D01*
X187633Y799000D01*
X186133Y799500D01*
X185800Y800083D01*
X185967Y800500D01*
X186300Y800750D01*
X186800Y800833D01*
X187300Y800750D01*
X187800Y800500D01*
G01X190900Y795833D02*
Y800833D01*
G01Y800083D02*
X191317Y800500D01*
X191733Y800750D01*
X192400Y800833D01*
X192983Y800750D01*
X193567Y800333D01*
X193817Y799750D01*
X193900Y799167D01*
X193817Y798583D01*
X193567Y798000D01*
X193067Y797667D01*
X192400Y797500D01*
X191817Y797583D01*
X191233Y797833D01*
X190900Y798167D01*
G01X196750Y799750D02*
X199417D01*
X199167Y800333D01*
X198750Y800667D01*
X198167Y800833D01*
X197583Y800750D01*
X197083Y800500D01*
X196750Y799917D01*
X196583Y799417D01*
Y798917D01*
X196750Y798417D01*
X197167Y797917D01*
X197667Y797583D01*
X198250Y797500D01*
X198833Y797667D01*
X199417Y798167D01*
G01X204933Y800417D02*
X204350Y800750D01*
X203850Y800833D01*
X203183Y800667D01*
X202683Y800333D01*
X202350Y799750D01*
X202267Y799167D01*
X202350Y798583D01*
X202683Y798083D01*
X203183Y797667D01*
X203850Y797500D01*
X204433Y797667D01*
X204933Y798000D01*
G01X209200Y800833D02*
Y797500D01*
G01Y802167D02*
X209033Y802250D01*
Y802417D01*
X209200Y802500D01*
X209367Y802417D01*
Y802250D01*
X209200Y802167D01*
G01X214300Y797500D02*
Y801750D01*
X214467Y802167D01*
X214800Y802417D01*
X215300Y802500D01*
X215800Y802333D01*
X216050Y801917D01*
G01X215050Y800500D02*
X213383D01*
G01X220400Y800833D02*
Y797500D01*
G01Y802167D02*
X220233Y802250D01*
Y802417D01*
X220400Y802500D01*
X220567Y802417D01*
Y802250D01*
X220400Y802167D01*
G01X224750Y799750D02*
X227417D01*
X227167Y800333D01*
X226750Y800667D01*
X226167Y800833D01*
X225583Y800750D01*
X225083Y800500D01*
X224750Y799917D01*
X224583Y799417D01*
Y798917D01*
X224750Y798417D01*
X225167Y797917D01*
X225667Y797583D01*
X226250Y797500D01*
X226833Y797667D01*
X227417Y798167D01*
G01X233100Y802500D02*
Y797500D01*
G01Y798250D02*
X232767Y797833D01*
X232267Y797583D01*
X231683Y797500D01*
X231017Y797667D01*
X230517Y798083D01*
X230183Y798583D01*
X230100Y799167D01*
X230183Y799750D01*
X230517Y800250D01*
X231017Y800667D01*
X231683Y800833D01*
X232267Y800750D01*
X232683Y800583D01*
X233100Y800250D01*
G01X242800Y800833D02*
Y797500D01*
G01Y802167D02*
X242633Y802250D01*
Y802417D01*
X242800Y802500D01*
X242967Y802417D01*
Y802250D01*
X242800Y802167D01*
G01X246983Y797500D02*
Y800833D01*
G01Y800000D02*
X247317Y800417D01*
X247817Y800750D01*
X248483Y800833D01*
X249067Y800750D01*
X249567Y800417D01*
X249817Y799833D01*
Y797500D01*
G01X259600Y802500D02*
Y797500D01*
G01X258433Y800833D02*
X260767D01*
G01X263783Y797500D02*
Y802500D01*
G01Y800083D02*
X264200Y800500D01*
X264617Y800750D01*
X265283Y800833D01*
X265783Y800750D01*
X266367Y800417D01*
X266617Y799917D01*
Y797500D01*
G01X269550Y799750D02*
X272217D01*
X271967Y800333D01*
X271550Y800667D01*
X270967Y800833D01*
X270383Y800750D01*
X269883Y800500D01*
X269550Y799917D01*
X269383Y799417D01*
Y798917D01*
X269550Y798417D01*
X269967Y797917D01*
X270467Y797583D01*
X271050Y797500D01*
X271633Y797667D01*
X272217Y798167D01*
G01X282000Y802500D02*
Y797500D01*
G01X280833Y800833D02*
X283167D01*
G01X289100Y797500D02*
Y800833D01*
G01Y800250D02*
X288767Y800583D01*
X288267Y800750D01*
X287683Y800833D01*
X287100Y800667D01*
X286600Y800333D01*
X286267Y799833D01*
X286100Y799167D01*
X286267Y798500D01*
X286600Y798000D01*
X287100Y797667D01*
X287683Y797500D01*
X288267Y797583D01*
X288767Y797833D01*
X289100Y798167D01*
G01X291700Y797500D02*
Y802500D01*
G01Y800000D02*
X292117Y800500D01*
X292617Y800750D01*
X293117Y800833D01*
X293867Y800667D01*
X294367Y800333D01*
X294700Y799750D01*
Y799083D01*
X294533Y798417D01*
X294200Y797917D01*
X293617Y797583D01*
X293117Y797500D01*
X292617Y797583D01*
X292117Y797833D01*
X291700Y798250D01*
G01X298800Y797500D02*
Y802500D01*
G01X303150Y799750D02*
X305817D01*
X305567Y800333D01*
X305150Y800667D01*
X304567Y800833D01*
X303983Y800750D01*
X303483Y800500D01*
X303150Y799917D01*
X302983Y799417D01*
Y798917D01*
X303150Y798417D01*
X303567Y797917D01*
X304067Y797583D01*
X304650Y797500D01*
X305233Y797667D01*
X305817Y798167D01*
G01X310000Y797333D02*
X309833Y797417D01*
Y797583D01*
X310000Y797667D01*
X310167Y797583D01*
Y797417D01*
X310000Y797333D01*
G01Y799583D02*
X309833Y799667D01*
Y799833D01*
X310000Y799917D01*
X310167Y799833D01*
Y799667D01*
X310000Y799583D01*
G01X67000Y779433D02*
X66833Y779517D01*
Y779683D01*
X67000Y779767D01*
X67167Y779683D01*
Y779517D01*
X67000Y779433D01*
G01Y786333D02*
X66833Y786417D01*
Y786583D01*
X67000Y786667D01*
X67167Y786583D01*
Y786417D01*
X67000Y786333D01*
G01X71000Y783600D02*
X73000D01*
G01X72000D02*
Y778600D01*
G01X71000D02*
X73000D01*
G01X75933D02*
Y783600D01*
X77933D01*
X78600Y783350D01*
X79100Y782767D01*
X79267Y782100D01*
X79100Y781433D01*
X78683Y780933D01*
X77933Y780683D01*
X75933D01*
G01X85033Y783183D02*
X84533Y783433D01*
X83950Y783600D01*
X83283D01*
X82533Y783350D01*
X81950Y782933D01*
X81533Y782433D01*
X81200Y781600D01*
X81117Y780850D01*
X81283Y780100D01*
X81533Y779600D01*
X82033Y779100D01*
X82617Y778767D01*
X83200Y778600D01*
X83783D01*
X84367Y778767D01*
X84867Y779017D01*
X85283Y779350D01*
G01X87717Y780267D02*
X89883D01*
G01X92817Y780683D02*
X93400Y781267D01*
X93900Y781600D01*
X94567Y781767D01*
X95150Y781600D01*
X95567Y781267D01*
X95900Y780767D01*
X95983Y780183D01*
X95900Y779683D01*
X95567Y779183D01*
X95067Y778767D01*
X94483Y778600D01*
X93817Y778767D01*
X93233Y779267D01*
X92900Y780017D01*
X92817Y780850D01*
X92983Y781933D01*
X93233Y782517D01*
X93650Y783100D01*
X94233Y783517D01*
X94817Y783600D01*
X95400Y783433D01*
X95817Y783017D01*
G01X100000Y783600D02*
X99333Y783433D01*
X98833Y783017D01*
X98500Y782517D01*
X98250Y781850D01*
X98167Y781100D01*
X98250Y780350D01*
X98500Y779683D01*
X98833Y779183D01*
X99333Y778767D01*
X100000Y778600D01*
X100667Y778767D01*
X101167Y779183D01*
X101500Y779683D01*
X101750Y780350D01*
X101833Y781100D01*
X101750Y781850D01*
X101500Y782517D01*
X101167Y783017D01*
X100667Y783433D01*
X100000Y783600D01*
G01X105600Y778600D02*
Y783600D01*
X104600Y782600D01*
G01Y778600D02*
X106600D01*
G01X111200D02*
Y783600D01*
X110200Y782600D01*
G01Y778600D02*
X112200D01*
G01X122900Y781100D02*
X124567D01*
Y779600D01*
X124067Y779100D01*
X123483Y778767D01*
X122650Y778600D01*
X121817Y778767D01*
X121233Y779100D01*
X120733Y779600D01*
X120400Y780183D01*
X120233Y780850D01*
Y781433D01*
X120400Y781933D01*
X120733Y782517D01*
X121233Y783017D01*
X121733Y783350D01*
X122400Y783600D01*
X122983D01*
X123650Y783433D01*
X124150Y783100D01*
G01X126750Y780850D02*
X129417D01*
X129167Y781433D01*
X128750Y781767D01*
X128167Y781933D01*
X127583Y781850D01*
X127083Y781600D01*
X126750Y781017D01*
X126583Y780517D01*
Y780017D01*
X126750Y779517D01*
X127167Y779017D01*
X127667Y778683D01*
X128250Y778600D01*
X128833Y778767D01*
X129417Y779267D01*
G01X132183Y778600D02*
Y781933D01*
G01Y781100D02*
X132517Y781517D01*
X133017Y781850D01*
X133683Y781933D01*
X134267Y781850D01*
X134767Y781517D01*
X135017Y780933D01*
Y778600D01*
G01X137950Y780850D02*
X140617D01*
X140367Y781433D01*
X139950Y781767D01*
X139367Y781933D01*
X138783Y781850D01*
X138283Y781600D01*
X137950Y781017D01*
X137783Y780517D01*
Y780017D01*
X137950Y779517D01*
X138367Y779017D01*
X138867Y778683D01*
X139450Y778600D01*
X140033Y778767D01*
X140617Y779267D01*
G01X143633Y778600D02*
Y781933D01*
G01Y781267D02*
X144050Y781600D01*
X144467Y781850D01*
X145050Y781933D01*
X145467Y781850D01*
X145967Y781600D01*
G01X150400Y781933D02*
Y778600D01*
G01Y783267D02*
X150233Y783350D01*
Y783517D01*
X150400Y783600D01*
X150567Y783517D01*
Y783350D01*
X150400Y783267D01*
G01X157333Y781517D02*
X156750Y781850D01*
X156250Y781933D01*
X155583Y781767D01*
X155083Y781433D01*
X154750Y780850D01*
X154667Y780267D01*
X154750Y779683D01*
X155083Y779183D01*
X155583Y778767D01*
X156250Y778600D01*
X156833Y778767D01*
X157333Y779100D01*
G01X165533Y778600D02*
Y783600D01*
X167533D01*
X168200Y783350D01*
X168700Y782767D01*
X168867Y782100D01*
X168700Y781433D01*
X168283Y780933D01*
X167533Y780683D01*
X165533D01*
G01X171550Y780850D02*
X174217D01*
X173967Y781433D01*
X173550Y781767D01*
X172967Y781933D01*
X172383Y781850D01*
X171883Y781600D01*
X171550Y781017D01*
X171383Y780517D01*
Y780017D01*
X171550Y779517D01*
X171967Y779017D01*
X172467Y778683D01*
X173050Y778600D01*
X173633Y778767D01*
X174217Y779267D01*
G01X177233Y778600D02*
Y781933D01*
G01Y781267D02*
X177650Y781600D01*
X178067Y781850D01*
X178650Y781933D01*
X179067Y781850D01*
X179567Y781600D01*
G01X183500Y778600D02*
Y782850D01*
X183667Y783267D01*
X184000Y783517D01*
X184500Y783600D01*
X185000Y783433D01*
X185250Y783017D01*
G01X184250Y781600D02*
X182583D01*
G01X189600Y778600D02*
X189100Y778683D01*
X188600Y779017D01*
X188267Y779600D01*
X188100Y780267D01*
X188267Y780933D01*
X188600Y781517D01*
X189100Y781850D01*
X189600Y781933D01*
X190100Y781850D01*
X190600Y781517D01*
X190933Y780933D01*
X191017Y780267D01*
X190933Y779600D01*
X190600Y779017D01*
X190100Y778683D01*
X189600Y778600D01*
G01X194033D02*
Y781933D01*
G01Y781267D02*
X194450Y781600D01*
X194867Y781850D01*
X195450Y781933D01*
X195867Y781850D01*
X196367Y781600D01*
G01X198300Y778600D02*
Y781933D01*
G01Y781017D02*
X198550Y781433D01*
X198967Y781767D01*
X199550Y781933D01*
X200133Y781767D01*
X200550Y781433D01*
X200800Y781017D01*
Y778600D01*
G01Y781017D02*
X201050Y781433D01*
X201467Y781767D01*
X202050Y781933D01*
X202633Y781767D01*
X203050Y781433D01*
X203300Y780933D01*
Y778600D01*
G01X207900D02*
Y781933D01*
G01Y781350D02*
X207567Y781683D01*
X207067Y781850D01*
X206483Y781933D01*
X205900Y781767D01*
X205400Y781433D01*
X205067Y780933D01*
X204900Y780267D01*
X205067Y779600D01*
X205400Y779100D01*
X205900Y778767D01*
X206483Y778600D01*
X207067Y778683D01*
X207567Y778933D01*
X207900Y779267D01*
G01X210583Y778600D02*
Y781933D01*
G01Y781100D02*
X210917Y781517D01*
X211417Y781850D01*
X212083Y781933D01*
X212667Y781850D01*
X213167Y781517D01*
X213417Y780933D01*
Y778600D01*
G01X218933Y781517D02*
X218350Y781850D01*
X217850Y781933D01*
X217183Y781767D01*
X216683Y781433D01*
X216350Y780850D01*
X216267Y780267D01*
X216350Y779683D01*
X216683Y779183D01*
X217183Y778767D01*
X217850Y778600D01*
X218433Y778767D01*
X218933Y779100D01*
G01X221950Y780850D02*
X224617D01*
X224367Y781433D01*
X223950Y781767D01*
X223367Y781933D01*
X222783Y781850D01*
X222283Y781600D01*
X221950Y781017D01*
X221783Y780517D01*
Y780017D01*
X221950Y779517D01*
X222367Y779017D01*
X222867Y778683D01*
X223450Y778600D01*
X224033Y778767D01*
X224617Y779267D01*
G01X232650D02*
X233317Y778850D01*
X234067Y778600D01*
X234733D01*
X235400Y778850D01*
X235900Y779267D01*
X236150Y779850D01*
X235983Y780433D01*
X235567Y780933D01*
X234817Y781267D01*
X233817Y781433D01*
X233233Y781767D01*
X232983Y782350D01*
X233150Y782933D01*
X233567Y783350D01*
X234150Y783600D01*
X234733D01*
X235317Y783433D01*
X235817Y783017D01*
G01X238500Y776933D02*
Y781933D01*
G01Y781183D02*
X238917Y781600D01*
X239333Y781850D01*
X240000Y781933D01*
X240583Y781850D01*
X241167Y781433D01*
X241417Y780850D01*
X241500Y780267D01*
X241417Y779683D01*
X241167Y779100D01*
X240667Y778767D01*
X240000Y778600D01*
X239417Y778683D01*
X238833Y778933D01*
X238500Y779267D01*
G01X244350Y780850D02*
X247017D01*
X246767Y781433D01*
X246350Y781767D01*
X245767Y781933D01*
X245183Y781850D01*
X244683Y781600D01*
X244350Y781017D01*
X244183Y780517D01*
Y780017D01*
X244350Y779517D01*
X244767Y779017D01*
X245267Y778683D01*
X245850Y778600D01*
X246433Y778767D01*
X247017Y779267D01*
G01X252533Y781517D02*
X251950Y781850D01*
X251450Y781933D01*
X250783Y781767D01*
X250283Y781433D01*
X249950Y780850D01*
X249867Y780267D01*
X249950Y779683D01*
X250283Y779183D01*
X250783Y778767D01*
X251450Y778600D01*
X252033Y778767D01*
X252533Y779100D01*
G01X256800Y781933D02*
Y778600D01*
G01Y783267D02*
X256633Y783350D01*
Y783517D01*
X256800Y783600D01*
X256967Y783517D01*
Y783350D01*
X256800Y783267D01*
G01X261900Y778600D02*
Y782850D01*
X262067Y783267D01*
X262400Y783517D01*
X262900Y783600D01*
X263400Y783433D01*
X263650Y783017D01*
G01X262650Y781600D02*
X260983D01*
G01X268000Y781933D02*
Y778600D01*
G01Y783267D02*
X267833Y783350D01*
Y783517D01*
X268000Y783600D01*
X268167Y783517D01*
Y783350D01*
X268000Y783267D01*
G01X274933Y781517D02*
X274350Y781850D01*
X273850Y781933D01*
X273183Y781767D01*
X272683Y781433D01*
X272350Y780850D01*
X272267Y780267D01*
X272350Y779683D01*
X272683Y779183D01*
X273183Y778767D01*
X273850Y778600D01*
X274433Y778767D01*
X274933Y779100D01*
G01X280700Y778600D02*
Y781933D01*
G01Y781350D02*
X280367Y781683D01*
X279867Y781850D01*
X279283Y781933D01*
X278700Y781767D01*
X278200Y781433D01*
X277867Y780933D01*
X277700Y780267D01*
X277867Y779600D01*
X278200Y779100D01*
X278700Y778767D01*
X279283Y778600D01*
X279867Y778683D01*
X280367Y778933D01*
X280700Y779267D01*
G01X284800Y783600D02*
Y778600D01*
G01X283633Y781933D02*
X285967D01*
G01X290400D02*
Y778600D01*
G01Y783267D02*
X290233Y783350D01*
Y783517D01*
X290400Y783600D01*
X290567Y783517D01*
Y783350D01*
X290400Y783267D01*
G01X296000Y778600D02*
X295500Y778683D01*
X295000Y779017D01*
X294667Y779600D01*
X294500Y780267D01*
X294667Y780933D01*
X295000Y781517D01*
X295500Y781850D01*
X296000Y781933D01*
X296500Y781850D01*
X297000Y781517D01*
X297333Y780933D01*
X297417Y780267D01*
X297333Y779600D01*
X297000Y779017D01*
X296500Y778683D01*
X296000Y778600D01*
G01X300183D02*
Y781933D01*
G01Y781100D02*
X300517Y781517D01*
X301017Y781850D01*
X301683Y781933D01*
X302267Y781850D01*
X302767Y781517D01*
X303017Y780933D01*
Y778600D01*
G01X312300D02*
Y782850D01*
X312467Y783267D01*
X312800Y783517D01*
X313300Y783600D01*
X313800Y783433D01*
X314050Y783017D01*
G01X313050Y781600D02*
X311383D01*
G01X318400Y778600D02*
X317900Y778683D01*
X317400Y779017D01*
X317067Y779600D01*
X316900Y780267D01*
X317067Y780933D01*
X317400Y781517D01*
X317900Y781850D01*
X318400Y781933D01*
X318900Y781850D01*
X319400Y781517D01*
X319733Y780933D01*
X319817Y780267D01*
X319733Y779600D01*
X319400Y779017D01*
X318900Y778683D01*
X318400Y778600D01*
G01X322833D02*
Y781933D01*
G01Y781267D02*
X323250Y781600D01*
X323667Y781850D01*
X324250Y781933D01*
X324667Y781850D01*
X325167Y781600D01*
G01X333533Y778600D02*
Y783600D01*
X335533D01*
X336200Y783350D01*
X336700Y782767D01*
X336867Y782100D01*
X336700Y781433D01*
X336283Y780933D01*
X335533Y780683D01*
X333533D01*
G01X339633Y778600D02*
Y781933D01*
G01Y781267D02*
X340050Y781600D01*
X340467Y781850D01*
X341050Y781933D01*
X341467Y781850D01*
X341967Y781600D01*
G01X346400Y781933D02*
Y778600D01*
G01Y783267D02*
X346233Y783350D01*
Y783517D01*
X346400Y783600D01*
X346567Y783517D01*
Y783350D01*
X346400Y783267D01*
G01X350583Y778600D02*
Y781933D01*
G01Y781100D02*
X350917Y781517D01*
X351417Y781850D01*
X352083Y781933D01*
X352667Y781850D01*
X353167Y781517D01*
X353417Y780933D01*
Y778600D01*
G01X357600Y783600D02*
Y778600D01*
G01X356433Y781933D02*
X358767D01*
G01X361950Y780850D02*
X364617D01*
X364367Y781433D01*
X363950Y781767D01*
X363367Y781933D01*
X362783Y781850D01*
X362283Y781600D01*
X361950Y781017D01*
X361783Y780517D01*
Y780017D01*
X361950Y779517D01*
X362367Y779017D01*
X362867Y778683D01*
X363450Y778600D01*
X364033Y778767D01*
X364617Y779267D01*
G01X370300Y783600D02*
Y778600D01*
G01Y779350D02*
X369967Y778933D01*
X369467Y778683D01*
X368883Y778600D01*
X368217Y778767D01*
X367717Y779183D01*
X367383Y779683D01*
X367300Y780267D01*
X367383Y780850D01*
X367717Y781350D01*
X368217Y781767D01*
X368883Y781933D01*
X369467Y781850D01*
X369883Y781683D01*
X370300Y781350D01*
G01X380667Y781267D02*
X381000Y781517D01*
X381250Y781933D01*
X381417Y782517D01*
X381250Y783017D01*
X380917Y783350D01*
X380333Y783600D01*
X378083D01*
Y778600D01*
X380833D01*
X381417Y778933D01*
X381750Y779433D01*
X381917Y780017D01*
X381750Y780600D01*
X381250Y781100D01*
X380667Y781267D01*
X378083D01*
G01X385600Y778600D02*
X385100Y778683D01*
X384600Y779017D01*
X384267Y779600D01*
X384100Y780267D01*
X384267Y780933D01*
X384600Y781517D01*
X385100Y781850D01*
X385600Y781933D01*
X386100Y781850D01*
X386600Y781517D01*
X386933Y780933D01*
X387017Y780267D01*
X386933Y779600D01*
X386600Y779017D01*
X386100Y778683D01*
X385600Y778600D01*
G01X392700D02*
Y781933D01*
G01Y781350D02*
X392367Y781683D01*
X391867Y781850D01*
X391283Y781933D01*
X390700Y781767D01*
X390200Y781433D01*
X389867Y780933D01*
X389700Y780267D01*
X389867Y779600D01*
X390200Y779100D01*
X390700Y778767D01*
X391283Y778600D01*
X391867Y778683D01*
X392367Y778933D01*
X392700Y779267D01*
G01X395633Y778600D02*
Y781933D01*
G01Y781267D02*
X396050Y781600D01*
X396467Y781850D01*
X397050Y781933D01*
X397467Y781850D01*
X397967Y781600D01*
G01X403900Y783600D02*
Y778600D01*
G01Y779350D02*
X403567Y778933D01*
X403067Y778683D01*
X402483Y778600D01*
X401817Y778767D01*
X401317Y779183D01*
X400983Y779683D01*
X400900Y780267D01*
X400983Y780850D01*
X401317Y781350D01*
X401817Y781767D01*
X402483Y781933D01*
X403067Y781850D01*
X403483Y781683D01*
X403900Y781350D01*
G01X406750Y779183D02*
X407167Y778850D01*
X407750Y778600D01*
X408250D01*
X408750Y778767D01*
X409083Y779017D01*
X409250Y779350D01*
X409167Y779850D01*
X408833Y780100D01*
X407333Y780600D01*
X407000Y781183D01*
X407167Y781600D01*
X407500Y781850D01*
X408000Y781933D01*
X408500Y781850D01*
X409000Y781600D01*
G01X71000Y791500D02*
X73000D01*
G01X72000D02*
Y786500D01*
G01X71000D02*
X73000D01*
G01X75933D02*
Y791500D01*
X77933D01*
X78600Y791250D01*
X79100Y790667D01*
X79267Y790000D01*
X79100Y789333D01*
X78683Y788833D01*
X77933Y788583D01*
X75933D01*
G01X85033Y791083D02*
X84533Y791333D01*
X83950Y791500D01*
X83283D01*
X82533Y791250D01*
X81950Y790833D01*
X81533Y790333D01*
X81200Y789500D01*
X81117Y788750D01*
X81283Y788000D01*
X81533Y787500D01*
X82033Y787000D01*
X82617Y786667D01*
X83200Y786500D01*
X83783D01*
X84367Y786667D01*
X84867Y786917D01*
X85283Y787250D01*
G01X87717Y788167D02*
X89883D01*
G01X92317Y786500D02*
X94400Y791500D01*
X96483Y786500D01*
G01X95733Y788250D02*
X93067D01*
G01X98917Y788167D02*
X101083D01*
G01X104017Y788583D02*
X104600Y789167D01*
X105100Y789500D01*
X105767Y789667D01*
X106350Y789500D01*
X106767Y789167D01*
X107100Y788667D01*
X107183Y788083D01*
X107100Y787583D01*
X106767Y787083D01*
X106267Y786667D01*
X105683Y786500D01*
X105017Y786667D01*
X104433Y787167D01*
X104100Y787917D01*
X104017Y788750D01*
X104183Y789833D01*
X104433Y790417D01*
X104850Y791000D01*
X105433Y791417D01*
X106017Y791500D01*
X106600Y791333D01*
X107017Y790917D01*
G01X111200Y791500D02*
X110533Y791333D01*
X110033Y790917D01*
X109700Y790417D01*
X109450Y789750D01*
X109367Y789000D01*
X109450Y788250D01*
X109700Y787583D01*
X110033Y787083D01*
X110533Y786667D01*
X111200Y786500D01*
X111867Y786667D01*
X112367Y787083D01*
X112700Y787583D01*
X112950Y788250D01*
X113033Y789000D01*
X112950Y789750D01*
X112700Y790417D01*
X112367Y790917D01*
X111867Y791333D01*
X111200Y791500D01*
G01X116800D02*
X116133Y791333D01*
X115633Y790917D01*
X115300Y790417D01*
X115050Y789750D01*
X114967Y789000D01*
X115050Y788250D01*
X115300Y787583D01*
X115633Y787083D01*
X116133Y786667D01*
X116800Y786500D01*
X117467Y786667D01*
X117967Y787083D01*
X118300Y787583D01*
X118550Y788250D01*
X118633Y789000D01*
X118550Y789750D01*
X118300Y790417D01*
X117967Y790917D01*
X117467Y791333D01*
X116800Y791500D01*
G01X125917Y786500D02*
X128000Y791500D01*
X130083Y786500D01*
G01X129333Y788250D02*
X126667D01*
G01X134933Y789417D02*
X134350Y789750D01*
X133850Y789833D01*
X133183Y789667D01*
X132683Y789333D01*
X132350Y788750D01*
X132267Y788167D01*
X132350Y787583D01*
X132683Y787083D01*
X133183Y786667D01*
X133850Y786500D01*
X134433Y786667D01*
X134933Y787000D01*
G01X140533Y789417D02*
X139950Y789750D01*
X139450Y789833D01*
X138783Y789667D01*
X138283Y789333D01*
X137950Y788750D01*
X137867Y788167D01*
X137950Y787583D01*
X138283Y787083D01*
X138783Y786667D01*
X139450Y786500D01*
X140033Y786667D01*
X140533Y787000D01*
G01X143550Y788750D02*
X146217D01*
X145967Y789333D01*
X145550Y789667D01*
X144967Y789833D01*
X144383Y789750D01*
X143883Y789500D01*
X143550Y788917D01*
X143383Y788417D01*
Y787917D01*
X143550Y787417D01*
X143967Y786917D01*
X144467Y786583D01*
X145050Y786500D01*
X145633Y786667D01*
X146217Y787167D01*
G01X148900Y784833D02*
Y789833D01*
G01Y789083D02*
X149317Y789500D01*
X149733Y789750D01*
X150400Y789833D01*
X150983Y789750D01*
X151567Y789333D01*
X151817Y788750D01*
X151900Y788167D01*
X151817Y787583D01*
X151567Y787000D01*
X151067Y786667D01*
X150400Y786500D01*
X149817Y786583D01*
X149233Y786833D01*
X148900Y787167D01*
G01X156000Y791500D02*
Y786500D01*
G01X154833Y789833D02*
X157167D01*
G01X163100Y786500D02*
Y789833D01*
G01Y789250D02*
X162767Y789583D01*
X162267Y789750D01*
X161683Y789833D01*
X161100Y789667D01*
X160600Y789333D01*
X160267Y788833D01*
X160100Y788167D01*
X160267Y787500D01*
X160600Y787000D01*
X161100Y786667D01*
X161683Y786500D01*
X162267Y786583D01*
X162767Y786833D01*
X163100Y787167D01*
G01X165700Y786500D02*
Y791500D01*
G01Y789000D02*
X166117Y789500D01*
X166617Y789750D01*
X167117Y789833D01*
X167867Y789667D01*
X168367Y789333D01*
X168700Y788750D01*
Y788083D01*
X168533Y787417D01*
X168200Y786917D01*
X167617Y786583D01*
X167117Y786500D01*
X166617Y786583D01*
X166117Y786833D01*
X165700Y787250D01*
G01X172800Y789833D02*
Y786500D01*
G01Y791167D02*
X172633Y791250D01*
Y791417D01*
X172800Y791500D01*
X172967Y791417D01*
Y791250D01*
X172800Y791167D01*
G01X178400Y786500D02*
Y791500D01*
G01X184000Y789833D02*
Y786500D01*
G01Y791167D02*
X183833Y791250D01*
Y791417D01*
X184000Y791500D01*
X184167Y791417D01*
Y791250D01*
X184000Y791167D01*
G01X189600Y791500D02*
Y786500D01*
G01X188433Y789833D02*
X190767D01*
G01X193450Y785000D02*
X193950Y784833D01*
X194617Y785000D01*
X195033Y785333D01*
X195367Y785750D01*
X195867Y787083D01*
X196950Y789833D01*
G01X194283D02*
X195867Y787083D01*
G01X206400Y786500D02*
X205900Y786583D01*
X205400Y786917D01*
X205067Y787500D01*
X204900Y788167D01*
X205067Y788833D01*
X205400Y789417D01*
X205900Y789750D01*
X206400Y789833D01*
X206900Y789750D01*
X207400Y789417D01*
X207733Y788833D01*
X207817Y788167D01*
X207733Y787500D01*
X207400Y786917D01*
X206900Y786583D01*
X206400Y786500D01*
G01X211500D02*
Y790750D01*
X211667Y791167D01*
X212000Y791417D01*
X212500Y791500D01*
X213000Y791333D01*
X213250Y790917D01*
G01X212250Y789500D02*
X210583D01*
G01X221533Y786500D02*
Y791500D01*
X223533D01*
X224200Y791250D01*
X224700Y790667D01*
X224867Y790000D01*
X224700Y789333D01*
X224283Y788833D01*
X223533Y788583D01*
X221533D01*
G01X227633Y786500D02*
Y789833D01*
G01Y789167D02*
X228050Y789500D01*
X228467Y789750D01*
X229050Y789833D01*
X229467Y789750D01*
X229967Y789500D01*
G01X234400Y789833D02*
Y786500D01*
G01Y791167D02*
X234233Y791250D01*
Y791417D01*
X234400Y791500D01*
X234567Y791417D01*
Y791250D01*
X234400Y791167D01*
G01X238583Y786500D02*
Y789833D01*
G01Y789000D02*
X238917Y789417D01*
X239417Y789750D01*
X240083Y789833D01*
X240667Y789750D01*
X241167Y789417D01*
X241417Y788833D01*
Y786500D01*
G01X245600Y791500D02*
Y786500D01*
G01X244433Y789833D02*
X246767D01*
G01X249950Y788750D02*
X252617D01*
X252367Y789333D01*
X251950Y789667D01*
X251367Y789833D01*
X250783Y789750D01*
X250283Y789500D01*
X249950Y788917D01*
X249783Y788417D01*
Y787917D01*
X249950Y787417D01*
X250367Y786917D01*
X250867Y786583D01*
X251450Y786500D01*
X252033Y786667D01*
X252617Y787167D01*
G01X258300Y791500D02*
Y786500D01*
G01Y787250D02*
X257967Y786833D01*
X257467Y786583D01*
X256883Y786500D01*
X256217Y786667D01*
X255717Y787083D01*
X255383Y787583D01*
X255300Y788167D01*
X255383Y788750D01*
X255717Y789250D01*
X256217Y789667D01*
X256883Y789833D01*
X257467Y789750D01*
X257883Y789583D01*
X258300Y789250D01*
G01X268667Y789167D02*
X269000Y789417D01*
X269250Y789833D01*
X269417Y790417D01*
X269250Y790917D01*
X268917Y791250D01*
X268333Y791500D01*
X266083D01*
Y786500D01*
X268833D01*
X269417Y786833D01*
X269750Y787333D01*
X269917Y787917D01*
X269750Y788500D01*
X269250Y789000D01*
X268667Y789167D01*
X266083D01*
G01X273600Y786500D02*
X273100Y786583D01*
X272600Y786917D01*
X272267Y787500D01*
X272100Y788167D01*
X272267Y788833D01*
X272600Y789417D01*
X273100Y789750D01*
X273600Y789833D01*
X274100Y789750D01*
X274600Y789417D01*
X274933Y788833D01*
X275017Y788167D01*
X274933Y787500D01*
X274600Y786917D01*
X274100Y786583D01*
X273600Y786500D01*
G01X280700D02*
Y789833D01*
G01Y789250D02*
X280367Y789583D01*
X279867Y789750D01*
X279283Y789833D01*
X278700Y789667D01*
X278200Y789333D01*
X277867Y788833D01*
X277700Y788167D01*
X277867Y787500D01*
X278200Y787000D01*
X278700Y786667D01*
X279283Y786500D01*
X279867Y786583D01*
X280367Y786833D01*
X280700Y787167D01*
G01X283633Y786500D02*
Y789833D01*
G01Y789167D02*
X284050Y789500D01*
X284467Y789750D01*
X285050Y789833D01*
X285467Y789750D01*
X285967Y789500D01*
G01X291900Y791500D02*
Y786500D01*
G01Y787250D02*
X291567Y786833D01*
X291067Y786583D01*
X290483Y786500D01*
X289817Y786667D01*
X289317Y787083D01*
X288983Y787583D01*
X288900Y788167D01*
X288983Y788750D01*
X289317Y789250D01*
X289817Y789667D01*
X290483Y789833D01*
X291067Y789750D01*
X291483Y789583D01*
X291900Y789250D01*
G01X294750Y787083D02*
X295167Y786750D01*
X295750Y786500D01*
X296250D01*
X296750Y786667D01*
X297083Y786917D01*
X297250Y787250D01*
X297167Y787750D01*
X296833Y788000D01*
X295333Y788500D01*
X295000Y789083D01*
X295167Y789500D01*
X295500Y789750D01*
X296000Y789833D01*
X296500Y789750D01*
X297000Y789500D01*
G01X57833Y806500D02*
Y811500D01*
X59833D01*
X60500Y811250D01*
X61000Y810667D01*
X61167Y810000D01*
X61000Y809333D01*
X60583Y808833D01*
X59833Y808583D01*
X57833D01*
G01X65100Y806500D02*
Y811500D01*
G01X69450Y808750D02*
X72117D01*
X71867Y809333D01*
X71450Y809667D01*
X70867Y809833D01*
X70283Y809750D01*
X69783Y809500D01*
X69450Y808917D01*
X69283Y808417D01*
Y807917D01*
X69450Y807417D01*
X69867Y806917D01*
X70367Y806583D01*
X70950Y806500D01*
X71533Y806667D01*
X72117Y807167D01*
G01X77800Y806500D02*
Y809833D01*
G01Y809250D02*
X77467Y809583D01*
X76967Y809750D01*
X76383Y809833D01*
X75800Y809667D01*
X75300Y809333D01*
X74967Y808833D01*
X74800Y808167D01*
X74967Y807500D01*
X75300Y807000D01*
X75800Y806667D01*
X76383Y806500D01*
X76967Y806583D01*
X77467Y806833D01*
X77800Y807167D01*
G01X80650Y807083D02*
X81067Y806750D01*
X81650Y806500D01*
X82150D01*
X82650Y806667D01*
X82983Y806917D01*
X83150Y807250D01*
X83067Y807750D01*
X82733Y808000D01*
X81233Y808500D01*
X80900Y809083D01*
X81067Y809500D01*
X81400Y809750D01*
X81900Y809833D01*
X82400Y809750D01*
X82900Y809500D01*
G01X86250Y808750D02*
X88917D01*
X88667Y809333D01*
X88250Y809667D01*
X87667Y809833D01*
X87083Y809750D01*
X86583Y809500D01*
X86250Y808917D01*
X86083Y808417D01*
Y807917D01*
X86250Y807417D01*
X86667Y806917D01*
X87167Y806583D01*
X87750Y806500D01*
X88333Y806667D01*
X88917Y807167D01*
G01X98200Y806500D02*
Y810750D01*
X98367Y811167D01*
X98700Y811417D01*
X99200Y811500D01*
X99700Y811333D01*
X99950Y810917D01*
G01X98950Y809500D02*
X97283D01*
G01X104300Y806500D02*
X103800Y806583D01*
X103300Y806917D01*
X102967Y807500D01*
X102800Y808167D01*
X102967Y808833D01*
X103300Y809417D01*
X103800Y809750D01*
X104300Y809833D01*
X104800Y809750D01*
X105300Y809417D01*
X105633Y808833D01*
X105717Y808167D01*
X105633Y807500D01*
X105300Y806917D01*
X104800Y806583D01*
X104300Y806500D01*
G01X109900D02*
Y811500D01*
G01X115500Y806500D02*
Y811500D01*
G01X121100Y806500D02*
X120600Y806583D01*
X120100Y806917D01*
X119767Y807500D01*
X119600Y808167D01*
X119767Y808833D01*
X120100Y809417D01*
X120600Y809750D01*
X121100Y809833D01*
X121600Y809750D01*
X122100Y809417D01*
X122433Y808833D01*
X122517Y808167D01*
X122433Y807500D01*
X122100Y806917D01*
X121600Y806583D01*
X121100Y806500D01*
G01X124617Y809833D02*
X125617Y806500D01*
X126700Y809833D01*
X127783Y806500D01*
X128783Y809833D01*
G01X137900Y811500D02*
Y806500D01*
G01X136733Y809833D02*
X139067D01*
G01X142083Y806500D02*
Y811500D01*
G01Y809083D02*
X142500Y809500D01*
X142917Y809750D01*
X143583Y809833D01*
X144083Y809750D01*
X144667Y809417D01*
X144917Y808917D01*
Y806500D01*
G01X147850Y808750D02*
X150517D01*
X150267Y809333D01*
X149850Y809667D01*
X149267Y809833D01*
X148683Y809750D01*
X148183Y809500D01*
X147850Y808917D01*
X147683Y808417D01*
Y807917D01*
X147850Y807417D01*
X148267Y806917D01*
X148767Y806583D01*
X149350Y806500D01*
X149933Y806667D01*
X150517Y807167D01*
G01X159050Y807083D02*
X159467Y806750D01*
X160050Y806500D01*
X160550D01*
X161050Y806667D01*
X161383Y806917D01*
X161550Y807250D01*
X161467Y807750D01*
X161133Y808000D01*
X159633Y808500D01*
X159300Y809083D01*
X159467Y809500D01*
X159800Y809750D01*
X160300Y809833D01*
X160800Y809750D01*
X161300Y809500D01*
G01X164400Y804833D02*
Y809833D01*
G01Y809083D02*
X164817Y809500D01*
X165233Y809750D01*
X165900Y809833D01*
X166483Y809750D01*
X167067Y809333D01*
X167317Y808750D01*
X167400Y808167D01*
X167317Y807583D01*
X167067Y807000D01*
X166567Y806667D01*
X165900Y806500D01*
X165317Y806583D01*
X164733Y806833D01*
X164400Y807167D01*
G01X170250Y808750D02*
X172917D01*
X172667Y809333D01*
X172250Y809667D01*
X171667Y809833D01*
X171083Y809750D01*
X170583Y809500D01*
X170250Y808917D01*
X170083Y808417D01*
Y807917D01*
X170250Y807417D01*
X170667Y806917D01*
X171167Y806583D01*
X171750Y806500D01*
X172333Y806667D01*
X172917Y807167D01*
G01X178433Y809417D02*
X177850Y809750D01*
X177350Y809833D01*
X176683Y809667D01*
X176183Y809333D01*
X175850Y808750D01*
X175767Y808167D01*
X175850Y807583D01*
X176183Y807083D01*
X176683Y806667D01*
X177350Y806500D01*
X177933Y806667D01*
X178433Y807000D01*
G01X182700Y809833D02*
Y806500D01*
G01Y811167D02*
X182533Y811250D01*
Y811417D01*
X182700Y811500D01*
X182867Y811417D01*
Y811250D01*
X182700Y811167D01*
G01X187800Y806500D02*
Y810750D01*
X187967Y811167D01*
X188300Y811417D01*
X188800Y811500D01*
X189300Y811333D01*
X189550Y810917D01*
G01X188550Y809500D02*
X186883D01*
G01X193900Y809833D02*
Y806500D01*
G01Y811167D02*
X193733Y811250D01*
Y811417D01*
X193900Y811500D01*
X194067Y811417D01*
Y811250D01*
X193900Y811167D01*
G01X200833Y809417D02*
X200250Y809750D01*
X199750Y809833D01*
X199083Y809667D01*
X198583Y809333D01*
X198250Y808750D01*
X198167Y808167D01*
X198250Y807583D01*
X198583Y807083D01*
X199083Y806667D01*
X199750Y806500D01*
X200333Y806667D01*
X200833Y807000D01*
G01X206600Y806500D02*
Y809833D01*
G01Y809250D02*
X206267Y809583D01*
X205767Y809750D01*
X205183Y809833D01*
X204600Y809667D01*
X204100Y809333D01*
X203767Y808833D01*
X203600Y808167D01*
X203767Y807500D01*
X204100Y807000D01*
X204600Y806667D01*
X205183Y806500D01*
X205767Y806583D01*
X206267Y806833D01*
X206600Y807167D01*
G01X210700Y811500D02*
Y806500D01*
G01X209533Y809833D02*
X211867D01*
G01X216300D02*
Y806500D01*
G01Y811167D02*
X216133Y811250D01*
Y811417D01*
X216300Y811500D01*
X216467Y811417D01*
Y811250D01*
X216300Y811167D01*
G01X221900Y806500D02*
X221400Y806583D01*
X220900Y806917D01*
X220567Y807500D01*
X220400Y808167D01*
X220567Y808833D01*
X220900Y809417D01*
X221400Y809750D01*
X221900Y809833D01*
X222400Y809750D01*
X222900Y809417D01*
X223233Y808833D01*
X223317Y808167D01*
X223233Y807500D01*
X222900Y806917D01*
X222400Y806583D01*
X221900Y806500D01*
G01X226083D02*
Y809833D01*
G01Y809000D02*
X226417Y809417D01*
X226917Y809750D01*
X227583Y809833D01*
X228167Y809750D01*
X228667Y809417D01*
X228917Y808833D01*
Y806500D01*
G01X240200Y811500D02*
Y806500D01*
G01Y807250D02*
X239867Y806833D01*
X239367Y806583D01*
X238783Y806500D01*
X238117Y806667D01*
X237617Y807083D01*
X237283Y807583D01*
X237200Y808167D01*
X237283Y808750D01*
X237617Y809250D01*
X238117Y809667D01*
X238783Y809833D01*
X239367Y809750D01*
X239783Y809583D01*
X240200Y809250D01*
G01X244300Y806500D02*
X243800Y806583D01*
X243300Y806917D01*
X242967Y807500D01*
X242800Y808167D01*
X242967Y808833D01*
X243300Y809417D01*
X243800Y809750D01*
X244300Y809833D01*
X244800Y809750D01*
X245300Y809417D01*
X245633Y808833D01*
X245717Y808167D01*
X245633Y807500D01*
X245300Y806917D01*
X244800Y806583D01*
X244300Y806500D01*
G01X251233Y809417D02*
X250650Y809750D01*
X250150Y809833D01*
X249483Y809667D01*
X248983Y809333D01*
X248650Y808750D01*
X248567Y808167D01*
X248650Y807583D01*
X248983Y807083D01*
X249483Y806667D01*
X250150Y806500D01*
X250733Y806667D01*
X251233Y807000D01*
G01X254083Y809833D02*
Y807500D01*
X254417Y806917D01*
X254917Y806583D01*
X255500Y806500D01*
X256083Y806583D01*
X256583Y806917D01*
X256917Y807500D01*
G01Y806500D02*
Y809833D01*
G01X258600Y806500D02*
Y809833D01*
G01Y808917D02*
X258850Y809333D01*
X259267Y809667D01*
X259850Y809833D01*
X260433Y809667D01*
X260850Y809333D01*
X261100Y808917D01*
Y806500D01*
G01Y808917D02*
X261350Y809333D01*
X261767Y809667D01*
X262350Y809833D01*
X262933Y809667D01*
X263350Y809333D01*
X263600Y808833D01*
Y806500D01*
G01X265450Y808750D02*
X268117D01*
X267867Y809333D01*
X267450Y809667D01*
X266867Y809833D01*
X266283Y809750D01*
X265783Y809500D01*
X265450Y808917D01*
X265283Y808417D01*
Y807917D01*
X265450Y807417D01*
X265867Y806917D01*
X266367Y806583D01*
X266950Y806500D01*
X267533Y806667D01*
X268117Y807167D01*
G01X270883Y806500D02*
Y809833D01*
G01Y809000D02*
X271217Y809417D01*
X271717Y809750D01*
X272383Y809833D01*
X272967Y809750D01*
X273467Y809417D01*
X273717Y808833D01*
Y806500D01*
G01X277900Y811500D02*
Y806500D01*
G01X276733Y809833D02*
X279067D01*
G01X282250Y807083D02*
X282667Y806750D01*
X283250Y806500D01*
X283750D01*
X284250Y806667D01*
X284583Y806917D01*
X284750Y807250D01*
X284667Y807750D01*
X284333Y808000D01*
X282833Y808500D01*
X282500Y809083D01*
X282667Y809500D01*
X283000Y809750D01*
X283500Y809833D01*
X284000Y809750D01*
X284500Y809500D01*
G01X294700Y809833D02*
Y806500D01*
G01Y811167D02*
X294533Y811250D01*
Y811417D01*
X294700Y811500D01*
X294867Y811417D01*
Y811250D01*
X294700Y811167D01*
G01X298883Y806500D02*
Y809833D01*
G01Y809000D02*
X299217Y809417D01*
X299717Y809750D01*
X300383Y809833D01*
X300967Y809750D01*
X301467Y809417D01*
X301717Y808833D01*
Y806500D01*
G01X312833Y809417D02*
X312250Y809750D01*
X311750Y809833D01*
X311083Y809667D01*
X310583Y809333D01*
X310250Y808750D01*
X310167Y808167D01*
X310250Y807583D01*
X310583Y807083D01*
X311083Y806667D01*
X311750Y806500D01*
X312333Y806667D01*
X312833Y807000D01*
G01X317100Y806500D02*
Y811500D01*
G01X324200Y806500D02*
Y809833D01*
G01Y809250D02*
X323867Y809583D01*
X323367Y809750D01*
X322783Y809833D01*
X322200Y809667D01*
X321700Y809333D01*
X321367Y808833D01*
X321200Y808167D01*
X321367Y807500D01*
X321700Y807000D01*
X322200Y806667D01*
X322783Y806500D01*
X323367Y806583D01*
X323867Y806833D01*
X324200Y807167D01*
G01X327050Y807083D02*
X327467Y806750D01*
X328050Y806500D01*
X328550D01*
X329050Y806667D01*
X329383Y806917D01*
X329550Y807250D01*
X329467Y807750D01*
X329133Y808000D01*
X327633Y808500D01*
X327300Y809083D01*
X327467Y809500D01*
X327800Y809750D01*
X328300Y809833D01*
X328800Y809750D01*
X329300Y809500D01*
G01X332650Y807083D02*
X333067Y806750D01*
X333650Y806500D01*
X334150D01*
X334650Y806667D01*
X334983Y806917D01*
X335150Y807250D01*
X335067Y807750D01*
X334733Y808000D01*
X333233Y808500D01*
X332900Y809083D01*
X333067Y809500D01*
X333400Y809750D01*
X333900Y809833D01*
X334400Y809750D01*
X334900Y809500D01*
G01X343517Y810667D02*
X344017Y811167D01*
X344600Y811417D01*
X345267Y811500D01*
X346100Y811333D01*
X346683Y810917D01*
X346850Y810417D01*
X346767Y809917D01*
X346433Y809500D01*
X344767Y808667D01*
X344017Y808083D01*
X343517Y807250D01*
X343350Y806500D01*
X346850D01*
G01X357800D02*
Y809833D01*
G01Y809250D02*
X357467Y809583D01*
X356967Y809750D01*
X356383Y809833D01*
X355800Y809667D01*
X355300Y809333D01*
X354967Y808833D01*
X354800Y808167D01*
X354967Y807500D01*
X355300Y807000D01*
X355800Y806667D01*
X356383Y806500D01*
X356967Y806583D01*
X357467Y806833D01*
X357800Y807167D01*
G01X360483Y806500D02*
Y809833D01*
G01Y809000D02*
X360817Y809417D01*
X361317Y809750D01*
X361983Y809833D01*
X362567Y809750D01*
X363067Y809417D01*
X363317Y808833D01*
Y806500D01*
G01X369000Y811500D02*
Y806500D01*
G01Y807250D02*
X368667Y806833D01*
X368167Y806583D01*
X367583Y806500D01*
X366917Y806667D01*
X366417Y807083D01*
X366083Y807583D01*
X366000Y808167D01*
X366083Y808750D01*
X366417Y809250D01*
X366917Y809667D01*
X367583Y809833D01*
X368167Y809750D01*
X368583Y809583D01*
X369000Y809250D01*
G01X378700Y811500D02*
Y806500D01*
G01X377533Y809833D02*
X379867D01*
G01X382883Y806500D02*
Y811500D01*
G01Y809083D02*
X383300Y809500D01*
X383717Y809750D01*
X384383Y809833D01*
X384883Y809750D01*
X385467Y809417D01*
X385717Y808917D01*
Y806500D01*
G01X388650Y808750D02*
X391317D01*
X391067Y809333D01*
X390650Y809667D01*
X390067Y809833D01*
X389483Y809750D01*
X388983Y809500D01*
X388650Y808917D01*
X388483Y808417D01*
Y807917D01*
X388650Y807417D01*
X389067Y806917D01*
X389567Y806583D01*
X390150Y806500D01*
X390733Y806667D01*
X391317Y807167D01*
G01X401100Y806500D02*
Y811500D01*
G01X408200Y806500D02*
Y809833D01*
G01Y809250D02*
X407867Y809583D01*
X407367Y809750D01*
X406783Y809833D01*
X406200Y809667D01*
X405700Y809333D01*
X405367Y808833D01*
X405200Y808167D01*
X405367Y807500D01*
X405700Y807000D01*
X406200Y806667D01*
X406783Y806500D01*
X407367Y806583D01*
X407867Y806833D01*
X408200Y807167D01*
G01X412300Y811500D02*
Y806500D01*
G01X411133Y809833D02*
X413467D01*
G01X416650Y808750D02*
X419317D01*
X419067Y809333D01*
X418650Y809667D01*
X418067Y809833D01*
X417483Y809750D01*
X416983Y809500D01*
X416650Y808917D01*
X416483Y808417D01*
Y807917D01*
X416650Y807417D01*
X417067Y806917D01*
X417567Y806583D01*
X418150Y806500D01*
X418733Y806667D01*
X419317Y807167D01*
G01X422250Y807083D02*
X422667Y806750D01*
X423250Y806500D01*
X423750D01*
X424250Y806667D01*
X424583Y806917D01*
X424750Y807250D01*
X424667Y807750D01*
X424333Y808000D01*
X422833Y808500D01*
X422500Y809083D01*
X422667Y809500D01*
X423000Y809750D01*
X423500Y809833D01*
X424000Y809750D01*
X424500Y809500D01*
G01X429100Y811500D02*
Y806500D01*
G01X427933Y809833D02*
X430267D01*
G01X438800D02*
X440300Y806500D01*
X441800Y809833D01*
G01X444650Y808750D02*
X447317D01*
X447067Y809333D01*
X446650Y809667D01*
X446067Y809833D01*
X445483Y809750D01*
X444983Y809500D01*
X444650Y808917D01*
X444483Y808417D01*
Y807917D01*
X444650Y807417D01*
X445067Y806917D01*
X445567Y806583D01*
X446150Y806500D01*
X446733Y806667D01*
X447317Y807167D01*
G01X450333Y806500D02*
Y809833D01*
G01Y809167D02*
X450750Y809500D01*
X451167Y809750D01*
X451750Y809833D01*
X452167Y809750D01*
X452667Y809500D01*
G01X455850Y807083D02*
X456267Y806750D01*
X456850Y806500D01*
X457350D01*
X457850Y806667D01*
X458183Y806917D01*
X458350Y807250D01*
X458267Y807750D01*
X457933Y808000D01*
X456433Y808500D01*
X456100Y809083D01*
X456267Y809500D01*
X456600Y809750D01*
X457100Y809833D01*
X457600Y809750D01*
X458100Y809500D01*
G01X462700Y809833D02*
Y806500D01*
G01Y811167D02*
X462533Y811250D01*
Y811417D01*
X462700Y811500D01*
X462867Y811417D01*
Y811250D01*
X462700Y811167D01*
G01X468300Y806500D02*
X467800Y806583D01*
X467300Y806917D01*
X466967Y807500D01*
X466800Y808167D01*
X466967Y808833D01*
X467300Y809417D01*
X467800Y809750D01*
X468300Y809833D01*
X468800Y809750D01*
X469300Y809417D01*
X469633Y808833D01*
X469717Y808167D01*
X469633Y807500D01*
X469300Y806917D01*
X468800Y806583D01*
X468300Y806500D01*
G01X472483D02*
Y809833D01*
G01Y809000D02*
X472817Y809417D01*
X473317Y809750D01*
X473983Y809833D01*
X474567Y809750D01*
X475067Y809417D01*
X475317Y808833D01*
Y806500D01*
G01X485100Y809833D02*
Y806500D01*
G01Y811167D02*
X484933Y811250D01*
Y811417D01*
X485100Y811500D01*
X485267Y811417D01*
Y811250D01*
X485100Y811167D01*
G01X489450Y807083D02*
X489867Y806750D01*
X490450Y806500D01*
X490950D01*
X491450Y806667D01*
X491783Y806917D01*
X491950Y807250D01*
X491867Y807750D01*
X491533Y808000D01*
X490033Y808500D01*
X489700Y809083D01*
X489867Y809500D01*
X490200Y809750D01*
X490700Y809833D01*
X491200Y809750D01*
X491700Y809500D01*
G01X500733Y806500D02*
Y809833D01*
G01Y809167D02*
X501150Y809500D01*
X501567Y809750D01*
X502150Y809833D01*
X502567Y809750D01*
X503067Y809500D01*
G01X506250Y808750D02*
X508917D01*
X508667Y809333D01*
X508250Y809667D01*
X507667Y809833D01*
X507083Y809750D01*
X506583Y809500D01*
X506250Y808917D01*
X506083Y808417D01*
Y807917D01*
X506250Y807417D01*
X506667Y806917D01*
X507167Y806583D01*
X507750Y806500D01*
X508333Y806667D01*
X508917Y807167D01*
G01X514600Y804833D02*
Y809833D01*
G01Y809083D02*
X514183Y809500D01*
X513683Y809750D01*
X513100Y809833D01*
X512600Y809750D01*
X512017Y809333D01*
X511683Y808750D01*
X511600Y808167D01*
X511683Y807583D01*
X512017Y807000D01*
X512600Y806583D01*
X513100Y806500D01*
X513683Y806583D01*
X514183Y806833D01*
X514600Y807250D01*
G01X517283Y809833D02*
Y807500D01*
X517617Y806917D01*
X518117Y806583D01*
X518700Y806500D01*
X519283Y806583D01*
X519783Y806917D01*
X520117Y807500D01*
G01Y806500D02*
Y809833D01*
G01X524300D02*
Y806500D01*
G01Y811167D02*
X524133Y811250D01*
Y811417D01*
X524300Y811500D01*
X524467Y811417D01*
Y811250D01*
X524300Y811167D01*
G01X528733Y806500D02*
Y809833D01*
G01Y809167D02*
X529150Y809500D01*
X529567Y809750D01*
X530150Y809833D01*
X530567Y809750D01*
X531067Y809500D01*
G01X534250Y808750D02*
X536917D01*
X536667Y809333D01*
X536250Y809667D01*
X535667Y809833D01*
X535083Y809750D01*
X534583Y809500D01*
X534250Y808917D01*
X534083Y808417D01*
Y807917D01*
X534250Y807417D01*
X534667Y806917D01*
X535167Y806583D01*
X535750Y806500D01*
X536333Y806667D01*
X536917Y807167D01*
G01X542600Y811500D02*
Y806500D01*
G01Y807250D02*
X542267Y806833D01*
X541767Y806583D01*
X541183Y806500D01*
X540517Y806667D01*
X540017Y807083D01*
X539683Y807583D01*
X539600Y808167D01*
X539683Y808750D01*
X540017Y809250D01*
X540517Y809667D01*
X541183Y809833D01*
X541767Y809750D01*
X542183Y809583D01*
X542600Y809250D01*
G01X546533Y805583D02*
X546867Y806667D01*
G01X160333Y668083D02*
X159833Y668333D01*
X159250Y668500D01*
X158583D01*
X157833Y668250D01*
X157250Y667833D01*
X156833Y667333D01*
X156500Y666500D01*
X156417Y665750D01*
X156583Y665000D01*
X156833Y664500D01*
X157333Y664000D01*
X157917Y663667D01*
X158500Y663500D01*
X159083D01*
X159667Y663667D01*
X160167Y663917D01*
X160583Y664250D01*
G01X164100Y663500D02*
Y668500D01*
G01X171200Y663500D02*
Y666833D01*
G01Y666250D02*
X170867Y666583D01*
X170367Y666750D01*
X169783Y666833D01*
X169200Y666667D01*
X168700Y666333D01*
X168367Y665833D01*
X168200Y665167D01*
X168367Y664500D01*
X168700Y664000D01*
X169200Y663667D01*
X169783Y663500D01*
X170367Y663583D01*
X170867Y663833D01*
X171200Y664167D01*
G01X174050Y664083D02*
X174467Y663750D01*
X175050Y663500D01*
X175550D01*
X176050Y663667D01*
X176383Y663917D01*
X176550Y664250D01*
X176467Y664750D01*
X176133Y665000D01*
X174633Y665500D01*
X174300Y666083D01*
X174467Y666500D01*
X174800Y666750D01*
X175300Y666833D01*
X175800Y666750D01*
X176300Y666500D01*
G01X179650Y664083D02*
X180067Y663750D01*
X180650Y663500D01*
X181150D01*
X181650Y663667D01*
X181983Y663917D01*
X182150Y664250D01*
X182067Y664750D01*
X181733Y665000D01*
X180233Y665500D01*
X179900Y666083D01*
X180067Y666500D01*
X180400Y666750D01*
X180900Y666833D01*
X181400Y666750D01*
X181900Y666500D01*
G01X186500Y666833D02*
Y663500D01*
G01Y668167D02*
X186333Y668250D01*
Y668417D01*
X186500Y668500D01*
X186667Y668417D01*
Y668250D01*
X186500Y668167D01*
G01X191600Y663500D02*
Y667750D01*
X191767Y668167D01*
X192100Y668417D01*
X192600Y668500D01*
X193100Y668333D01*
X193350Y667917D01*
G01X192350Y666500D02*
X190683D01*
G01X195950Y662000D02*
X196450Y661833D01*
X197117Y662000D01*
X197533Y662333D01*
X197867Y662750D01*
X198367Y664083D01*
X199450Y666833D01*
G01X196783D02*
X198367Y664083D01*
G01X274000Y-63500D02*
Y-60167D01*
G01Y-60750D02*
X273667Y-60417D01*
X273167Y-60250D01*
X272583Y-60167D01*
X272000Y-60333D01*
X271500Y-60667D01*
X271167Y-61167D01*
X271000Y-61833D01*
X271167Y-62500D01*
X271500Y-63000D01*
X272000Y-63333D01*
X272583Y-63500D01*
X273167Y-63417D01*
X273667Y-63167D01*
X274000Y-62833D01*
G01X279600Y-58500D02*
Y-63500D01*
G01Y-62750D02*
X279267Y-63167D01*
X278767Y-63417D01*
X278183Y-63500D01*
X277517Y-63333D01*
X277017Y-62917D01*
X276683Y-62417D01*
X276600Y-61833D01*
X276683Y-61250D01*
X277017Y-60750D01*
X277517Y-60333D01*
X278183Y-60167D01*
X278767Y-60250D01*
X279183Y-60417D01*
X279600Y-60750D01*
G01X285200Y-58500D02*
Y-63500D01*
G01Y-62750D02*
X284867Y-63167D01*
X284367Y-63417D01*
X283783Y-63500D01*
X283117Y-63333D01*
X282617Y-62917D01*
X282283Y-62417D01*
X282200Y-61833D01*
X282283Y-61250D01*
X282617Y-60750D01*
X283117Y-60333D01*
X283783Y-60167D01*
X284367Y-60250D01*
X284783Y-60417D01*
X285200Y-60750D01*
G01X293650Y-62917D02*
X294067Y-63250D01*
X294650Y-63500D01*
X295150D01*
X295650Y-63333D01*
X295983Y-63083D01*
X296150Y-62750D01*
X296067Y-62250D01*
X295733Y-62000D01*
X294233Y-61500D01*
X293900Y-60917D01*
X294067Y-60500D01*
X294400Y-60250D01*
X294900Y-60167D01*
X295400Y-60250D01*
X295900Y-60500D01*
G01X299083Y-60167D02*
Y-62500D01*
X299417Y-63083D01*
X299917Y-63417D01*
X300500Y-63500D01*
X301083Y-63417D01*
X301583Y-63083D01*
X301917Y-62500D01*
G01Y-63500D02*
Y-60167D01*
G01X304600Y-65167D02*
Y-60167D01*
G01Y-60917D02*
X305017Y-60500D01*
X305433Y-60250D01*
X306100Y-60167D01*
X306683Y-60250D01*
X307267Y-60667D01*
X307517Y-61250D01*
X307600Y-61833D01*
X307517Y-62417D01*
X307267Y-63000D01*
X306767Y-63333D01*
X306100Y-63500D01*
X305517Y-63417D01*
X304933Y-63167D01*
X304600Y-62833D01*
G01X310200Y-65167D02*
Y-60167D01*
G01Y-60917D02*
X310617Y-60500D01*
X311033Y-60250D01*
X311700Y-60167D01*
X312283Y-60250D01*
X312867Y-60667D01*
X313117Y-61250D01*
X313200Y-61833D01*
X313117Y-62417D01*
X312867Y-63000D01*
X312367Y-63333D01*
X311700Y-63500D01*
X311117Y-63417D01*
X310533Y-63167D01*
X310200Y-62833D01*
G01X317300Y-63500D02*
Y-58500D01*
G01X322900Y-60167D02*
Y-63500D01*
G01Y-58833D02*
X322733Y-58750D01*
Y-58583D01*
X322900Y-58500D01*
X323067Y-58583D01*
Y-58750D01*
X322900Y-58833D01*
G01X327250Y-61250D02*
X329917D01*
X329667Y-60667D01*
X329250Y-60333D01*
X328667Y-60167D01*
X328083Y-60250D01*
X327583Y-60500D01*
X327250Y-61083D01*
X327083Y-61583D01*
Y-62083D01*
X327250Y-62583D01*
X327667Y-63083D01*
X328167Y-63417D01*
X328750Y-63500D01*
X329333Y-63333D01*
X329917Y-62833D01*
G01X332933Y-63500D02*
Y-60167D01*
G01Y-60833D02*
X333350Y-60500D01*
X333767Y-60250D01*
X334350Y-60167D01*
X334767Y-60250D01*
X335267Y-60500D01*
G01X339700Y-60167D02*
X340533Y-59125D01*
Y-58500D01*
X339908D01*
Y-59125D01*
X340533D01*
G01X344050Y-62917D02*
X344467Y-63250D01*
X345050Y-63500D01*
X345550D01*
X346050Y-63333D01*
X346383Y-63083D01*
X346550Y-62750D01*
X346467Y-62250D01*
X346133Y-62000D01*
X344633Y-61500D01*
X344300Y-60917D01*
X344467Y-60500D01*
X344800Y-60250D01*
X345300Y-60167D01*
X345800Y-60250D01*
X346300Y-60500D01*
G01X354833Y-58500D02*
Y-63500D01*
X358167D01*
G01X362100D02*
X361600Y-63417D01*
X361100Y-63083D01*
X360767Y-62500D01*
X360600Y-61833D01*
X360767Y-61167D01*
X361100Y-60583D01*
X361600Y-60250D01*
X362100Y-60167D01*
X362600Y-60250D01*
X363100Y-60583D01*
X363433Y-61167D01*
X363517Y-61833D01*
X363433Y-62500D01*
X363100Y-63083D01*
X362600Y-63417D01*
X362100Y-63500D01*
G01X366533Y-64750D02*
X367117Y-65083D01*
X367783Y-65167D01*
X368367Y-65083D01*
X368867Y-64667D01*
X369200Y-64083D01*
Y-60167D01*
G01Y-60833D02*
X368867Y-60500D01*
X368367Y-60250D01*
X367783Y-60167D01*
X367117Y-60333D01*
X366700Y-60667D01*
X366367Y-61250D01*
X366200Y-61833D01*
X366283Y-62333D01*
X366617Y-62917D01*
X367117Y-63333D01*
X367783Y-63500D01*
X368283Y-63417D01*
X368867Y-63083D01*
X369200Y-62750D01*
G01X373300Y-63500D02*
X372800Y-63417D01*
X372300Y-63083D01*
X371967Y-62500D01*
X371800Y-61833D01*
X371967Y-61167D01*
X372300Y-60583D01*
X372800Y-60250D01*
X373300Y-60167D01*
X373800Y-60250D01*
X374300Y-60583D01*
X374633Y-61167D01*
X374717Y-61833D01*
X374633Y-62500D01*
X374300Y-63083D01*
X373800Y-63417D01*
X373300Y-63500D01*
G01X386000D02*
Y-60167D01*
G01Y-60750D02*
X385667Y-60417D01*
X385167Y-60250D01*
X384583Y-60167D01*
X384000Y-60333D01*
X383500Y-60667D01*
X383167Y-61167D01*
X383000Y-61833D01*
X383167Y-62500D01*
X383500Y-63000D01*
X384000Y-63333D01*
X384583Y-63500D01*
X385167Y-63417D01*
X385667Y-63167D01*
X386000Y-62833D01*
G01X388683Y-63500D02*
Y-60167D01*
G01Y-61000D02*
X389017Y-60583D01*
X389517Y-60250D01*
X390183Y-60167D01*
X390767Y-60250D01*
X391267Y-60583D01*
X391517Y-61167D01*
Y-63500D01*
G01X397200Y-58500D02*
Y-63500D01*
G01Y-62750D02*
X396867Y-63167D01*
X396367Y-63417D01*
X395783Y-63500D01*
X395117Y-63333D01*
X394617Y-62917D01*
X394283Y-62417D01*
X394200Y-61833D01*
X394283Y-61250D01*
X394617Y-60750D01*
X395117Y-60333D01*
X395783Y-60167D01*
X396367Y-60250D01*
X396783Y-60417D01*
X397200Y-60750D01*
G01X405067Y-58500D02*
Y-62083D01*
X405400Y-62833D01*
X406067Y-63333D01*
X406900Y-63500D01*
X407733Y-63333D01*
X408400Y-62833D01*
X408733Y-62083D01*
Y-58500D01*
G01X410833D02*
Y-63500D01*
X414167D01*
G01X423200D02*
Y-59250D01*
X423367Y-58833D01*
X423700Y-58583D01*
X424200Y-58500D01*
X424700Y-58667D01*
X424950Y-59083D01*
G01X423950Y-60500D02*
X422283D01*
G01X429300Y-60167D02*
Y-63500D01*
G01Y-58833D02*
X429133Y-58750D01*
Y-58583D01*
X429300Y-58500D01*
X429467Y-58583D01*
Y-58750D01*
X429300Y-58833D01*
G01X434900Y-63500D02*
Y-58500D01*
G01X439250Y-61250D02*
X441917D01*
X441667Y-60667D01*
X441250Y-60333D01*
X440667Y-60167D01*
X440083Y-60250D01*
X439583Y-60500D01*
X439250Y-61083D01*
X439083Y-61583D01*
Y-62083D01*
X439250Y-62583D01*
X439667Y-63083D01*
X440167Y-63417D01*
X440750Y-63500D01*
X441333Y-63333D01*
X441917Y-62833D01*
G01X449783Y-63500D02*
Y-58500D01*
X453617Y-63500D01*
Y-58500D01*
G01X455883Y-60167D02*
Y-62500D01*
X456217Y-63083D01*
X456717Y-63417D01*
X457300Y-63500D01*
X457883Y-63417D01*
X458383Y-63083D01*
X458717Y-62500D01*
G01Y-63500D02*
Y-60167D01*
G01X460400Y-63500D02*
Y-60167D01*
G01Y-61083D02*
X460650Y-60667D01*
X461067Y-60333D01*
X461650Y-60167D01*
X462233Y-60333D01*
X462650Y-60667D01*
X462900Y-61083D01*
Y-63500D01*
G01Y-61083D02*
X463150Y-60667D01*
X463567Y-60333D01*
X464150Y-60167D01*
X464733Y-60333D01*
X465150Y-60667D01*
X465400Y-61167D01*
Y-63500D01*
G01X467000D02*
Y-58500D01*
G01Y-61000D02*
X467417Y-60500D01*
X467917Y-60250D01*
X468417Y-60167D01*
X469167Y-60333D01*
X469667Y-60667D01*
X470000Y-61250D01*
Y-61917D01*
X469833Y-62583D01*
X469500Y-63083D01*
X468917Y-63417D01*
X468417Y-63500D01*
X467917Y-63417D01*
X467417Y-63167D01*
X467000Y-62750D01*
G01X472850Y-61250D02*
X475517D01*
X475267Y-60667D01*
X474850Y-60333D01*
X474267Y-60167D01*
X473683Y-60250D01*
X473183Y-60500D01*
X472850Y-61083D01*
X472683Y-61583D01*
Y-62083D01*
X472850Y-62583D01*
X473267Y-63083D01*
X473767Y-63417D01*
X474350Y-63500D01*
X474933Y-63333D01*
X475517Y-62833D01*
G01X478533Y-63500D02*
Y-60167D01*
G01Y-60833D02*
X478950Y-60500D01*
X479367Y-60250D01*
X479950Y-60167D01*
X480367Y-60250D01*
X480867Y-60500D01*
G01X490900Y-60167D02*
Y-63500D01*
G01Y-58833D02*
X490733Y-58750D01*
Y-58583D01*
X490900Y-58500D01*
X491067Y-58583D01*
Y-58750D01*
X490900Y-58833D01*
G01X495083Y-63500D02*
Y-60167D01*
G01Y-61000D02*
X495417Y-60583D01*
X495917Y-60250D01*
X496583Y-60167D01*
X497167Y-60250D01*
X497667Y-60583D01*
X497917Y-61167D01*
Y-63500D01*
G01X506450Y-62917D02*
X506867Y-63250D01*
X507450Y-63500D01*
X507950D01*
X508450Y-63333D01*
X508783Y-63083D01*
X508950Y-62750D01*
X508867Y-62250D01*
X508533Y-62000D01*
X507033Y-61500D01*
X506700Y-60917D01*
X506867Y-60500D01*
X507200Y-60250D01*
X507700Y-60167D01*
X508200Y-60250D01*
X508700Y-60500D01*
G01X513300Y-60167D02*
Y-63500D01*
G01Y-58833D02*
X513133Y-58750D01*
Y-58583D01*
X513300Y-58500D01*
X513467Y-58583D01*
Y-58750D01*
X513300Y-58833D01*
G01X518900Y-63500D02*
Y-58500D01*
G01X523083Y-63500D02*
Y-58500D01*
G01X525750Y-60167D02*
X523083Y-62083D01*
G01X524167Y-61333D02*
X525917Y-63500D01*
G01X528850Y-62917D02*
X529267Y-63250D01*
X529850Y-63500D01*
X530350D01*
X530850Y-63333D01*
X531183Y-63083D01*
X531350Y-62750D01*
X531267Y-62250D01*
X530933Y-62000D01*
X529433Y-61500D01*
X529100Y-60917D01*
X529267Y-60500D01*
X529600Y-60250D01*
X530100Y-60167D01*
X530600Y-60250D01*
X531100Y-60500D01*
G01X537033Y-60583D02*
X536450Y-60250D01*
X535950Y-60167D01*
X535283Y-60333D01*
X534783Y-60667D01*
X534450Y-61250D01*
X534367Y-61833D01*
X534450Y-62417D01*
X534783Y-62917D01*
X535283Y-63333D01*
X535950Y-63500D01*
X536533Y-63333D01*
X537033Y-63000D01*
G01X540133Y-63500D02*
Y-60167D01*
G01Y-60833D02*
X540550Y-60500D01*
X540967Y-60250D01*
X541550Y-60167D01*
X541967Y-60250D01*
X542467Y-60500D01*
G01X545650Y-61250D02*
X548317D01*
X548067Y-60667D01*
X547650Y-60333D01*
X547067Y-60167D01*
X546483Y-60250D01*
X545983Y-60500D01*
X545650Y-61083D01*
X545483Y-61583D01*
Y-62083D01*
X545650Y-62583D01*
X546067Y-63083D01*
X546567Y-63417D01*
X547150Y-63500D01*
X547733Y-63333D01*
X548317Y-62833D01*
G01X551250Y-61250D02*
X553917D01*
X553667Y-60667D01*
X553250Y-60333D01*
X552667Y-60167D01*
X552083Y-60250D01*
X551583Y-60500D01*
X551250Y-61083D01*
X551083Y-61583D01*
Y-62083D01*
X551250Y-62583D01*
X551667Y-63083D01*
X552167Y-63417D01*
X552750Y-63500D01*
X553333Y-63333D01*
X553917Y-62833D01*
G01X556683Y-63500D02*
Y-60167D01*
G01Y-61000D02*
X557017Y-60583D01*
X557517Y-60250D01*
X558183Y-60167D01*
X558767Y-60250D01*
X559267Y-60583D01*
X559517Y-61167D01*
Y-63500D01*
G01X262500Y-69500D02*
Y439000D01*
G01X272500Y0D02*
Y-5000D01*
G01X270583Y0D02*
X274417D01*
G01X276683Y-5000D02*
Y0D01*
G01Y-2417D02*
X277100Y-2000D01*
X277517Y-1750D01*
X278183Y-1667D01*
X278683Y-1750D01*
X279267Y-2083D01*
X279517Y-2583D01*
Y-5000D01*
G01X282450Y-2750D02*
X285117D01*
X284867Y-2167D01*
X284450Y-1833D01*
X283867Y-1667D01*
X283283Y-1750D01*
X282783Y-2000D01*
X282450Y-2583D01*
X282283Y-3083D01*
Y-3583D01*
X282450Y-4083D01*
X282867Y-4583D01*
X283367Y-4917D01*
X283950Y-5000D01*
X284533Y-4833D01*
X285117Y-4333D01*
G01X294900Y-5000D02*
Y0D01*
G01X302000Y-5000D02*
Y-1667D01*
G01Y-2250D02*
X301667Y-1917D01*
X301167Y-1750D01*
X300583Y-1667D01*
X300000Y-1833D01*
X299500Y-2167D01*
X299167Y-2667D01*
X299000Y-3333D01*
X299167Y-4000D01*
X299500Y-4500D01*
X300000Y-4833D01*
X300583Y-5000D01*
X301167Y-4917D01*
X301667Y-4667D01*
X302000Y-4333D01*
G01X304933Y-5000D02*
Y-1667D01*
G01Y-2333D02*
X305350Y-2000D01*
X305767Y-1750D01*
X306350Y-1667D01*
X306767Y-1750D01*
X307267Y-2000D01*
G01X310533Y-6250D02*
X311117Y-6583D01*
X311783Y-6667D01*
X312367Y-6583D01*
X312867Y-6167D01*
X313200Y-5583D01*
Y-1667D01*
G01Y-2333D02*
X312867Y-2000D01*
X312367Y-1750D01*
X311783Y-1667D01*
X311117Y-1833D01*
X310700Y-2167D01*
X310367Y-2750D01*
X310200Y-3333D01*
X310283Y-3833D01*
X310617Y-4417D01*
X311117Y-4833D01*
X311783Y-5000D01*
X312283Y-4917D01*
X312867Y-4583D01*
X313200Y-4250D01*
G01X316050Y-2750D02*
X318717D01*
X318467Y-2167D01*
X318050Y-1833D01*
X317467Y-1667D01*
X316883Y-1750D01*
X316383Y-2000D01*
X316050Y-2583D01*
X315883Y-3083D01*
Y-3583D01*
X316050Y-4083D01*
X316467Y-4583D01*
X316967Y-4917D01*
X317550Y-5000D01*
X318133Y-4833D01*
X318717Y-4333D01*
G01X321650Y-4417D02*
X322067Y-4750D01*
X322650Y-5000D01*
X323150D01*
X323650Y-4833D01*
X323983Y-4583D01*
X324150Y-4250D01*
X324067Y-3750D01*
X323733Y-3500D01*
X322233Y-3000D01*
X321900Y-2417D01*
X322067Y-2000D01*
X322400Y-1750D01*
X322900Y-1667D01*
X323400Y-1750D01*
X323900Y-2000D01*
G01X328500Y0D02*
Y-5000D01*
G01X327333Y-1667D02*
X329667D01*
G01X341200Y0D02*
Y-5000D01*
G01Y-4250D02*
X340867Y-4667D01*
X340367Y-4917D01*
X339783Y-5000D01*
X339117Y-4833D01*
X338617Y-4417D01*
X338283Y-3917D01*
X338200Y-3333D01*
X338283Y-2750D01*
X338617Y-2250D01*
X339117Y-1833D01*
X339783Y-1667D01*
X340367Y-1750D01*
X340783Y-1917D01*
X341200Y-2250D01*
G01X345300Y-1667D02*
Y-5000D01*
G01Y-333D02*
X345133Y-250D01*
Y-83D01*
X345300Y0D01*
X345467Y-83D01*
Y-250D01*
X345300Y-333D01*
G01X348400Y-5000D02*
Y-1667D01*
G01Y-2583D02*
X348650Y-2167D01*
X349067Y-1833D01*
X349650Y-1667D01*
X350233Y-1833D01*
X350650Y-2167D01*
X350900Y-2583D01*
Y-5000D01*
G01Y-2583D02*
X351150Y-2167D01*
X351567Y-1833D01*
X352150Y-1667D01*
X352733Y-1833D01*
X353150Y-2167D01*
X353400Y-2667D01*
Y-5000D01*
G01X355250Y-2750D02*
X357917D01*
X357667Y-2167D01*
X357250Y-1833D01*
X356667Y-1667D01*
X356083Y-1750D01*
X355583Y-2000D01*
X355250Y-2583D01*
X355083Y-3083D01*
Y-3583D01*
X355250Y-4083D01*
X355667Y-4583D01*
X356167Y-4917D01*
X356750Y-5000D01*
X357333Y-4833D01*
X357917Y-4333D01*
G01X360683Y-5000D02*
Y-1667D01*
G01Y-2500D02*
X361017Y-2083D01*
X361517Y-1750D01*
X362183Y-1667D01*
X362767Y-1750D01*
X363267Y-2083D01*
X363517Y-2667D01*
Y-5000D01*
G01X366450Y-4417D02*
X366867Y-4750D01*
X367450Y-5000D01*
X367950D01*
X368450Y-4833D01*
X368783Y-4583D01*
X368950Y-4250D01*
X368867Y-3750D01*
X368533Y-3500D01*
X367033Y-3000D01*
X366700Y-2417D01*
X366867Y-2000D01*
X367200Y-1750D01*
X367700Y-1667D01*
X368200Y-1750D01*
X368700Y-2000D01*
G01X373300Y-1667D02*
Y-5000D01*
G01Y-333D02*
X373133Y-250D01*
Y-83D01*
X373300Y0D01*
X373467Y-83D01*
Y-250D01*
X373300Y-333D01*
G01X378900Y-5000D02*
X378400Y-4917D01*
X377900Y-4583D01*
X377567Y-4000D01*
X377400Y-3333D01*
X377567Y-2667D01*
X377900Y-2083D01*
X378400Y-1750D01*
X378900Y-1667D01*
X379400Y-1750D01*
X379900Y-2083D01*
X380233Y-2667D01*
X380317Y-3333D01*
X380233Y-4000D01*
X379900Y-4583D01*
X379400Y-4917D01*
X378900Y-5000D01*
G01X383083D02*
Y-1667D01*
G01Y-2500D02*
X383417Y-2083D01*
X383917Y-1750D01*
X384583Y-1667D01*
X385167Y-1750D01*
X385667Y-2083D01*
X385917Y-2667D01*
Y-5000D01*
G01X395700D02*
X395200Y-4917D01*
X394700Y-4583D01*
X394367Y-4000D01*
X394200Y-3333D01*
X394367Y-2667D01*
X394700Y-2083D01*
X395200Y-1750D01*
X395700Y-1667D01*
X396200Y-1750D01*
X396700Y-2083D01*
X397033Y-2667D01*
X397117Y-3333D01*
X397033Y-4000D01*
X396700Y-4583D01*
X396200Y-4917D01*
X395700Y-5000D01*
G01X400800D02*
Y-750D01*
X400967Y-333D01*
X401300Y-83D01*
X401800Y0D01*
X402300Y-167D01*
X402550Y-583D01*
G01X401550Y-2000D02*
X399883D01*
G01X411000Y-6667D02*
Y-1667D01*
G01Y-2417D02*
X411417Y-2000D01*
X411833Y-1750D01*
X412500Y-1667D01*
X413083Y-1750D01*
X413667Y-2167D01*
X413917Y-2750D01*
X414000Y-3333D01*
X413917Y-3917D01*
X413667Y-4500D01*
X413167Y-4833D01*
X412500Y-5000D01*
X411917Y-4917D01*
X411333Y-4667D01*
X411000Y-4333D01*
G01X419600Y-5000D02*
Y-1667D01*
G01Y-2250D02*
X419267Y-1917D01*
X418767Y-1750D01*
X418183Y-1667D01*
X417600Y-1833D01*
X417100Y-2167D01*
X416767Y-2667D01*
X416600Y-3333D01*
X416767Y-4000D01*
X417100Y-4500D01*
X417600Y-4833D01*
X418183Y-5000D01*
X418767Y-4917D01*
X419267Y-4667D01*
X419600Y-4333D01*
G01X425200Y0D02*
Y-5000D01*
G01Y-4250D02*
X424867Y-4667D01*
X424367Y-4917D01*
X423783Y-5000D01*
X423117Y-4833D01*
X422617Y-4417D01*
X422283Y-3917D01*
X422200Y-3333D01*
X422283Y-2750D01*
X422617Y-2250D01*
X423117Y-1833D01*
X423783Y-1667D01*
X424367Y-1750D01*
X424783Y-1917D01*
X425200Y-2250D01*
G01X434900Y-5000D02*
X434400Y-4917D01*
X433900Y-4583D01*
X433567Y-4000D01*
X433400Y-3333D01*
X433567Y-2667D01*
X433900Y-2083D01*
X434400Y-1750D01*
X434900Y-1667D01*
X435400Y-1750D01*
X435900Y-2083D01*
X436233Y-2667D01*
X436317Y-3333D01*
X436233Y-4000D01*
X435900Y-4583D01*
X435400Y-4917D01*
X434900Y-5000D01*
G01X439333D02*
Y-1667D01*
G01Y-2333D02*
X439750Y-2000D01*
X440167Y-1750D01*
X440750Y-1667D01*
X441167Y-1750D01*
X441667Y-2000D01*
G01X453200Y0D02*
Y-5000D01*
G01Y-4250D02*
X452867Y-4667D01*
X452367Y-4917D01*
X451783Y-5000D01*
X451117Y-4833D01*
X450617Y-4417D01*
X450283Y-3917D01*
X450200Y-3333D01*
X450283Y-2750D01*
X450617Y-2250D01*
X451117Y-1833D01*
X451783Y-1667D01*
X452367Y-1750D01*
X452783Y-1917D01*
X453200Y-2250D01*
G01X457300Y-1667D02*
Y-5000D01*
G01Y-333D02*
X457133Y-250D01*
Y-83D01*
X457300Y0D01*
X457467Y-83D01*
Y-250D01*
X457300Y-333D01*
G01X464400Y-5000D02*
Y-1667D01*
G01Y-2250D02*
X464067Y-1917D01*
X463567Y-1750D01*
X462983Y-1667D01*
X462400Y-1833D01*
X461900Y-2167D01*
X461567Y-2667D01*
X461400Y-3333D01*
X461567Y-4000D01*
X461900Y-4500D01*
X462400Y-4833D01*
X462983Y-5000D01*
X463567Y-4917D01*
X464067Y-4667D01*
X464400Y-4333D01*
G01X466000Y-5000D02*
Y-1667D01*
G01Y-2583D02*
X466250Y-2167D01*
X466667Y-1833D01*
X467250Y-1667D01*
X467833Y-1833D01*
X468250Y-2167D01*
X468500Y-2583D01*
Y-5000D01*
G01Y-2583D02*
X468750Y-2167D01*
X469167Y-1833D01*
X469750Y-1667D01*
X470333Y-1833D01*
X470750Y-2167D01*
X471000Y-2667D01*
Y-5000D01*
G01X472850Y-2750D02*
X475517D01*
X475267Y-2167D01*
X474850Y-1833D01*
X474267Y-1667D01*
X473683Y-1750D01*
X473183Y-2000D01*
X472850Y-2583D01*
X472683Y-3083D01*
Y-3583D01*
X472850Y-4083D01*
X473267Y-4583D01*
X473767Y-4917D01*
X474350Y-5000D01*
X474933Y-4833D01*
X475517Y-4333D01*
G01X479700Y0D02*
Y-5000D01*
G01X478533Y-1667D02*
X480867D01*
G01X484050Y-2750D02*
X486717D01*
X486467Y-2167D01*
X486050Y-1833D01*
X485467Y-1667D01*
X484883Y-1750D01*
X484383Y-2000D01*
X484050Y-2583D01*
X483883Y-3083D01*
Y-3583D01*
X484050Y-4083D01*
X484467Y-4583D01*
X484967Y-4917D01*
X485550Y-5000D01*
X486133Y-4833D01*
X486717Y-4333D01*
G01X489733Y-5000D02*
Y-1667D01*
G01Y-2333D02*
X490150Y-2000D01*
X490567Y-1750D01*
X491150Y-1667D01*
X491567Y-1750D01*
X492067Y-2000D01*
G01X503767Y-5000D02*
X500433Y-3333D01*
X503767Y-1667D01*
G01X506617Y-4083D02*
X508783D01*
G01Y-2583D02*
X506617D01*
G01X518900Y-5000D02*
Y0D01*
X517900Y-1000D01*
G01Y-5000D02*
X519900D01*
G01X525500D02*
Y0D01*
X522417Y-3583D01*
X526583D01*
G01X533200Y-5000D02*
Y-1667D01*
G01Y-2583D02*
X533450Y-2167D01*
X533867Y-1833D01*
X534450Y-1667D01*
X535033Y-1833D01*
X535450Y-2167D01*
X535700Y-2583D01*
Y-5000D01*
G01Y-2583D02*
X535950Y-2167D01*
X536367Y-1833D01*
X536950Y-1667D01*
X537533Y-1833D01*
X537950Y-2167D01*
X538200Y-2667D01*
Y-5000D01*
G01X541300Y-1667D02*
Y-5000D01*
G01Y-333D02*
X541133Y-250D01*
Y-83D01*
X541300Y0D01*
X541467Y-83D01*
Y-250D01*
X541300Y-333D01*
G01X546900Y-5000D02*
Y0D01*
G01X270750Y-47833D02*
X271417Y-48250D01*
X272167Y-48500D01*
X272833D01*
X273500Y-48250D01*
X274000Y-47833D01*
X274250Y-47250D01*
X274083Y-46667D01*
X273667Y-46167D01*
X272917Y-45833D01*
X271917Y-45667D01*
X271333Y-45333D01*
X271083Y-44750D01*
X271250Y-44167D01*
X271667Y-43750D01*
X272250Y-43500D01*
X272833D01*
X273417Y-43667D01*
X273917Y-44083D01*
G01X278100Y-48500D02*
X277600Y-48417D01*
X277100Y-48083D01*
X276767Y-47500D01*
X276600Y-46833D01*
X276767Y-46167D01*
X277100Y-45583D01*
X277600Y-45250D01*
X278100Y-45167D01*
X278600Y-45250D01*
X279100Y-45583D01*
X279433Y-46167D01*
X279517Y-46833D01*
X279433Y-47500D01*
X279100Y-48083D01*
X278600Y-48417D01*
X278100Y-48500D01*
G01X283700D02*
Y-43500D01*
G01X290800D02*
Y-48500D01*
G01Y-47750D02*
X290467Y-48167D01*
X289967Y-48417D01*
X289383Y-48500D01*
X288717Y-48333D01*
X288217Y-47917D01*
X287883Y-47417D01*
X287800Y-46833D01*
X287883Y-46250D01*
X288217Y-45750D01*
X288717Y-45333D01*
X289383Y-45167D01*
X289967Y-45250D01*
X290383Y-45417D01*
X290800Y-45750D01*
G01X293650Y-46250D02*
X296317D01*
X296067Y-45667D01*
X295650Y-45333D01*
X295067Y-45167D01*
X294483Y-45250D01*
X293983Y-45500D01*
X293650Y-46083D01*
X293483Y-46583D01*
Y-47083D01*
X293650Y-47583D01*
X294067Y-48083D01*
X294567Y-48417D01*
X295150Y-48500D01*
X295733Y-48333D01*
X296317Y-47833D01*
G01X299333Y-48500D02*
Y-45167D01*
G01Y-45833D02*
X299750Y-45500D01*
X300167Y-45250D01*
X300750Y-45167D01*
X301167Y-45250D01*
X301667Y-45500D01*
G01X309200Y-48500D02*
Y-45167D01*
G01Y-46083D02*
X309450Y-45667D01*
X309867Y-45333D01*
X310450Y-45167D01*
X311033Y-45333D01*
X311450Y-45667D01*
X311700Y-46083D01*
Y-48500D01*
G01Y-46083D02*
X311950Y-45667D01*
X312367Y-45333D01*
X312950Y-45167D01*
X313533Y-45333D01*
X313950Y-45667D01*
X314200Y-46167D01*
Y-48500D01*
G01X318800D02*
Y-45167D01*
G01Y-45750D02*
X318467Y-45417D01*
X317967Y-45250D01*
X317383Y-45167D01*
X316800Y-45333D01*
X316300Y-45667D01*
X315967Y-46167D01*
X315800Y-46833D01*
X315967Y-47500D01*
X316300Y-48000D01*
X316800Y-48333D01*
X317383Y-48500D01*
X317967Y-48417D01*
X318467Y-48167D01*
X318800Y-47833D01*
G01X321650Y-47917D02*
X322067Y-48250D01*
X322650Y-48500D01*
X323150D01*
X323650Y-48333D01*
X323983Y-48083D01*
X324150Y-47750D01*
X324067Y-47250D01*
X323733Y-47000D01*
X322233Y-46500D01*
X321900Y-45917D01*
X322067Y-45500D01*
X322400Y-45250D01*
X322900Y-45167D01*
X323400Y-45250D01*
X323900Y-45500D01*
G01X327083Y-48500D02*
Y-43500D01*
G01X329750Y-45167D02*
X327083Y-47083D01*
G01X328167Y-46333D02*
X329917Y-48500D01*
G01X339700Y-43500D02*
Y-48500D01*
G01X338533Y-45167D02*
X340867D01*
G01X343883Y-48500D02*
Y-43500D01*
G01Y-45917D02*
X344300Y-45500D01*
X344717Y-45250D01*
X345383Y-45167D01*
X345883Y-45250D01*
X346467Y-45583D01*
X346717Y-46083D01*
Y-48500D01*
G01X350900Y-45167D02*
Y-48500D01*
G01Y-43833D02*
X350733Y-43750D01*
Y-43583D01*
X350900Y-43500D01*
X351067Y-43583D01*
Y-43750D01*
X350900Y-43833D01*
G01X357833Y-45583D02*
X357250Y-45250D01*
X356750Y-45167D01*
X356083Y-45333D01*
X355583Y-45667D01*
X355250Y-46250D01*
X355167Y-46833D01*
X355250Y-47417D01*
X355583Y-47917D01*
X356083Y-48333D01*
X356750Y-48500D01*
X357333Y-48333D01*
X357833Y-48000D01*
G01X360683Y-48500D02*
Y-43500D01*
G01X363350Y-45167D02*
X360683Y-47083D01*
G01X361767Y-46333D02*
X363517Y-48500D01*
G01X366283D02*
Y-45167D01*
G01Y-46000D02*
X366617Y-45583D01*
X367117Y-45250D01*
X367783Y-45167D01*
X368367Y-45250D01*
X368867Y-45583D01*
X369117Y-46167D01*
Y-48500D01*
G01X372050Y-46250D02*
X374717D01*
X374467Y-45667D01*
X374050Y-45333D01*
X373467Y-45167D01*
X372883Y-45250D01*
X372383Y-45500D01*
X372050Y-46083D01*
X371883Y-46583D01*
Y-47083D01*
X372050Y-47583D01*
X372467Y-48083D01*
X372967Y-48417D01*
X373550Y-48500D01*
X374133Y-48333D01*
X374717Y-47833D01*
G01X377650Y-47917D02*
X378067Y-48250D01*
X378650Y-48500D01*
X379150D01*
X379650Y-48333D01*
X379983Y-48083D01*
X380150Y-47750D01*
X380067Y-47250D01*
X379733Y-47000D01*
X378233Y-46500D01*
X377900Y-45917D01*
X378067Y-45500D01*
X378400Y-45250D01*
X378900Y-45167D01*
X379400Y-45250D01*
X379900Y-45500D01*
G01X383250Y-47917D02*
X383667Y-48250D01*
X384250Y-48500D01*
X384750D01*
X385250Y-48333D01*
X385583Y-48083D01*
X385750Y-47750D01*
X385667Y-47250D01*
X385333Y-47000D01*
X383833Y-46500D01*
X383500Y-45917D01*
X383667Y-45500D01*
X384000Y-45250D01*
X384500Y-45167D01*
X385000Y-45250D01*
X385500Y-45500D01*
G01X394200Y-50167D02*
Y-45167D01*
G01Y-45917D02*
X394617Y-45500D01*
X395033Y-45250D01*
X395700Y-45167D01*
X396283Y-45250D01*
X396867Y-45667D01*
X397117Y-46250D01*
X397200Y-46833D01*
X397117Y-47417D01*
X396867Y-48000D01*
X396367Y-48333D01*
X395700Y-48500D01*
X395117Y-48417D01*
X394533Y-48167D01*
X394200Y-47833D01*
G01X401300Y-48500D02*
Y-43500D01*
G01X405483Y-45167D02*
Y-47500D01*
X405817Y-48083D01*
X406317Y-48417D01*
X406900Y-48500D01*
X407483Y-48417D01*
X407983Y-48083D01*
X408317Y-47500D01*
G01Y-48500D02*
Y-45167D01*
G01X411250Y-47917D02*
X411667Y-48250D01*
X412250Y-48500D01*
X412750D01*
X413250Y-48333D01*
X413583Y-48083D01*
X413750Y-47750D01*
X413667Y-47250D01*
X413333Y-47000D01*
X411833Y-46500D01*
X411500Y-45917D01*
X411667Y-45500D01*
X412000Y-45250D01*
X412500Y-45167D01*
X413000Y-45250D01*
X413500Y-45500D01*
G01X423700Y-48500D02*
Y-43500D01*
G01X428050Y-46250D02*
X430717D01*
X430467Y-45667D01*
X430050Y-45333D01*
X429467Y-45167D01*
X428883Y-45250D01*
X428383Y-45500D01*
X428050Y-46083D01*
X427883Y-46583D01*
Y-47083D01*
X428050Y-47583D01*
X428467Y-48083D01*
X428967Y-48417D01*
X429550Y-48500D01*
X430133Y-48333D01*
X430717Y-47833D01*
G01X433733Y-49750D02*
X434317Y-50083D01*
X434983Y-50167D01*
X435567Y-50083D01*
X436067Y-49667D01*
X436400Y-49083D01*
Y-45167D01*
G01Y-45833D02*
X436067Y-45500D01*
X435567Y-45250D01*
X434983Y-45167D01*
X434317Y-45333D01*
X433900Y-45667D01*
X433567Y-46250D01*
X433400Y-46833D01*
X433483Y-47333D01*
X433817Y-47917D01*
X434317Y-48333D01*
X434983Y-48500D01*
X435483Y-48417D01*
X436067Y-48083D01*
X436400Y-47750D01*
G01X439250Y-46250D02*
X441917D01*
X441667Y-45667D01*
X441250Y-45333D01*
X440667Y-45167D01*
X440083Y-45250D01*
X439583Y-45500D01*
X439250Y-46083D01*
X439083Y-46583D01*
Y-47083D01*
X439250Y-47583D01*
X439667Y-48083D01*
X440167Y-48417D01*
X440750Y-48500D01*
X441333Y-48333D01*
X441917Y-47833D01*
G01X444683Y-48500D02*
Y-45167D01*
G01Y-46000D02*
X445017Y-45583D01*
X445517Y-45250D01*
X446183Y-45167D01*
X446767Y-45250D01*
X447267Y-45583D01*
X447517Y-46167D01*
Y-48500D01*
G01X453200Y-43500D02*
Y-48500D01*
G01Y-47750D02*
X452867Y-48167D01*
X452367Y-48417D01*
X451783Y-48500D01*
X451117Y-48333D01*
X450617Y-47917D01*
X450283Y-47417D01*
X450200Y-46833D01*
X450283Y-46250D01*
X450617Y-45750D01*
X451117Y-45333D01*
X451783Y-45167D01*
X452367Y-45250D01*
X452783Y-45417D01*
X453200Y-45750D01*
G01X462900Y-43500D02*
Y-48500D01*
G01X461733Y-45167D02*
X464067D01*
G01X467083Y-48500D02*
Y-43500D01*
G01Y-45917D02*
X467500Y-45500D01*
X467917Y-45250D01*
X468583Y-45167D01*
X469083Y-45250D01*
X469667Y-45583D01*
X469917Y-46083D01*
Y-48500D01*
G01X474100Y-45167D02*
Y-48500D01*
G01Y-43833D02*
X473933Y-43750D01*
Y-43583D01*
X474100Y-43500D01*
X474267Y-43583D01*
Y-43750D01*
X474100Y-43833D01*
G01X481033Y-45583D02*
X480450Y-45250D01*
X479950Y-45167D01*
X479283Y-45333D01*
X478783Y-45667D01*
X478450Y-46250D01*
X478367Y-46833D01*
X478450Y-47417D01*
X478783Y-47917D01*
X479283Y-48333D01*
X479950Y-48500D01*
X480533Y-48333D01*
X481033Y-48000D01*
G01X483883Y-48500D02*
Y-43500D01*
G01X486550Y-45167D02*
X483883Y-47083D01*
G01X484967Y-46333D02*
X486717Y-48500D01*
G01X489483D02*
Y-45167D01*
G01Y-46000D02*
X489817Y-45583D01*
X490317Y-45250D01*
X490983Y-45167D01*
X491567Y-45250D01*
X492067Y-45583D01*
X492317Y-46167D01*
Y-48500D01*
G01X495250Y-46250D02*
X497917D01*
X497667Y-45667D01*
X497250Y-45333D01*
X496667Y-45167D01*
X496083Y-45250D01*
X495583Y-45500D01*
X495250Y-46083D01*
X495083Y-46583D01*
Y-47083D01*
X495250Y-47583D01*
X495667Y-48083D01*
X496167Y-48417D01*
X496750Y-48500D01*
X497333Y-48333D01*
X497917Y-47833D01*
G01X500850Y-47917D02*
X501267Y-48250D01*
X501850Y-48500D01*
X502350D01*
X502850Y-48333D01*
X503183Y-48083D01*
X503350Y-47750D01*
X503267Y-47250D01*
X502933Y-47000D01*
X501433Y-46500D01*
X501100Y-45917D01*
X501267Y-45500D01*
X501600Y-45250D01*
X502100Y-45167D01*
X502600Y-45250D01*
X503100Y-45500D01*
G01X506450Y-47917D02*
X506867Y-48250D01*
X507450Y-48500D01*
X507950D01*
X508450Y-48333D01*
X508783Y-48083D01*
X508950Y-47750D01*
X508867Y-47250D01*
X508533Y-47000D01*
X507033Y-46500D01*
X506700Y-45917D01*
X506867Y-45500D01*
X507200Y-45250D01*
X507700Y-45167D01*
X508200Y-45250D01*
X508700Y-45500D01*
G01X518900Y-48500D02*
X518400Y-48417D01*
X517900Y-48083D01*
X517567Y-47500D01*
X517400Y-46833D01*
X517567Y-46167D01*
X517900Y-45583D01*
X518400Y-45250D01*
X518900Y-45167D01*
X519400Y-45250D01*
X519900Y-45583D01*
X520233Y-46167D01*
X520317Y-46833D01*
X520233Y-47500D01*
X519900Y-48083D01*
X519400Y-48417D01*
X518900Y-48500D01*
G01X523083D02*
Y-45167D01*
G01Y-46000D02*
X523417Y-45583D01*
X523917Y-45250D01*
X524583Y-45167D01*
X525167Y-45250D01*
X525667Y-45583D01*
X525917Y-46167D01*
Y-48500D01*
G01X535700Y-43500D02*
Y-48500D01*
G01X534533Y-45167D02*
X536867D01*
G01X540133Y-48500D02*
Y-45167D01*
G01Y-45833D02*
X540550Y-45500D01*
X540967Y-45250D01*
X541550Y-45167D01*
X541967Y-45250D01*
X542467Y-45500D01*
G01X548400Y-48500D02*
Y-45167D01*
G01Y-45750D02*
X548067Y-45417D01*
X547567Y-45250D01*
X546983Y-45167D01*
X546400Y-45333D01*
X545900Y-45667D01*
X545567Y-46167D01*
X545400Y-46833D01*
X545567Y-47500D01*
X545900Y-48000D01*
X546400Y-48333D01*
X546983Y-48500D01*
X547567Y-48417D01*
X548067Y-48167D01*
X548400Y-47833D01*
G01X553833Y-45583D02*
X553250Y-45250D01*
X552750Y-45167D01*
X552083Y-45333D01*
X551583Y-45667D01*
X551250Y-46250D01*
X551167Y-46833D01*
X551250Y-47417D01*
X551583Y-47917D01*
X552083Y-48333D01*
X552750Y-48500D01*
X553333Y-48333D01*
X553833Y-48000D01*
G01X556850Y-46250D02*
X559517D01*
X559267Y-45667D01*
X558850Y-45333D01*
X558267Y-45167D01*
X557683Y-45250D01*
X557183Y-45500D01*
X556850Y-46083D01*
X556683Y-46583D01*
Y-47083D01*
X556850Y-47583D01*
X557267Y-48083D01*
X557767Y-48417D01*
X558350Y-48500D01*
X558933Y-48333D01*
X559517Y-47833D01*
G01X563700Y-48667D02*
X563533Y-48583D01*
Y-48417D01*
X563700Y-48333D01*
X563867Y-48417D01*
Y-48583D01*
X563700Y-48667D01*
G01X272500Y-33500D02*
Y-28500D01*
G01X276850Y-31250D02*
X279517D01*
X279267Y-30667D01*
X278850Y-30333D01*
X278267Y-30167D01*
X277683Y-30250D01*
X277183Y-30500D01*
X276850Y-31083D01*
X276683Y-31583D01*
Y-32083D01*
X276850Y-32583D01*
X277267Y-33083D01*
X277767Y-33417D01*
X278350Y-33500D01*
X278933Y-33333D01*
X279517Y-32833D01*
G01X282533Y-34750D02*
X283117Y-35083D01*
X283783Y-35167D01*
X284367Y-35083D01*
X284867Y-34667D01*
X285200Y-34083D01*
Y-30167D01*
G01Y-30833D02*
X284867Y-30500D01*
X284367Y-30250D01*
X283783Y-30167D01*
X283117Y-30333D01*
X282700Y-30667D01*
X282367Y-31250D01*
X282200Y-31833D01*
X282283Y-32333D01*
X282617Y-32917D01*
X283117Y-33333D01*
X283783Y-33500D01*
X284283Y-33417D01*
X284867Y-33083D01*
X285200Y-32750D01*
G01X288050Y-31250D02*
X290717D01*
X290467Y-30667D01*
X290050Y-30333D01*
X289467Y-30167D01*
X288883Y-30250D01*
X288383Y-30500D01*
X288050Y-31083D01*
X287883Y-31583D01*
Y-32083D01*
X288050Y-32583D01*
X288467Y-33083D01*
X288967Y-33417D01*
X289550Y-33500D01*
X290133Y-33333D01*
X290717Y-32833D01*
G01X293483Y-33500D02*
Y-30167D01*
G01Y-31000D02*
X293817Y-30583D01*
X294317Y-30250D01*
X294983Y-30167D01*
X295567Y-30250D01*
X296067Y-30583D01*
X296317Y-31167D01*
Y-33500D01*
G01X302000Y-28500D02*
Y-33500D01*
G01Y-32750D02*
X301667Y-33167D01*
X301167Y-33417D01*
X300583Y-33500D01*
X299917Y-33333D01*
X299417Y-32917D01*
X299083Y-32417D01*
X299000Y-31833D01*
X299083Y-31250D01*
X299417Y-30750D01*
X299917Y-30333D01*
X300583Y-30167D01*
X301167Y-30250D01*
X301583Y-30417D01*
X302000Y-30750D01*
G01X311700Y-28500D02*
Y-33500D01*
G01X310533Y-30167D02*
X312867D01*
G01X315883Y-33500D02*
Y-28500D01*
G01Y-30917D02*
X316300Y-30500D01*
X316717Y-30250D01*
X317383Y-30167D01*
X317883Y-30250D01*
X318467Y-30583D01*
X318717Y-31083D01*
Y-33500D01*
G01X322900Y-30167D02*
Y-33500D01*
G01Y-28833D02*
X322733Y-28750D01*
Y-28583D01*
X322900Y-28500D01*
X323067Y-28583D01*
Y-28750D01*
X322900Y-28833D01*
G01X329833Y-30583D02*
X329250Y-30250D01*
X328750Y-30167D01*
X328083Y-30333D01*
X327583Y-30667D01*
X327250Y-31250D01*
X327167Y-31833D01*
X327250Y-32417D01*
X327583Y-32917D01*
X328083Y-33333D01*
X328750Y-33500D01*
X329333Y-33333D01*
X329833Y-33000D01*
G01X332683Y-33500D02*
Y-28500D01*
G01X335350Y-30167D02*
X332683Y-32083D01*
G01X333767Y-31333D02*
X335517Y-33500D01*
G01X338283D02*
Y-30167D01*
G01Y-31000D02*
X338617Y-30583D01*
X339117Y-30250D01*
X339783Y-30167D01*
X340367Y-30250D01*
X340867Y-30583D01*
X341117Y-31167D01*
Y-33500D01*
G01X344050Y-31250D02*
X346717D01*
X346467Y-30667D01*
X346050Y-30333D01*
X345467Y-30167D01*
X344883Y-30250D01*
X344383Y-30500D01*
X344050Y-31083D01*
X343883Y-31583D01*
Y-32083D01*
X344050Y-32583D01*
X344467Y-33083D01*
X344967Y-33417D01*
X345550Y-33500D01*
X346133Y-33333D01*
X346717Y-32833D01*
G01X349650Y-32917D02*
X350067Y-33250D01*
X350650Y-33500D01*
X351150D01*
X351650Y-33333D01*
X351983Y-33083D01*
X352150Y-32750D01*
X352067Y-32250D01*
X351733Y-32000D01*
X350233Y-31500D01*
X349900Y-30917D01*
X350067Y-30500D01*
X350400Y-30250D01*
X350900Y-30167D01*
X351400Y-30250D01*
X351900Y-30500D01*
G01X355250Y-32917D02*
X355667Y-33250D01*
X356250Y-33500D01*
X356750D01*
X357250Y-33333D01*
X357583Y-33083D01*
X357750Y-32750D01*
X357667Y-32250D01*
X357333Y-32000D01*
X355833Y-31500D01*
X355500Y-30917D01*
X355667Y-30500D01*
X356000Y-30250D01*
X356500Y-30167D01*
X357000Y-30250D01*
X357500Y-30500D01*
G01X367700Y-33500D02*
X367200Y-33417D01*
X366700Y-33083D01*
X366367Y-32500D01*
X366200Y-31833D01*
X366367Y-31167D01*
X366700Y-30583D01*
X367200Y-30250D01*
X367700Y-30167D01*
X368200Y-30250D01*
X368700Y-30583D01*
X369033Y-31167D01*
X369117Y-31833D01*
X369033Y-32500D01*
X368700Y-33083D01*
X368200Y-33417D01*
X367700Y-33500D01*
G01X371883D02*
Y-30167D01*
G01Y-31000D02*
X372217Y-30583D01*
X372717Y-30250D01*
X373383Y-30167D01*
X373967Y-30250D01*
X374467Y-30583D01*
X374717Y-31167D01*
Y-33500D01*
G01X385833Y-30583D02*
X385250Y-30250D01*
X384750Y-30167D01*
X384083Y-30333D01*
X383583Y-30667D01*
X383250Y-31250D01*
X383167Y-31833D01*
X383250Y-32417D01*
X383583Y-32917D01*
X384083Y-33333D01*
X384750Y-33500D01*
X385333Y-33333D01*
X385833Y-33000D01*
G01X390100Y-33500D02*
X389600Y-33417D01*
X389100Y-33083D01*
X388767Y-32500D01*
X388600Y-31833D01*
X388767Y-31167D01*
X389100Y-30583D01*
X389600Y-30250D01*
X390100Y-30167D01*
X390600Y-30250D01*
X391100Y-30583D01*
X391433Y-31167D01*
X391517Y-31833D01*
X391433Y-32500D01*
X391100Y-33083D01*
X390600Y-33417D01*
X390100Y-33500D01*
G01X394200Y-35167D02*
Y-30167D01*
G01Y-30917D02*
X394617Y-30500D01*
X395033Y-30250D01*
X395700Y-30167D01*
X396283Y-30250D01*
X396867Y-30667D01*
X397117Y-31250D01*
X397200Y-31833D01*
X397117Y-32417D01*
X396867Y-33000D01*
X396367Y-33333D01*
X395700Y-33500D01*
X395117Y-33417D01*
X394533Y-33167D01*
X394200Y-32833D01*
G01X399800Y-35167D02*
Y-30167D01*
G01Y-30917D02*
X400217Y-30500D01*
X400633Y-30250D01*
X401300Y-30167D01*
X401883Y-30250D01*
X402467Y-30667D01*
X402717Y-31250D01*
X402800Y-31833D01*
X402717Y-32417D01*
X402467Y-33000D01*
X401967Y-33333D01*
X401300Y-33500D01*
X400717Y-33417D01*
X400133Y-33167D01*
X399800Y-32833D01*
G01X405650Y-31250D02*
X408317D01*
X408067Y-30667D01*
X407650Y-30333D01*
X407067Y-30167D01*
X406483Y-30250D01*
X405983Y-30500D01*
X405650Y-31083D01*
X405483Y-31583D01*
Y-32083D01*
X405650Y-32583D01*
X406067Y-33083D01*
X406567Y-33417D01*
X407150Y-33500D01*
X407733Y-33333D01*
X408317Y-32833D01*
G01X411333Y-33500D02*
Y-30167D01*
G01Y-30833D02*
X411750Y-30500D01*
X412167Y-30250D01*
X412750Y-30167D01*
X413167Y-30250D01*
X413667Y-30500D01*
G01X423283Y-35167D02*
X422450Y-34333D01*
X422033Y-33500D01*
Y-30167D01*
X422450Y-29333D01*
X423283Y-28500D01*
G01X427217Y-30167D02*
X428217Y-33500D01*
X429300Y-30167D01*
X430383Y-33500D01*
X431383Y-30167D01*
G01X433483Y-33500D02*
Y-28500D01*
G01Y-30917D02*
X433900Y-30500D01*
X434317Y-30250D01*
X434983Y-30167D01*
X435483Y-30250D01*
X436067Y-30583D01*
X436317Y-31083D01*
Y-33500D01*
G01X440500Y-30167D02*
Y-33500D01*
G01Y-28833D02*
X440333Y-28750D01*
Y-28583D01*
X440500Y-28500D01*
X440667Y-28583D01*
Y-28750D01*
X440500Y-28833D01*
G01X447433Y-30583D02*
X446850Y-30250D01*
X446350Y-30167D01*
X445683Y-30333D01*
X445183Y-30667D01*
X444850Y-31250D01*
X444767Y-31833D01*
X444850Y-32417D01*
X445183Y-32917D01*
X445683Y-33333D01*
X446350Y-33500D01*
X446933Y-33333D01*
X447433Y-33000D01*
G01X450283Y-33500D02*
Y-28500D01*
G01Y-30917D02*
X450700Y-30500D01*
X451117Y-30250D01*
X451783Y-30167D01*
X452283Y-30250D01*
X452867Y-30583D01*
X453117Y-31083D01*
Y-33500D01*
G01X462900Y-30167D02*
Y-33500D01*
G01Y-28833D02*
X462733Y-28750D01*
Y-28583D01*
X462900Y-28500D01*
X463067Y-28583D01*
Y-28750D01*
X462900Y-28833D01*
G01X467250Y-32917D02*
X467667Y-33250D01*
X468250Y-33500D01*
X468750D01*
X469250Y-33333D01*
X469583Y-33083D01*
X469750Y-32750D01*
X469667Y-32250D01*
X469333Y-32000D01*
X467833Y-31500D01*
X467500Y-30917D01*
X467667Y-30500D01*
X468000Y-30250D01*
X468500Y-30167D01*
X469000Y-30250D01*
X469500Y-30500D01*
G01X478200Y-33500D02*
Y-28500D01*
G01Y-31000D02*
X478617Y-30500D01*
X479117Y-30250D01*
X479617Y-30167D01*
X480367Y-30333D01*
X480867Y-30667D01*
X481200Y-31250D01*
Y-31917D01*
X481033Y-32583D01*
X480700Y-33083D01*
X480117Y-33417D01*
X479617Y-33500D01*
X479117Y-33417D01*
X478617Y-33167D01*
X478200Y-32750D01*
G01X484050Y-31250D02*
X486717D01*
X486467Y-30667D01*
X486050Y-30333D01*
X485467Y-30167D01*
X484883Y-30250D01*
X484383Y-30500D01*
X484050Y-31083D01*
X483883Y-31583D01*
Y-32083D01*
X484050Y-32583D01*
X484467Y-33083D01*
X484967Y-33417D01*
X485550Y-33500D01*
X486133Y-33333D01*
X486717Y-32833D01*
G01X490900Y-28500D02*
Y-33500D01*
G01X489733Y-30167D02*
X492067D01*
G01X496500Y-28500D02*
Y-33500D01*
G01X495333Y-30167D02*
X497667D01*
G01X500850Y-31250D02*
X503517D01*
X503267Y-30667D01*
X502850Y-30333D01*
X502267Y-30167D01*
X501683Y-30250D01*
X501183Y-30500D01*
X500850Y-31083D01*
X500683Y-31583D01*
Y-32083D01*
X500850Y-32583D01*
X501267Y-33083D01*
X501767Y-33417D01*
X502350Y-33500D01*
X502933Y-33333D01*
X503517Y-32833D01*
G01X506533Y-33500D02*
Y-30167D01*
G01Y-30833D02*
X506950Y-30500D01*
X507367Y-30250D01*
X507950Y-30167D01*
X508367Y-30250D01*
X508867Y-30500D01*
G01X513717Y-35167D02*
X514550Y-34333D01*
X514967Y-33500D01*
Y-30167D01*
X514550Y-29333D01*
X513717Y-28500D01*
G01X271250Y-19417D02*
X271667Y-19750D01*
X272250Y-20000D01*
X272750D01*
X273250Y-19833D01*
X273583Y-19583D01*
X273750Y-19250D01*
X273667Y-18750D01*
X273333Y-18500D01*
X271833Y-18000D01*
X271500Y-17417D01*
X271667Y-17000D01*
X272000Y-16750D01*
X272500Y-16667D01*
X273000Y-16750D01*
X273500Y-17000D01*
G01X278100Y-20000D02*
X277600Y-19917D01*
X277100Y-19583D01*
X276767Y-19000D01*
X276600Y-18333D01*
X276767Y-17667D01*
X277100Y-17083D01*
X277600Y-16750D01*
X278100Y-16667D01*
X278600Y-16750D01*
X279100Y-17083D01*
X279433Y-17667D01*
X279517Y-18333D01*
X279433Y-19000D01*
X279100Y-19583D01*
X278600Y-19917D01*
X278100Y-20000D01*
G01X283700D02*
Y-15000D01*
G01X290800D02*
Y-20000D01*
G01Y-19250D02*
X290467Y-19667D01*
X289967Y-19917D01*
X289383Y-20000D01*
X288717Y-19833D01*
X288217Y-19417D01*
X287883Y-18917D01*
X287800Y-18333D01*
X287883Y-17750D01*
X288217Y-17250D01*
X288717Y-16833D01*
X289383Y-16667D01*
X289967Y-16750D01*
X290383Y-16917D01*
X290800Y-17250D01*
G01X293650Y-17750D02*
X296317D01*
X296067Y-17167D01*
X295650Y-16833D01*
X295067Y-16667D01*
X294483Y-16750D01*
X293983Y-17000D01*
X293650Y-17583D01*
X293483Y-18083D01*
Y-18583D01*
X293650Y-19083D01*
X294067Y-19583D01*
X294567Y-19917D01*
X295150Y-20000D01*
X295733Y-19833D01*
X296317Y-19333D01*
G01X299333Y-20000D02*
Y-16667D01*
G01Y-17333D02*
X299750Y-17000D01*
X300167Y-16750D01*
X300750Y-16667D01*
X301167Y-16750D01*
X301667Y-17000D01*
G01X309200Y-20000D02*
Y-16667D01*
G01Y-17583D02*
X309450Y-17167D01*
X309867Y-16833D01*
X310450Y-16667D01*
X311033Y-16833D01*
X311450Y-17167D01*
X311700Y-17583D01*
Y-20000D01*
G01Y-17583D02*
X311950Y-17167D01*
X312367Y-16833D01*
X312950Y-16667D01*
X313533Y-16833D01*
X313950Y-17167D01*
X314200Y-17667D01*
Y-20000D01*
G01X318800D02*
Y-16667D01*
G01Y-17250D02*
X318467Y-16917D01*
X317967Y-16750D01*
X317383Y-16667D01*
X316800Y-16833D01*
X316300Y-17167D01*
X315967Y-17667D01*
X315800Y-18333D01*
X315967Y-19000D01*
X316300Y-19500D01*
X316800Y-19833D01*
X317383Y-20000D01*
X317967Y-19917D01*
X318467Y-19667D01*
X318800Y-19333D01*
G01X321650Y-19417D02*
X322067Y-19750D01*
X322650Y-20000D01*
X323150D01*
X323650Y-19833D01*
X323983Y-19583D01*
X324150Y-19250D01*
X324067Y-18750D01*
X323733Y-18500D01*
X322233Y-18000D01*
X321900Y-17417D01*
X322067Y-17000D01*
X322400Y-16750D01*
X322900Y-16667D01*
X323400Y-16750D01*
X323900Y-17000D01*
G01X327083Y-20000D02*
Y-15000D01*
G01X329750Y-16667D02*
X327083Y-18583D01*
G01X328167Y-17833D02*
X329917Y-20000D01*
G01X339700Y-15000D02*
Y-20000D01*
G01X338533Y-16667D02*
X340867D01*
G01X343883Y-20000D02*
Y-15000D01*
G01Y-17417D02*
X344300Y-17000D01*
X344717Y-16750D01*
X345383Y-16667D01*
X345883Y-16750D01*
X346467Y-17083D01*
X346717Y-17583D01*
Y-20000D01*
G01X350900Y-16667D02*
Y-20000D01*
G01Y-15333D02*
X350733Y-15250D01*
Y-15083D01*
X350900Y-15000D01*
X351067Y-15083D01*
Y-15250D01*
X350900Y-15333D01*
G01X357833Y-17083D02*
X357250Y-16750D01*
X356750Y-16667D01*
X356083Y-16833D01*
X355583Y-17167D01*
X355250Y-17750D01*
X355167Y-18333D01*
X355250Y-18917D01*
X355583Y-19417D01*
X356083Y-19833D01*
X356750Y-20000D01*
X357333Y-19833D01*
X357833Y-19500D01*
G01X360683Y-20000D02*
Y-15000D01*
G01X363350Y-16667D02*
X360683Y-18583D01*
G01X361767Y-17833D02*
X363517Y-20000D01*
G01X366283D02*
Y-16667D01*
G01Y-17500D02*
X366617Y-17083D01*
X367117Y-16750D01*
X367783Y-16667D01*
X368367Y-16750D01*
X368867Y-17083D01*
X369117Y-17667D01*
Y-20000D01*
G01X372050Y-17750D02*
X374717D01*
X374467Y-17167D01*
X374050Y-16833D01*
X373467Y-16667D01*
X372883Y-16750D01*
X372383Y-17000D01*
X372050Y-17583D01*
X371883Y-18083D01*
Y-18583D01*
X372050Y-19083D01*
X372467Y-19583D01*
X372967Y-19917D01*
X373550Y-20000D01*
X374133Y-19833D01*
X374717Y-19333D01*
G01X377650Y-19417D02*
X378067Y-19750D01*
X378650Y-20000D01*
X379150D01*
X379650Y-19833D01*
X379983Y-19583D01*
X380150Y-19250D01*
X380067Y-18750D01*
X379733Y-18500D01*
X378233Y-18000D01*
X377900Y-17417D01*
X378067Y-17000D01*
X378400Y-16750D01*
X378900Y-16667D01*
X379400Y-16750D01*
X379900Y-17000D01*
G01X383250Y-19417D02*
X383667Y-19750D01*
X384250Y-20000D01*
X384750D01*
X385250Y-19833D01*
X385583Y-19583D01*
X385750Y-19250D01*
X385667Y-18750D01*
X385333Y-18500D01*
X383833Y-18000D01*
X383500Y-17417D01*
X383667Y-17000D01*
X384000Y-16750D01*
X384500Y-16667D01*
X385000Y-16750D01*
X385500Y-17000D01*
G01X273580Y32670D02*
Y27670D01*
G01X271663Y32670D02*
X275497D01*
G01X277763Y27670D02*
Y32670D01*
G01Y30253D02*
X278180Y30670D01*
X278597Y30920D01*
X279263Y31003D01*
X279763Y30920D01*
X280347Y30587D01*
X280597Y30087D01*
Y27670D01*
G01X283530Y29920D02*
X286197D01*
X285947Y30503D01*
X285530Y30837D01*
X284947Y31003D01*
X284363Y30920D01*
X283863Y30670D01*
X283530Y30087D01*
X283363Y29587D01*
Y29087D01*
X283530Y28587D01*
X283947Y28087D01*
X284447Y27753D01*
X285030Y27670D01*
X285613Y27837D01*
X286197Y28337D01*
G01X295980Y27670D02*
Y32670D01*
G01X303080Y27670D02*
Y31003D01*
G01Y30420D02*
X302747Y30753D01*
X302247Y30920D01*
X301663Y31003D01*
X301080Y30837D01*
X300580Y30503D01*
X300247Y30003D01*
X300080Y29337D01*
X300247Y28670D01*
X300580Y28170D01*
X301080Y27837D01*
X301663Y27670D01*
X302247Y27753D01*
X302747Y28003D01*
X303080Y28337D01*
G01X306013Y27670D02*
Y31003D01*
G01Y30337D02*
X306430Y30670D01*
X306847Y30920D01*
X307430Y31003D01*
X307847Y30920D01*
X308347Y30670D01*
G01X311613Y26420D02*
X312197Y26087D01*
X312863Y26003D01*
X313447Y26087D01*
X313947Y26503D01*
X314280Y27087D01*
Y31003D01*
G01Y30337D02*
X313947Y30670D01*
X313447Y30920D01*
X312863Y31003D01*
X312197Y30837D01*
X311780Y30503D01*
X311447Y29920D01*
X311280Y29337D01*
X311363Y28837D01*
X311697Y28253D01*
X312197Y27837D01*
X312863Y27670D01*
X313363Y27753D01*
X313947Y28087D01*
X314280Y28420D01*
G01X317130Y29920D02*
X319797D01*
X319547Y30503D01*
X319130Y30837D01*
X318547Y31003D01*
X317963Y30920D01*
X317463Y30670D01*
X317130Y30087D01*
X316963Y29587D01*
Y29087D01*
X317130Y28587D01*
X317547Y28087D01*
X318047Y27753D01*
X318630Y27670D01*
X319213Y27837D01*
X319797Y28337D01*
G01X322730Y28253D02*
X323147Y27920D01*
X323730Y27670D01*
X324230D01*
X324730Y27837D01*
X325063Y28087D01*
X325230Y28420D01*
X325147Y28920D01*
X324813Y29170D01*
X323313Y29670D01*
X322980Y30253D01*
X323147Y30670D01*
X323480Y30920D01*
X323980Y31003D01*
X324480Y30920D01*
X324980Y30670D01*
G01X329580Y32670D02*
Y27670D01*
G01X328413Y31003D02*
X330747D01*
G01X342280Y32670D02*
Y27670D01*
G01Y28420D02*
X341947Y28003D01*
X341447Y27753D01*
X340863Y27670D01*
X340197Y27837D01*
X339697Y28253D01*
X339363Y28753D01*
X339280Y29337D01*
X339363Y29920D01*
X339697Y30420D01*
X340197Y30837D01*
X340863Y31003D01*
X341447Y30920D01*
X341863Y30753D01*
X342280Y30420D01*
G01X346380Y31003D02*
Y27670D01*
G01Y32337D02*
X346213Y32420D01*
Y32587D01*
X346380Y32670D01*
X346547Y32587D01*
Y32420D01*
X346380Y32337D01*
G01X349480Y27670D02*
Y31003D01*
G01Y30087D02*
X349730Y30503D01*
X350147Y30837D01*
X350730Y31003D01*
X351313Y30837D01*
X351730Y30503D01*
X351980Y30087D01*
Y27670D01*
G01Y30087D02*
X352230Y30503D01*
X352647Y30837D01*
X353230Y31003D01*
X353813Y30837D01*
X354230Y30503D01*
X354480Y30003D01*
Y27670D01*
G01X356330Y29920D02*
X358997D01*
X358747Y30503D01*
X358330Y30837D01*
X357747Y31003D01*
X357163Y30920D01*
X356663Y30670D01*
X356330Y30087D01*
X356163Y29587D01*
Y29087D01*
X356330Y28587D01*
X356747Y28087D01*
X357247Y27753D01*
X357830Y27670D01*
X358413Y27837D01*
X358997Y28337D01*
G01X361763Y27670D02*
Y31003D01*
G01Y30170D02*
X362097Y30587D01*
X362597Y30920D01*
X363263Y31003D01*
X363847Y30920D01*
X364347Y30587D01*
X364597Y30003D01*
Y27670D01*
G01X367530Y28253D02*
X367947Y27920D01*
X368530Y27670D01*
X369030D01*
X369530Y27837D01*
X369863Y28087D01*
X370030Y28420D01*
X369947Y28920D01*
X369613Y29170D01*
X368113Y29670D01*
X367780Y30253D01*
X367947Y30670D01*
X368280Y30920D01*
X368780Y31003D01*
X369280Y30920D01*
X369780Y30670D01*
G01X374380Y31003D02*
Y27670D01*
G01Y32337D02*
X374213Y32420D01*
Y32587D01*
X374380Y32670D01*
X374547Y32587D01*
Y32420D01*
X374380Y32337D01*
G01X379980Y27670D02*
X379480Y27753D01*
X378980Y28087D01*
X378647Y28670D01*
X378480Y29337D01*
X378647Y30003D01*
X378980Y30587D01*
X379480Y30920D01*
X379980Y31003D01*
X380480Y30920D01*
X380980Y30587D01*
X381313Y30003D01*
X381397Y29337D01*
X381313Y28670D01*
X380980Y28087D01*
X380480Y27753D01*
X379980Y27670D01*
G01X384163D02*
Y31003D01*
G01Y30170D02*
X384497Y30587D01*
X384997Y30920D01*
X385663Y31003D01*
X386247Y30920D01*
X386747Y30587D01*
X386997Y30003D01*
Y27670D01*
G01X396780D02*
X396280Y27753D01*
X395780Y28087D01*
X395447Y28670D01*
X395280Y29337D01*
X395447Y30003D01*
X395780Y30587D01*
X396280Y30920D01*
X396780Y31003D01*
X397280Y30920D01*
X397780Y30587D01*
X398113Y30003D01*
X398197Y29337D01*
X398113Y28670D01*
X397780Y28087D01*
X397280Y27753D01*
X396780Y27670D01*
G01X401880D02*
Y31920D01*
X402047Y32337D01*
X402380Y32587D01*
X402880Y32670D01*
X403380Y32503D01*
X403630Y32087D01*
G01X402630Y30670D02*
X400963D01*
G01X412080Y26003D02*
Y31003D01*
G01Y30253D02*
X412497Y30670D01*
X412913Y30920D01*
X413580Y31003D01*
X414163Y30920D01*
X414747Y30503D01*
X414997Y29920D01*
X415080Y29337D01*
X414997Y28753D01*
X414747Y28170D01*
X414247Y27837D01*
X413580Y27670D01*
X412997Y27753D01*
X412413Y28003D01*
X412080Y28337D01*
G01X420680Y27670D02*
Y31003D01*
G01Y30420D02*
X420347Y30753D01*
X419847Y30920D01*
X419263Y31003D01*
X418680Y30837D01*
X418180Y30503D01*
X417847Y30003D01*
X417680Y29337D01*
X417847Y28670D01*
X418180Y28170D01*
X418680Y27837D01*
X419263Y27670D01*
X419847Y27753D01*
X420347Y28003D01*
X420680Y28337D01*
G01X426280Y32670D02*
Y27670D01*
G01Y28420D02*
X425947Y28003D01*
X425447Y27753D01*
X424863Y27670D01*
X424197Y27837D01*
X423697Y28253D01*
X423363Y28753D01*
X423280Y29337D01*
X423363Y29920D01*
X423697Y30420D01*
X424197Y30837D01*
X424863Y31003D01*
X425447Y30920D01*
X425863Y30753D01*
X426280Y30420D01*
G01X435980Y27670D02*
X435480Y27753D01*
X434980Y28087D01*
X434647Y28670D01*
X434480Y29337D01*
X434647Y30003D01*
X434980Y30587D01*
X435480Y30920D01*
X435980Y31003D01*
X436480Y30920D01*
X436980Y30587D01*
X437313Y30003D01*
X437397Y29337D01*
X437313Y28670D01*
X436980Y28087D01*
X436480Y27753D01*
X435980Y27670D01*
G01X440413D02*
Y31003D01*
G01Y30337D02*
X440830Y30670D01*
X441247Y30920D01*
X441830Y31003D01*
X442247Y30920D01*
X442747Y30670D01*
G01X454280Y32670D02*
Y27670D01*
G01Y28420D02*
X453947Y28003D01*
X453447Y27753D01*
X452863Y27670D01*
X452197Y27837D01*
X451697Y28253D01*
X451363Y28753D01*
X451280Y29337D01*
X451363Y29920D01*
X451697Y30420D01*
X452197Y30837D01*
X452863Y31003D01*
X453447Y30920D01*
X453863Y30753D01*
X454280Y30420D01*
G01X458380Y31003D02*
Y27670D01*
G01Y32337D02*
X458213Y32420D01*
Y32587D01*
X458380Y32670D01*
X458547Y32587D01*
Y32420D01*
X458380Y32337D01*
G01X465480Y27670D02*
Y31003D01*
G01Y30420D02*
X465147Y30753D01*
X464647Y30920D01*
X464063Y31003D01*
X463480Y30837D01*
X462980Y30503D01*
X462647Y30003D01*
X462480Y29337D01*
X462647Y28670D01*
X462980Y28170D01*
X463480Y27837D01*
X464063Y27670D01*
X464647Y27753D01*
X465147Y28003D01*
X465480Y28337D01*
G01X467080Y27670D02*
Y31003D01*
G01Y30087D02*
X467330Y30503D01*
X467747Y30837D01*
X468330Y31003D01*
X468913Y30837D01*
X469330Y30503D01*
X469580Y30087D01*
Y27670D01*
G01Y30087D02*
X469830Y30503D01*
X470247Y30837D01*
X470830Y31003D01*
X471413Y30837D01*
X471830Y30503D01*
X472080Y30003D01*
Y27670D01*
G01X473930Y29920D02*
X476597D01*
X476347Y30503D01*
X475930Y30837D01*
X475347Y31003D01*
X474763Y30920D01*
X474263Y30670D01*
X473930Y30087D01*
X473763Y29587D01*
Y29087D01*
X473930Y28587D01*
X474347Y28087D01*
X474847Y27753D01*
X475430Y27670D01*
X476013Y27837D01*
X476597Y28337D01*
G01X480780Y32670D02*
Y27670D01*
G01X479613Y31003D02*
X481947D01*
G01X485130Y29920D02*
X487797D01*
X487547Y30503D01*
X487130Y30837D01*
X486547Y31003D01*
X485963Y30920D01*
X485463Y30670D01*
X485130Y30087D01*
X484963Y29587D01*
Y29087D01*
X485130Y28587D01*
X485547Y28087D01*
X486047Y27753D01*
X486630Y27670D01*
X487213Y27837D01*
X487797Y28337D01*
G01X490813Y27670D02*
Y31003D01*
G01Y30337D02*
X491230Y30670D01*
X491647Y30920D01*
X492230Y31003D01*
X492647Y30920D01*
X493147Y30670D01*
G01X504847Y27670D02*
X501513Y29337D01*
X504847Y31003D01*
G01X507697Y28587D02*
X509863D01*
G01Y30087D02*
X507697D01*
G01X519980Y27670D02*
Y32670D01*
X518980Y31670D01*
G01Y27670D02*
X520980D01*
G01X526580D02*
Y32670D01*
X523497Y29087D01*
X527663D01*
G01X534280Y27670D02*
Y31003D01*
G01Y30087D02*
X534530Y30503D01*
X534947Y30837D01*
X535530Y31003D01*
X536113Y30837D01*
X536530Y30503D01*
X536780Y30087D01*
Y27670D01*
G01Y30087D02*
X537030Y30503D01*
X537447Y30837D01*
X538030Y31003D01*
X538613Y30837D01*
X539030Y30503D01*
X539280Y30003D01*
Y27670D01*
G01X542380Y31003D02*
Y27670D01*
G01Y32337D02*
X542213Y32420D01*
Y32587D01*
X542380Y32670D01*
X542547Y32587D01*
Y32420D01*
X542380Y32337D01*
G01X547980Y27670D02*
Y32670D01*
G01X272500Y15000D02*
Y10000D01*
G01X270583Y15000D02*
X274417D01*
G01X276683Y10000D02*
Y15000D01*
G01Y12583D02*
X277100Y13000D01*
X277517Y13250D01*
X278183Y13333D01*
X278683Y13250D01*
X279267Y12917D01*
X279517Y12417D01*
Y10000D01*
G01X282450Y12250D02*
X285117D01*
X284867Y12833D01*
X284450Y13167D01*
X283867Y13333D01*
X283283Y13250D01*
X282783Y13000D01*
X282450Y12417D01*
X282283Y11917D01*
Y11417D01*
X282450Y10917D01*
X282867Y10417D01*
X283367Y10083D01*
X283950Y10000D01*
X284533Y10167D01*
X285117Y10667D01*
G01X294900Y10000D02*
Y15000D01*
G01X302000Y10000D02*
Y13333D01*
G01Y12750D02*
X301667Y13083D01*
X301167Y13250D01*
X300583Y13333D01*
X300000Y13167D01*
X299500Y12833D01*
X299167Y12333D01*
X299000Y11667D01*
X299167Y11000D01*
X299500Y10500D01*
X300000Y10167D01*
X300583Y10000D01*
X301167Y10083D01*
X301667Y10333D01*
X302000Y10667D01*
G01X304933Y10000D02*
Y13333D01*
G01Y12667D02*
X305350Y13000D01*
X305767Y13250D01*
X306350Y13333D01*
X306767Y13250D01*
X307267Y13000D01*
G01X310533Y8750D02*
X311117Y8417D01*
X311783Y8333D01*
X312367Y8417D01*
X312867Y8833D01*
X313200Y9417D01*
Y13333D01*
G01Y12667D02*
X312867Y13000D01*
X312367Y13250D01*
X311783Y13333D01*
X311117Y13167D01*
X310700Y12833D01*
X310367Y12250D01*
X310200Y11667D01*
X310283Y11167D01*
X310617Y10583D01*
X311117Y10167D01*
X311783Y10000D01*
X312283Y10083D01*
X312867Y10417D01*
X313200Y10750D01*
G01X316050Y12250D02*
X318717D01*
X318467Y12833D01*
X318050Y13167D01*
X317467Y13333D01*
X316883Y13250D01*
X316383Y13000D01*
X316050Y12417D01*
X315883Y11917D01*
Y11417D01*
X316050Y10917D01*
X316467Y10417D01*
X316967Y10083D01*
X317550Y10000D01*
X318133Y10167D01*
X318717Y10667D01*
G01X321650Y10583D02*
X322067Y10250D01*
X322650Y10000D01*
X323150D01*
X323650Y10167D01*
X323983Y10417D01*
X324150Y10750D01*
X324067Y11250D01*
X323733Y11500D01*
X322233Y12000D01*
X321900Y12583D01*
X322067Y13000D01*
X322400Y13250D01*
X322900Y13333D01*
X323400Y13250D01*
X323900Y13000D01*
G01X328500Y15000D02*
Y10000D01*
G01X327333Y13333D02*
X329667D01*
G01X341200Y15000D02*
Y10000D01*
G01Y10750D02*
X340867Y10333D01*
X340367Y10083D01*
X339783Y10000D01*
X339117Y10167D01*
X338617Y10583D01*
X338283Y11083D01*
X338200Y11667D01*
X338283Y12250D01*
X338617Y12750D01*
X339117Y13167D01*
X339783Y13333D01*
X340367Y13250D01*
X340783Y13083D01*
X341200Y12750D01*
G01X345300Y13333D02*
Y10000D01*
G01Y14667D02*
X345133Y14750D01*
Y14917D01*
X345300Y15000D01*
X345467Y14917D01*
Y14750D01*
X345300Y14667D01*
G01X348400Y10000D02*
Y13333D01*
G01Y12417D02*
X348650Y12833D01*
X349067Y13167D01*
X349650Y13333D01*
X350233Y13167D01*
X350650Y12833D01*
X350900Y12417D01*
Y10000D01*
G01Y12417D02*
X351150Y12833D01*
X351567Y13167D01*
X352150Y13333D01*
X352733Y13167D01*
X353150Y12833D01*
X353400Y12333D01*
Y10000D01*
G01X355250Y12250D02*
X357917D01*
X357667Y12833D01*
X357250Y13167D01*
X356667Y13333D01*
X356083Y13250D01*
X355583Y13000D01*
X355250Y12417D01*
X355083Y11917D01*
Y11417D01*
X355250Y10917D01*
X355667Y10417D01*
X356167Y10083D01*
X356750Y10000D01*
X357333Y10167D01*
X357917Y10667D01*
G01X360683Y10000D02*
Y13333D01*
G01Y12500D02*
X361017Y12917D01*
X361517Y13250D01*
X362183Y13333D01*
X362767Y13250D01*
X363267Y12917D01*
X363517Y12333D01*
Y10000D01*
G01X366450Y10583D02*
X366867Y10250D01*
X367450Y10000D01*
X367950D01*
X368450Y10167D01*
X368783Y10417D01*
X368950Y10750D01*
X368867Y11250D01*
X368533Y11500D01*
X367033Y12000D01*
X366700Y12583D01*
X366867Y13000D01*
X367200Y13250D01*
X367700Y13333D01*
X368200Y13250D01*
X368700Y13000D01*
G01X373300Y13333D02*
Y10000D01*
G01Y14667D02*
X373133Y14750D01*
Y14917D01*
X373300Y15000D01*
X373467Y14917D01*
Y14750D01*
X373300Y14667D01*
G01X378900Y10000D02*
X378400Y10083D01*
X377900Y10417D01*
X377567Y11000D01*
X377400Y11667D01*
X377567Y12333D01*
X377900Y12917D01*
X378400Y13250D01*
X378900Y13333D01*
X379400Y13250D01*
X379900Y12917D01*
X380233Y12333D01*
X380317Y11667D01*
X380233Y11000D01*
X379900Y10417D01*
X379400Y10083D01*
X378900Y10000D01*
G01X383083D02*
Y13333D01*
G01Y12500D02*
X383417Y12917D01*
X383917Y13250D01*
X384583Y13333D01*
X385167Y13250D01*
X385667Y12917D01*
X385917Y12333D01*
Y10000D01*
G01X395700D02*
X395200Y10083D01*
X394700Y10417D01*
X394367Y11000D01*
X394200Y11667D01*
X394367Y12333D01*
X394700Y12917D01*
X395200Y13250D01*
X395700Y13333D01*
X396200Y13250D01*
X396700Y12917D01*
X397033Y12333D01*
X397117Y11667D01*
X397033Y11000D01*
X396700Y10417D01*
X396200Y10083D01*
X395700Y10000D01*
G01X400800D02*
Y14250D01*
X400967Y14667D01*
X401300Y14917D01*
X401800Y15000D01*
X402300Y14833D01*
X402550Y14417D01*
G01X401550Y13000D02*
X399883D01*
G01X411000Y8333D02*
Y13333D01*
G01Y12583D02*
X411417Y13000D01*
X411833Y13250D01*
X412500Y13333D01*
X413083Y13250D01*
X413667Y12833D01*
X413917Y12250D01*
X414000Y11667D01*
X413917Y11083D01*
X413667Y10500D01*
X413167Y10167D01*
X412500Y10000D01*
X411917Y10083D01*
X411333Y10333D01*
X411000Y10667D01*
G01X419600Y10000D02*
Y13333D01*
G01Y12750D02*
X419267Y13083D01*
X418767Y13250D01*
X418183Y13333D01*
X417600Y13167D01*
X417100Y12833D01*
X416767Y12333D01*
X416600Y11667D01*
X416767Y11000D01*
X417100Y10500D01*
X417600Y10167D01*
X418183Y10000D01*
X418767Y10083D01*
X419267Y10333D01*
X419600Y10667D01*
G01X425200Y15000D02*
Y10000D01*
G01Y10750D02*
X424867Y10333D01*
X424367Y10083D01*
X423783Y10000D01*
X423117Y10167D01*
X422617Y10583D01*
X422283Y11083D01*
X422200Y11667D01*
X422283Y12250D01*
X422617Y12750D01*
X423117Y13167D01*
X423783Y13333D01*
X424367Y13250D01*
X424783Y13083D01*
X425200Y12750D01*
G01X434900Y10000D02*
X434400Y10083D01*
X433900Y10417D01*
X433567Y11000D01*
X433400Y11667D01*
X433567Y12333D01*
X433900Y12917D01*
X434400Y13250D01*
X434900Y13333D01*
X435400Y13250D01*
X435900Y12917D01*
X436233Y12333D01*
X436317Y11667D01*
X436233Y11000D01*
X435900Y10417D01*
X435400Y10083D01*
X434900Y10000D01*
G01X439333D02*
Y13333D01*
G01Y12667D02*
X439750Y13000D01*
X440167Y13250D01*
X440750Y13333D01*
X441167Y13250D01*
X441667Y13000D01*
G01X453200Y15000D02*
Y10000D01*
G01Y10750D02*
X452867Y10333D01*
X452367Y10083D01*
X451783Y10000D01*
X451117Y10167D01*
X450617Y10583D01*
X450283Y11083D01*
X450200Y11667D01*
X450283Y12250D01*
X450617Y12750D01*
X451117Y13167D01*
X451783Y13333D01*
X452367Y13250D01*
X452783Y13083D01*
X453200Y12750D01*
G01X457300Y13333D02*
Y10000D01*
G01Y14667D02*
X457133Y14750D01*
Y14917D01*
X457300Y15000D01*
X457467Y14917D01*
Y14750D01*
X457300Y14667D01*
G01X464400Y10000D02*
Y13333D01*
G01Y12750D02*
X464067Y13083D01*
X463567Y13250D01*
X462983Y13333D01*
X462400Y13167D01*
X461900Y12833D01*
X461567Y12333D01*
X461400Y11667D01*
X461567Y11000D01*
X461900Y10500D01*
X462400Y10167D01*
X462983Y10000D01*
X463567Y10083D01*
X464067Y10333D01*
X464400Y10667D01*
G01X466000Y10000D02*
Y13333D01*
G01Y12417D02*
X466250Y12833D01*
X466667Y13167D01*
X467250Y13333D01*
X467833Y13167D01*
X468250Y12833D01*
X468500Y12417D01*
Y10000D01*
G01Y12417D02*
X468750Y12833D01*
X469167Y13167D01*
X469750Y13333D01*
X470333Y13167D01*
X470750Y12833D01*
X471000Y12333D01*
Y10000D01*
G01X472850Y12250D02*
X475517D01*
X475267Y12833D01*
X474850Y13167D01*
X474267Y13333D01*
X473683Y13250D01*
X473183Y13000D01*
X472850Y12417D01*
X472683Y11917D01*
Y11417D01*
X472850Y10917D01*
X473267Y10417D01*
X473767Y10083D01*
X474350Y10000D01*
X474933Y10167D01*
X475517Y10667D01*
G01X479700Y15000D02*
Y10000D01*
G01X478533Y13333D02*
X480867D01*
G01X484050Y12250D02*
X486717D01*
X486467Y12833D01*
X486050Y13167D01*
X485467Y13333D01*
X484883Y13250D01*
X484383Y13000D01*
X484050Y12417D01*
X483883Y11917D01*
Y11417D01*
X484050Y10917D01*
X484467Y10417D01*
X484967Y10083D01*
X485550Y10000D01*
X486133Y10167D01*
X486717Y10667D01*
G01X489733Y10000D02*
Y13333D01*
G01Y12667D02*
X490150Y13000D01*
X490567Y13250D01*
X491150Y13333D01*
X491567Y13250D01*
X492067Y13000D01*
G01X500433Y10000D02*
X503767Y11667D01*
X500433Y13333D01*
G01X507700Y10000D02*
Y15000D01*
X506700Y14000D01*
G01Y10000D02*
X508700D01*
G01X514300D02*
Y15000D01*
X511217Y11417D01*
X515383D01*
G01X522000Y10000D02*
Y13333D01*
G01Y12417D02*
X522250Y12833D01*
X522667Y13167D01*
X523250Y13333D01*
X523833Y13167D01*
X524250Y12833D01*
X524500Y12417D01*
Y10000D01*
G01Y12417D02*
X524750Y12833D01*
X525167Y13167D01*
X525750Y13333D01*
X526333Y13167D01*
X526750Y12833D01*
X527000Y12333D01*
Y10000D01*
G01X530100Y13333D02*
Y10000D01*
G01Y14667D02*
X529933Y14750D01*
Y14917D01*
X530100Y15000D01*
X530267Y14917D01*
Y14750D01*
X530100Y14667D01*
G01X535700Y10000D02*
Y15000D01*
G01X264000Y-39500D02*
X694500D01*
G01X264000Y5500D02*
X694500D01*
G01X272500Y101500D02*
Y96500D01*
G01X271333Y99833D02*
X273667D01*
G01X276933Y96500D02*
Y99833D01*
G01Y99167D02*
X277350Y99500D01*
X277767Y99750D01*
X278350Y99833D01*
X278767Y99750D01*
X279267Y99500D01*
G01X285200Y96500D02*
Y99833D01*
G01Y99250D02*
X284867Y99583D01*
X284367Y99750D01*
X283783Y99833D01*
X283200Y99667D01*
X282700Y99333D01*
X282367Y98833D01*
X282200Y98167D01*
X282367Y97500D01*
X282700Y97000D01*
X283200Y96667D01*
X283783Y96500D01*
X284367Y96583D01*
X284867Y96833D01*
X285200Y97167D01*
G01X290633Y99417D02*
X290050Y99750D01*
X289550Y99833D01*
X288883Y99667D01*
X288383Y99333D01*
X288050Y98750D01*
X287967Y98167D01*
X288050Y97583D01*
X288383Y97083D01*
X288883Y96667D01*
X289550Y96500D01*
X290133Y96667D01*
X290633Y97000D01*
G01X293650Y98750D02*
X296317D01*
X296067Y99333D01*
X295650Y99667D01*
X295067Y99833D01*
X294483Y99750D01*
X293983Y99500D01*
X293650Y98917D01*
X293483Y98417D01*
Y97917D01*
X293650Y97417D01*
X294067Y96917D01*
X294567Y96583D01*
X295150Y96500D01*
X295733Y96667D01*
X296317Y97167D01*
G01X304017Y99833D02*
X305017Y96500D01*
X306100Y99833D01*
X307183Y96500D01*
X308183Y99833D01*
G01X311700D02*
Y96500D01*
G01Y101167D02*
X311533Y101250D01*
Y101417D01*
X311700Y101500D01*
X311867Y101417D01*
Y101250D01*
X311700Y101167D01*
G01X318800Y101500D02*
Y96500D01*
G01Y97250D02*
X318467Y96833D01*
X317967Y96583D01*
X317383Y96500D01*
X316717Y96667D01*
X316217Y97083D01*
X315883Y97583D01*
X315800Y98167D01*
X315883Y98750D01*
X316217Y99250D01*
X316717Y99667D01*
X317383Y99833D01*
X317967Y99750D01*
X318383Y99583D01*
X318800Y99250D01*
G01X322900Y101500D02*
Y96500D01*
G01X321733Y99833D02*
X324067D01*
G01X327083Y96500D02*
Y101500D01*
G01Y99083D02*
X327500Y99500D01*
X327917Y99750D01*
X328583Y99833D01*
X329083Y99750D01*
X329667Y99417D01*
X329917Y98917D01*
Y96500D01*
G01X341367D02*
X338033Y98167D01*
X341367Y99833D01*
G01X344217Y97417D02*
X346383D01*
G01Y98917D02*
X344217D01*
G01X354667Y97250D02*
X355167Y96833D01*
X355750Y96583D01*
X356500Y96500D01*
X357250Y96667D01*
X357833Y97000D01*
X358250Y97583D01*
X358333Y98250D01*
X358167Y98917D01*
X357750Y99333D01*
X357167Y99667D01*
X356583Y99750D01*
X356000Y99667D01*
X355250Y99333D01*
X355500Y101500D01*
X357750D01*
G01X365200Y96500D02*
Y99833D01*
G01Y98917D02*
X365450Y99333D01*
X365867Y99667D01*
X366450Y99833D01*
X367033Y99667D01*
X367450Y99333D01*
X367700Y98917D01*
Y96500D01*
G01Y98917D02*
X367950Y99333D01*
X368367Y99667D01*
X368950Y99833D01*
X369533Y99667D01*
X369950Y99333D01*
X370200Y98833D01*
Y96500D01*
G01X373300Y99833D02*
Y96500D01*
G01Y101167D02*
X373133Y101250D01*
Y101417D01*
X373300Y101500D01*
X373467Y101417D01*
Y101250D01*
X373300Y101167D01*
G01X378900Y96500D02*
Y101500D01*
G01X270667Y82250D02*
X271167Y81833D01*
X271750Y81583D01*
X272500Y81500D01*
X273250Y81667D01*
X273833Y82000D01*
X274250Y82583D01*
X274333Y83250D01*
X274167Y83917D01*
X273750Y84333D01*
X273167Y84667D01*
X272583Y84750D01*
X272000Y84667D01*
X271250Y84333D01*
X271500Y86500D01*
X273750D01*
G01X281200Y81500D02*
Y84833D01*
G01Y83917D02*
X281450Y84333D01*
X281867Y84667D01*
X282450Y84833D01*
X283033Y84667D01*
X283450Y84333D01*
X283700Y83917D01*
Y81500D01*
G01Y83917D02*
X283950Y84333D01*
X284367Y84667D01*
X284950Y84833D01*
X285533Y84667D01*
X285950Y84333D01*
X286200Y83833D01*
Y81500D01*
G01X289300Y84833D02*
Y81500D01*
G01Y86167D02*
X289133Y86250D01*
Y86417D01*
X289300Y86500D01*
X289467Y86417D01*
Y86250D01*
X289300Y86167D01*
G01X294900Y81500D02*
Y86500D01*
G01X307767Y81500D02*
X304433Y83167D01*
X307767Y84833D01*
G01X317300Y86500D02*
Y81500D01*
G01X316133Y84833D02*
X318467D01*
G01X321733Y81500D02*
Y84833D01*
G01Y84167D02*
X322150Y84500D01*
X322567Y84750D01*
X323150Y84833D01*
X323567Y84750D01*
X324067Y84500D01*
G01X330000Y81500D02*
Y84833D01*
G01Y84250D02*
X329667Y84583D01*
X329167Y84750D01*
X328583Y84833D01*
X328000Y84667D01*
X327500Y84333D01*
X327167Y83833D01*
X327000Y83167D01*
X327167Y82500D01*
X327500Y82000D01*
X328000Y81667D01*
X328583Y81500D01*
X329167Y81583D01*
X329667Y81833D01*
X330000Y82167D01*
G01X335433Y84417D02*
X334850Y84750D01*
X334350Y84833D01*
X333683Y84667D01*
X333183Y84333D01*
X332850Y83750D01*
X332767Y83167D01*
X332850Y82583D01*
X333183Y82083D01*
X333683Y81667D01*
X334350Y81500D01*
X334933Y81667D01*
X335433Y82000D01*
G01X338450Y83750D02*
X341117D01*
X340867Y84333D01*
X340450Y84667D01*
X339867Y84833D01*
X339283Y84750D01*
X338783Y84500D01*
X338450Y83917D01*
X338283Y83417D01*
Y82917D01*
X338450Y82417D01*
X338867Y81917D01*
X339367Y81583D01*
X339950Y81500D01*
X340533Y81667D01*
X341117Y82167D01*
G01X348817Y84833D02*
X349817Y81500D01*
X350900Y84833D01*
X351983Y81500D01*
X352983Y84833D01*
G01X356500D02*
Y81500D01*
G01Y86167D02*
X356333Y86250D01*
Y86417D01*
X356500Y86500D01*
X356667Y86417D01*
Y86250D01*
X356500Y86167D01*
G01X363600Y86500D02*
Y81500D01*
G01Y82250D02*
X363267Y81833D01*
X362767Y81583D01*
X362183Y81500D01*
X361517Y81667D01*
X361017Y82083D01*
X360683Y82583D01*
X360600Y83167D01*
X360683Y83750D01*
X361017Y84250D01*
X361517Y84667D01*
X362183Y84833D01*
X362767Y84750D01*
X363183Y84583D01*
X363600Y84250D01*
G01X367700Y86500D02*
Y81500D01*
G01X366533Y84833D02*
X368867D01*
G01X371883Y81500D02*
Y86500D01*
G01Y84083D02*
X372300Y84500D01*
X372717Y84750D01*
X373383Y84833D01*
X373883Y84750D01*
X374467Y84417D01*
X374717Y83917D01*
Y81500D01*
G01X386167D02*
X382833Y83167D01*
X386167Y84833D01*
G01X389017Y82417D02*
X391183D01*
G01Y83917D02*
X389017D01*
G01X401133Y81500D02*
X401300Y82583D01*
X401550Y83500D01*
X401883Y84333D01*
X402300Y85250D01*
X402967Y86500D01*
X399633D01*
G01X410000Y81500D02*
Y84833D01*
G01Y83917D02*
X410250Y84333D01*
X410667Y84667D01*
X411250Y84833D01*
X411833Y84667D01*
X412250Y84333D01*
X412500Y83917D01*
Y81500D01*
G01Y83917D02*
X412750Y84333D01*
X413167Y84667D01*
X413750Y84833D01*
X414333Y84667D01*
X414750Y84333D01*
X415000Y83833D01*
Y81500D01*
G01X418100Y84833D02*
Y81500D01*
G01Y86167D02*
X417933Y86250D01*
Y86417D01*
X418100Y86500D01*
X418267Y86417D01*
Y86250D01*
X418100Y86167D01*
G01X423700Y81500D02*
Y86500D01*
G01X272500Y71500D02*
Y66500D01*
G01X271333Y69833D02*
X273667D01*
G01X276933Y66500D02*
Y69833D01*
G01Y69167D02*
X277350Y69500D01*
X277767Y69750D01*
X278350Y69833D01*
X278767Y69750D01*
X279267Y69500D01*
G01X285200Y66500D02*
Y69833D01*
G01Y69250D02*
X284867Y69583D01*
X284367Y69750D01*
X283783Y69833D01*
X283200Y69667D01*
X282700Y69333D01*
X282367Y68833D01*
X282200Y68167D01*
X282367Y67500D01*
X282700Y67000D01*
X283200Y66667D01*
X283783Y66500D01*
X284367Y66583D01*
X284867Y66833D01*
X285200Y67167D01*
G01X290633Y69417D02*
X290050Y69750D01*
X289550Y69833D01*
X288883Y69667D01*
X288383Y69333D01*
X288050Y68750D01*
X287967Y68167D01*
X288050Y67583D01*
X288383Y67083D01*
X288883Y66667D01*
X289550Y66500D01*
X290133Y66667D01*
X290633Y67000D01*
G01X293650Y68750D02*
X296317D01*
X296067Y69333D01*
X295650Y69667D01*
X295067Y69833D01*
X294483Y69750D01*
X293983Y69500D01*
X293650Y68917D01*
X293483Y68417D01*
Y67917D01*
X293650Y67417D01*
X294067Y66917D01*
X294567Y66583D01*
X295150Y66500D01*
X295733Y66667D01*
X296317Y67167D01*
G01X304017Y69833D02*
X305017Y66500D01*
X306100Y69833D01*
X307183Y66500D01*
X308183Y69833D01*
G01X311700D02*
Y66500D01*
G01Y71167D02*
X311533Y71250D01*
Y71417D01*
X311700Y71500D01*
X311867Y71417D01*
Y71250D01*
X311700Y71167D01*
G01X318800Y71500D02*
Y66500D01*
G01Y67250D02*
X318467Y66833D01*
X317967Y66583D01*
X317383Y66500D01*
X316717Y66667D01*
X316217Y67083D01*
X315883Y67583D01*
X315800Y68167D01*
X315883Y68750D01*
X316217Y69250D01*
X316717Y69667D01*
X317383Y69833D01*
X317967Y69750D01*
X318383Y69583D01*
X318800Y69250D01*
G01X322900Y71500D02*
Y66500D01*
G01X321733Y69833D02*
X324067D01*
G01X327083Y66500D02*
Y71500D01*
G01Y69083D02*
X327500Y69500D01*
X327917Y69750D01*
X328583Y69833D01*
X329083Y69750D01*
X329667Y69417D01*
X329917Y68917D01*
Y66500D01*
G01X338033D02*
X341367Y68167D01*
X338033Y69833D01*
G01X350733Y66500D02*
X350900Y67583D01*
X351150Y68500D01*
X351483Y69333D01*
X351900Y70250D01*
X352567Y71500D01*
X349233D01*
G01X359600Y66500D02*
Y69833D01*
G01Y68917D02*
X359850Y69333D01*
X360267Y69667D01*
X360850Y69833D01*
X361433Y69667D01*
X361850Y69333D01*
X362100Y68917D01*
Y66500D01*
G01Y68917D02*
X362350Y69333D01*
X362767Y69667D01*
X363350Y69833D01*
X363933Y69667D01*
X364350Y69333D01*
X364600Y68833D01*
Y66500D01*
G01X367700Y69833D02*
Y66500D01*
G01Y71167D02*
X367533Y71250D01*
Y71417D01*
X367700Y71500D01*
X367867Y71417D01*
Y71250D01*
X367700Y71167D01*
G01X373300Y66500D02*
Y71500D01*
G01X272500Y52000D02*
Y47000D01*
G01X270583Y52000D02*
X274417D01*
G01X276683Y47000D02*
Y52000D01*
G01Y49583D02*
X277100Y50000D01*
X277517Y50250D01*
X278183Y50333D01*
X278683Y50250D01*
X279267Y49917D01*
X279517Y49417D01*
Y47000D01*
G01X282450Y49250D02*
X285117D01*
X284867Y49833D01*
X284450Y50167D01*
X283867Y50333D01*
X283283Y50250D01*
X282783Y50000D01*
X282450Y49417D01*
X282283Y48917D01*
Y48417D01*
X282450Y47917D01*
X282867Y47417D01*
X283367Y47083D01*
X283950Y47000D01*
X284533Y47167D01*
X285117Y47667D01*
G01X294900Y47000D02*
Y52000D01*
G01X302000Y47000D02*
Y50333D01*
G01Y49750D02*
X301667Y50083D01*
X301167Y50250D01*
X300583Y50333D01*
X300000Y50167D01*
X299500Y49833D01*
X299167Y49333D01*
X299000Y48667D01*
X299167Y48000D01*
X299500Y47500D01*
X300000Y47167D01*
X300583Y47000D01*
X301167Y47083D01*
X301667Y47333D01*
X302000Y47667D01*
G01X304933Y47000D02*
Y50333D01*
G01Y49667D02*
X305350Y50000D01*
X305767Y50250D01*
X306350Y50333D01*
X306767Y50250D01*
X307267Y50000D01*
G01X310533Y45750D02*
X311117Y45417D01*
X311783Y45333D01*
X312367Y45417D01*
X312867Y45833D01*
X313200Y46417D01*
Y50333D01*
G01Y49667D02*
X312867Y50000D01*
X312367Y50250D01*
X311783Y50333D01*
X311117Y50167D01*
X310700Y49833D01*
X310367Y49250D01*
X310200Y48667D01*
X310283Y48167D01*
X310617Y47583D01*
X311117Y47167D01*
X311783Y47000D01*
X312283Y47083D01*
X312867Y47417D01*
X313200Y47750D01*
G01X316050Y49250D02*
X318717D01*
X318467Y49833D01*
X318050Y50167D01*
X317467Y50333D01*
X316883Y50250D01*
X316383Y50000D01*
X316050Y49417D01*
X315883Y48917D01*
Y48417D01*
X316050Y47917D01*
X316467Y47417D01*
X316967Y47083D01*
X317550Y47000D01*
X318133Y47167D01*
X318717Y47667D01*
G01X321650Y47583D02*
X322067Y47250D01*
X322650Y47000D01*
X323150D01*
X323650Y47167D01*
X323983Y47417D01*
X324150Y47750D01*
X324067Y48250D01*
X323733Y48500D01*
X322233Y49000D01*
X321900Y49583D01*
X322067Y50000D01*
X322400Y50250D01*
X322900Y50333D01*
X323400Y50250D01*
X323900Y50000D01*
G01X328500Y52000D02*
Y47000D01*
G01X327333Y50333D02*
X329667D01*
G01X341200Y52000D02*
Y47000D01*
G01Y47750D02*
X340867Y47333D01*
X340367Y47083D01*
X339783Y47000D01*
X339117Y47167D01*
X338617Y47583D01*
X338283Y48083D01*
X338200Y48667D01*
X338283Y49250D01*
X338617Y49750D01*
X339117Y50167D01*
X339783Y50333D01*
X340367Y50250D01*
X340783Y50083D01*
X341200Y49750D01*
G01X345300Y50333D02*
Y47000D01*
G01Y51667D02*
X345133Y51750D01*
Y51917D01*
X345300Y52000D01*
X345467Y51917D01*
Y51750D01*
X345300Y51667D01*
G01X348400Y47000D02*
Y50333D01*
G01Y49417D02*
X348650Y49833D01*
X349067Y50167D01*
X349650Y50333D01*
X350233Y50167D01*
X350650Y49833D01*
X350900Y49417D01*
Y47000D01*
G01Y49417D02*
X351150Y49833D01*
X351567Y50167D01*
X352150Y50333D01*
X352733Y50167D01*
X353150Y49833D01*
X353400Y49333D01*
Y47000D01*
G01X355250Y49250D02*
X357917D01*
X357667Y49833D01*
X357250Y50167D01*
X356667Y50333D01*
X356083Y50250D01*
X355583Y50000D01*
X355250Y49417D01*
X355083Y48917D01*
Y48417D01*
X355250Y47917D01*
X355667Y47417D01*
X356167Y47083D01*
X356750Y47000D01*
X357333Y47167D01*
X357917Y47667D01*
G01X360683Y47000D02*
Y50333D01*
G01Y49500D02*
X361017Y49917D01*
X361517Y50250D01*
X362183Y50333D01*
X362767Y50250D01*
X363267Y49917D01*
X363517Y49333D01*
Y47000D01*
G01X366450Y47583D02*
X366867Y47250D01*
X367450Y47000D01*
X367950D01*
X368450Y47167D01*
X368783Y47417D01*
X368950Y47750D01*
X368867Y48250D01*
X368533Y48500D01*
X367033Y49000D01*
X366700Y49583D01*
X366867Y50000D01*
X367200Y50250D01*
X367700Y50333D01*
X368200Y50250D01*
X368700Y50000D01*
G01X373300Y50333D02*
Y47000D01*
G01Y51667D02*
X373133Y51750D01*
Y51917D01*
X373300Y52000D01*
X373467Y51917D01*
Y51750D01*
X373300Y51667D01*
G01X378900Y47000D02*
X378400Y47083D01*
X377900Y47417D01*
X377567Y48000D01*
X377400Y48667D01*
X377567Y49333D01*
X377900Y49917D01*
X378400Y50250D01*
X378900Y50333D01*
X379400Y50250D01*
X379900Y49917D01*
X380233Y49333D01*
X380317Y48667D01*
X380233Y48000D01*
X379900Y47417D01*
X379400Y47083D01*
X378900Y47000D01*
G01X383083D02*
Y50333D01*
G01Y49500D02*
X383417Y49917D01*
X383917Y50250D01*
X384583Y50333D01*
X385167Y50250D01*
X385667Y49917D01*
X385917Y49333D01*
Y47000D01*
G01X395700D02*
X395200Y47083D01*
X394700Y47417D01*
X394367Y48000D01*
X394200Y48667D01*
X394367Y49333D01*
X394700Y49917D01*
X395200Y50250D01*
X395700Y50333D01*
X396200Y50250D01*
X396700Y49917D01*
X397033Y49333D01*
X397117Y48667D01*
X397033Y48000D01*
X396700Y47417D01*
X396200Y47083D01*
X395700Y47000D01*
G01X400800D02*
Y51250D01*
X400967Y51667D01*
X401300Y51917D01*
X401800Y52000D01*
X402300Y51833D01*
X402550Y51417D01*
G01X401550Y50000D02*
X399883D01*
G01X411000Y45333D02*
Y50333D01*
G01Y49583D02*
X411417Y50000D01*
X411833Y50250D01*
X412500Y50333D01*
X413083Y50250D01*
X413667Y49833D01*
X413917Y49250D01*
X414000Y48667D01*
X413917Y48083D01*
X413667Y47500D01*
X413167Y47167D01*
X412500Y47000D01*
X411917Y47083D01*
X411333Y47333D01*
X411000Y47667D01*
G01X419600Y47000D02*
Y50333D01*
G01Y49750D02*
X419267Y50083D01*
X418767Y50250D01*
X418183Y50333D01*
X417600Y50167D01*
X417100Y49833D01*
X416767Y49333D01*
X416600Y48667D01*
X416767Y48000D01*
X417100Y47500D01*
X417600Y47167D01*
X418183Y47000D01*
X418767Y47083D01*
X419267Y47333D01*
X419600Y47667D01*
G01X425200Y52000D02*
Y47000D01*
G01Y47750D02*
X424867Y47333D01*
X424367Y47083D01*
X423783Y47000D01*
X423117Y47167D01*
X422617Y47583D01*
X422283Y48083D01*
X422200Y48667D01*
X422283Y49250D01*
X422617Y49750D01*
X423117Y50167D01*
X423783Y50333D01*
X424367Y50250D01*
X424783Y50083D01*
X425200Y49750D01*
G01X434900Y47000D02*
X434400Y47083D01*
X433900Y47417D01*
X433567Y48000D01*
X433400Y48667D01*
X433567Y49333D01*
X433900Y49917D01*
X434400Y50250D01*
X434900Y50333D01*
X435400Y50250D01*
X435900Y49917D01*
X436233Y49333D01*
X436317Y48667D01*
X436233Y48000D01*
X435900Y47417D01*
X435400Y47083D01*
X434900Y47000D01*
G01X439333D02*
Y50333D01*
G01Y49667D02*
X439750Y50000D01*
X440167Y50250D01*
X440750Y50333D01*
X441167Y50250D01*
X441667Y50000D01*
G01X453200Y52000D02*
Y47000D01*
G01Y47750D02*
X452867Y47333D01*
X452367Y47083D01*
X451783Y47000D01*
X451117Y47167D01*
X450617Y47583D01*
X450283Y48083D01*
X450200Y48667D01*
X450283Y49250D01*
X450617Y49750D01*
X451117Y50167D01*
X451783Y50333D01*
X452367Y50250D01*
X452783Y50083D01*
X453200Y49750D01*
G01X457300Y50333D02*
Y47000D01*
G01Y51667D02*
X457133Y51750D01*
Y51917D01*
X457300Y52000D01*
X457467Y51917D01*
Y51750D01*
X457300Y51667D01*
G01X464400Y47000D02*
Y50333D01*
G01Y49750D02*
X464067Y50083D01*
X463567Y50250D01*
X462983Y50333D01*
X462400Y50167D01*
X461900Y49833D01*
X461567Y49333D01*
X461400Y48667D01*
X461567Y48000D01*
X461900Y47500D01*
X462400Y47167D01*
X462983Y47000D01*
X463567Y47083D01*
X464067Y47333D01*
X464400Y47667D01*
G01X466000Y47000D02*
Y50333D01*
G01Y49417D02*
X466250Y49833D01*
X466667Y50167D01*
X467250Y50333D01*
X467833Y50167D01*
X468250Y49833D01*
X468500Y49417D01*
Y47000D01*
G01Y49417D02*
X468750Y49833D01*
X469167Y50167D01*
X469750Y50333D01*
X470333Y50167D01*
X470750Y49833D01*
X471000Y49333D01*
Y47000D01*
G01X472850Y49250D02*
X475517D01*
X475267Y49833D01*
X474850Y50167D01*
X474267Y50333D01*
X473683Y50250D01*
X473183Y50000D01*
X472850Y49417D01*
X472683Y48917D01*
Y48417D01*
X472850Y47917D01*
X473267Y47417D01*
X473767Y47083D01*
X474350Y47000D01*
X474933Y47167D01*
X475517Y47667D01*
G01X479700Y52000D02*
Y47000D01*
G01X478533Y50333D02*
X480867D01*
G01X484050Y49250D02*
X486717D01*
X486467Y49833D01*
X486050Y50167D01*
X485467Y50333D01*
X484883Y50250D01*
X484383Y50000D01*
X484050Y49417D01*
X483883Y48917D01*
Y48417D01*
X484050Y47917D01*
X484467Y47417D01*
X484967Y47083D01*
X485550Y47000D01*
X486133Y47167D01*
X486717Y47667D01*
G01X489733Y47000D02*
Y50333D01*
G01Y49667D02*
X490150Y50000D01*
X490567Y50250D01*
X491150Y50333D01*
X491567Y50250D01*
X492067Y50000D01*
G01X500433Y47000D02*
X503767Y48667D01*
X500433Y50333D01*
G01X513300Y47000D02*
Y52000D01*
X512300Y51000D01*
G01Y47000D02*
X514300D01*
G01X519900D02*
Y52000D01*
X516817Y48417D01*
X520983D01*
G01X527600Y47000D02*
Y50333D01*
G01Y49417D02*
X527850Y49833D01*
X528267Y50167D01*
X528850Y50333D01*
X529433Y50167D01*
X529850Y49833D01*
X530100Y49417D01*
Y47000D01*
G01Y49417D02*
X530350Y49833D01*
X530767Y50167D01*
X531350Y50333D01*
X531933Y50167D01*
X532350Y49833D01*
X532600Y49333D01*
Y47000D01*
G01X535700Y50333D02*
Y47000D01*
G01Y51667D02*
X535533Y51750D01*
Y51917D01*
X535700Y52000D01*
X535867Y51917D01*
Y51750D01*
X535700Y51667D01*
G01X541300Y47000D02*
Y52000D01*
G01X270833Y110000D02*
Y115000D01*
X272917D01*
X273583Y114750D01*
X274000Y114417D01*
X274167Y113750D01*
X274000Y113083D01*
X273500Y112667D01*
X272917Y112417D01*
X270833D01*
G01X272917D02*
X274167Y110000D01*
G01X276850Y112250D02*
X279517D01*
X279267Y112833D01*
X278850Y113167D01*
X278267Y113333D01*
X277683Y113250D01*
X277183Y113000D01*
X276850Y112417D01*
X276683Y111917D01*
Y111417D01*
X276850Y110917D01*
X277267Y110417D01*
X277767Y110083D01*
X278350Y110000D01*
X278933Y110167D01*
X279517Y110667D01*
G01X283700Y110000D02*
Y115000D01*
G01X290800Y110000D02*
Y113333D01*
G01Y112750D02*
X290467Y113083D01*
X289967Y113250D01*
X289383Y113333D01*
X288800Y113167D01*
X288300Y112833D01*
X287967Y112333D01*
X287800Y111667D01*
X287967Y111000D01*
X288300Y110500D01*
X288800Y110167D01*
X289383Y110000D01*
X289967Y110083D01*
X290467Y110333D01*
X290800Y110667D01*
G01X294900Y115000D02*
Y110000D01*
G01X293733Y113333D02*
X296067D01*
G01X300500D02*
Y110000D01*
G01Y114667D02*
X300333Y114750D01*
Y114917D01*
X300500Y115000D01*
X300667Y114917D01*
Y114750D01*
X300500Y114667D01*
G01X304600Y113333D02*
X306100Y110000D01*
X307600Y113333D01*
G01X310450Y112250D02*
X313117D01*
X312867Y112833D01*
X312450Y113167D01*
X311867Y113333D01*
X311283Y113250D01*
X310783Y113000D01*
X310450Y112417D01*
X310283Y111917D01*
Y111417D01*
X310450Y110917D01*
X310867Y110417D01*
X311367Y110083D01*
X311950Y110000D01*
X312533Y110167D01*
X313117Y110667D01*
G01X321400Y108333D02*
Y113333D01*
G01Y112583D02*
X321817Y113000D01*
X322233Y113250D01*
X322900Y113333D01*
X323483Y113250D01*
X324067Y112833D01*
X324317Y112250D01*
X324400Y111667D01*
X324317Y111083D01*
X324067Y110500D01*
X323567Y110167D01*
X322900Y110000D01*
X322317Y110083D01*
X321733Y110333D01*
X321400Y110667D01*
G01X328500Y110000D02*
X328000Y110083D01*
X327500Y110417D01*
X327167Y111000D01*
X327000Y111667D01*
X327167Y112333D01*
X327500Y112917D01*
X328000Y113250D01*
X328500Y113333D01*
X329000Y113250D01*
X329500Y112917D01*
X329833Y112333D01*
X329917Y111667D01*
X329833Y111000D01*
X329500Y110417D01*
X329000Y110083D01*
X328500Y110000D01*
G01X332850Y110583D02*
X333267Y110250D01*
X333850Y110000D01*
X334350D01*
X334850Y110167D01*
X335183Y110417D01*
X335350Y110750D01*
X335267Y111250D01*
X334933Y111500D01*
X333433Y112000D01*
X333100Y112583D01*
X333267Y113000D01*
X333600Y113250D01*
X334100Y113333D01*
X334600Y113250D01*
X335100Y113000D01*
G01X339700Y113333D02*
Y110000D01*
G01Y114667D02*
X339533Y114750D01*
Y114917D01*
X339700Y115000D01*
X339867Y114917D01*
Y114750D01*
X339700Y114667D01*
G01X345300Y115000D02*
Y110000D01*
G01X344133Y113333D02*
X346467D01*
G01X350900D02*
Y110000D01*
G01Y114667D02*
X350733Y114750D01*
Y114917D01*
X350900Y115000D01*
X351067Y114917D01*
Y114750D01*
X350900Y114667D01*
G01X356500Y110000D02*
X356000Y110083D01*
X355500Y110417D01*
X355167Y111000D01*
X355000Y111667D01*
X355167Y112333D01*
X355500Y112917D01*
X356000Y113250D01*
X356500Y113333D01*
X357000Y113250D01*
X357500Y112917D01*
X357833Y112333D01*
X357917Y111667D01*
X357833Y111000D01*
X357500Y110417D01*
X357000Y110083D01*
X356500Y110000D01*
G01X360683D02*
Y113333D01*
G01Y112500D02*
X361017Y112917D01*
X361517Y113250D01*
X362183Y113333D01*
X362767Y113250D01*
X363267Y112917D01*
X363517Y112333D01*
Y110000D01*
G01X371800D02*
Y115000D01*
G01Y112500D02*
X372217Y113000D01*
X372717Y113250D01*
X373217Y113333D01*
X373967Y113167D01*
X374467Y112833D01*
X374800Y112250D01*
Y111583D01*
X374633Y110917D01*
X374300Y110417D01*
X373717Y110083D01*
X373217Y110000D01*
X372717Y110083D01*
X372217Y110333D01*
X371800Y110750D01*
G01X377650Y112250D02*
X380317D01*
X380067Y112833D01*
X379650Y113167D01*
X379067Y113333D01*
X378483Y113250D01*
X377983Y113000D01*
X377650Y112417D01*
X377483Y111917D01*
Y111417D01*
X377650Y110917D01*
X378067Y110417D01*
X378567Y110083D01*
X379150Y110000D01*
X379733Y110167D01*
X380317Y110667D01*
G01X384500Y115000D02*
Y110000D01*
G01X383333Y113333D02*
X385667D01*
G01X388017D02*
X389017Y110000D01*
X390100Y113333D01*
X391183Y110000D01*
X392183Y113333D01*
G01X394450Y112250D02*
X397117D01*
X396867Y112833D01*
X396450Y113167D01*
X395867Y113333D01*
X395283Y113250D01*
X394783Y113000D01*
X394450Y112417D01*
X394283Y111917D01*
Y111417D01*
X394450Y110917D01*
X394867Y110417D01*
X395367Y110083D01*
X395950Y110000D01*
X396533Y110167D01*
X397117Y110667D01*
G01X400050Y112250D02*
X402717D01*
X402467Y112833D01*
X402050Y113167D01*
X401467Y113333D01*
X400883Y113250D01*
X400383Y113000D01*
X400050Y112417D01*
X399883Y111917D01*
Y111417D01*
X400050Y110917D01*
X400467Y110417D01*
X400967Y110083D01*
X401550Y110000D01*
X402133Y110167D01*
X402717Y110667D01*
G01X405483Y110000D02*
Y113333D01*
G01Y112500D02*
X405817Y112917D01*
X406317Y113250D01*
X406983Y113333D01*
X407567Y113250D01*
X408067Y112917D01*
X408317Y112333D01*
Y110000D01*
G01X419600D02*
Y113333D01*
G01Y112750D02*
X419267Y113083D01*
X418767Y113250D01*
X418183Y113333D01*
X417600Y113167D01*
X417100Y112833D01*
X416767Y112333D01*
X416600Y111667D01*
X416767Y111000D01*
X417100Y110500D01*
X417600Y110167D01*
X418183Y110000D01*
X418767Y110083D01*
X419267Y110333D01*
X419600Y110667D01*
G01X422283Y110000D02*
Y113333D01*
G01Y112500D02*
X422617Y112917D01*
X423117Y113250D01*
X423783Y113333D01*
X424367Y113250D01*
X424867Y112917D01*
X425117Y112333D01*
Y110000D01*
G01X427550Y108500D02*
X428050Y108333D01*
X428717Y108500D01*
X429133Y108833D01*
X429467Y109250D01*
X429967Y110583D01*
X431050Y113333D01*
G01X428383D02*
X429967Y110583D01*
G01X439000Y108333D02*
Y113333D01*
G01Y112583D02*
X439417Y113000D01*
X439833Y113250D01*
X440500Y113333D01*
X441083Y113250D01*
X441667Y112833D01*
X441917Y112250D01*
X442000Y111667D01*
X441917Y111083D01*
X441667Y110500D01*
X441167Y110167D01*
X440500Y110000D01*
X439917Y110083D01*
X439333Y110333D01*
X439000Y110667D01*
G01X447600Y110000D02*
Y113333D01*
G01Y112750D02*
X447267Y113083D01*
X446767Y113250D01*
X446183Y113333D01*
X445600Y113167D01*
X445100Y112833D01*
X444767Y112333D01*
X444600Y111667D01*
X444767Y111000D01*
X445100Y110500D01*
X445600Y110167D01*
X446183Y110000D01*
X446767Y110083D01*
X447267Y110333D01*
X447600Y110667D01*
G01X453200Y115000D02*
Y110000D01*
G01Y110750D02*
X452867Y110333D01*
X452367Y110083D01*
X451783Y110000D01*
X451117Y110167D01*
X450617Y110583D01*
X450283Y111083D01*
X450200Y111667D01*
X450283Y112250D01*
X450617Y112750D01*
X451117Y113167D01*
X451783Y113333D01*
X452367Y113250D01*
X452783Y113083D01*
X453200Y112750D01*
G01X462900Y115000D02*
Y110000D01*
G01X461733Y113333D02*
X464067D01*
G01X468500Y110000D02*
X468000Y110083D01*
X467500Y110417D01*
X467167Y111000D01*
X467000Y111667D01*
X467167Y112333D01*
X467500Y112917D01*
X468000Y113250D01*
X468500Y113333D01*
X469000Y113250D01*
X469500Y112917D01*
X469833Y112333D01*
X469917Y111667D01*
X469833Y111000D01*
X469500Y110417D01*
X469000Y110083D01*
X468500Y110000D01*
G01X478200Y108333D02*
Y113333D01*
G01Y112583D02*
X478617Y113000D01*
X479033Y113250D01*
X479700Y113333D01*
X480283Y113250D01*
X480867Y112833D01*
X481117Y112250D01*
X481200Y111667D01*
X481117Y111083D01*
X480867Y110500D01*
X480367Y110167D01*
X479700Y110000D01*
X479117Y110083D01*
X478533Y110333D01*
X478200Y110667D01*
G01X486800Y110000D02*
Y113333D01*
G01Y112750D02*
X486467Y113083D01*
X485967Y113250D01*
X485383Y113333D01*
X484800Y113167D01*
X484300Y112833D01*
X483967Y112333D01*
X483800Y111667D01*
X483967Y111000D01*
X484300Y110500D01*
X484800Y110167D01*
X485383Y110000D01*
X485967Y110083D01*
X486467Y110333D01*
X486800Y110667D01*
G01X492400Y115000D02*
Y110000D01*
G01Y110750D02*
X492067Y110333D01*
X491567Y110083D01*
X490983Y110000D01*
X490317Y110167D01*
X489817Y110583D01*
X489483Y111083D01*
X489400Y111667D01*
X489483Y112250D01*
X489817Y112750D01*
X490317Y113167D01*
X490983Y113333D01*
X491567Y113250D01*
X491983Y113083D01*
X492400Y112750D01*
G01X264000Y40500D02*
X694500D01*
G01X264000Y75500D02*
X694500D01*
G01X264000Y90500D02*
X694500D01*
G01X271250Y141583D02*
X271667Y141250D01*
X272250Y141000D01*
X272750D01*
X273250Y141167D01*
X273583Y141417D01*
X273750Y141750D01*
X273667Y142250D01*
X273333Y142500D01*
X271833Y143000D01*
X271500Y143583D01*
X271667Y144000D01*
X272000Y144250D01*
X272500Y144333D01*
X273000Y144250D01*
X273500Y144000D01*
G01X276600Y139333D02*
Y144333D01*
G01Y143583D02*
X277017Y144000D01*
X277433Y144250D01*
X278100Y144333D01*
X278683Y144250D01*
X279267Y143833D01*
X279517Y143250D01*
X279600Y142667D01*
X279517Y142083D01*
X279267Y141500D01*
X278767Y141167D01*
X278100Y141000D01*
X277517Y141083D01*
X276933Y141333D01*
X276600Y141667D01*
G01X282450Y143250D02*
X285117D01*
X284867Y143833D01*
X284450Y144167D01*
X283867Y144333D01*
X283283Y144250D01*
X282783Y144000D01*
X282450Y143417D01*
X282283Y142917D01*
Y142417D01*
X282450Y141917D01*
X282867Y141417D01*
X283367Y141083D01*
X283950Y141000D01*
X284533Y141167D01*
X285117Y141667D01*
G01X290633Y143917D02*
X290050Y144250D01*
X289550Y144333D01*
X288883Y144167D01*
X288383Y143833D01*
X288050Y143250D01*
X287967Y142667D01*
X288050Y142083D01*
X288383Y141583D01*
X288883Y141167D01*
X289550Y141000D01*
X290133Y141167D01*
X290633Y141500D01*
G01X294900Y144333D02*
Y141000D01*
G01Y145667D02*
X294733Y145750D01*
Y145917D01*
X294900Y146000D01*
X295067Y145917D01*
Y145750D01*
X294900Y145667D01*
G01X300000Y141000D02*
Y145250D01*
X300167Y145667D01*
X300500Y145917D01*
X301000Y146000D01*
X301500Y145833D01*
X301750Y145417D01*
G01X300750Y144000D02*
X299083D01*
G01X306100Y144333D02*
Y141000D01*
G01Y145667D02*
X305933Y145750D01*
Y145917D01*
X306100Y146000D01*
X306267Y145917D01*
Y145750D01*
X306100Y145667D01*
G01X313033Y143917D02*
X312450Y144250D01*
X311950Y144333D01*
X311283Y144167D01*
X310783Y143833D01*
X310450Y143250D01*
X310367Y142667D01*
X310450Y142083D01*
X310783Y141583D01*
X311283Y141167D01*
X311950Y141000D01*
X312533Y141167D01*
X313033Y141500D01*
G01X318800Y141000D02*
Y144333D01*
G01Y143750D02*
X318467Y144083D01*
X317967Y144250D01*
X317383Y144333D01*
X316800Y144167D01*
X316300Y143833D01*
X315967Y143333D01*
X315800Y142667D01*
X315967Y142000D01*
X316300Y141500D01*
X316800Y141167D01*
X317383Y141000D01*
X317967Y141083D01*
X318467Y141333D01*
X318800Y141667D01*
G01X322900Y146000D02*
Y141000D01*
G01X321733Y144333D02*
X324067D01*
G01X328500D02*
Y141000D01*
G01Y145667D02*
X328333Y145750D01*
Y145917D01*
X328500Y146000D01*
X328667Y145917D01*
Y145750D01*
X328500Y145667D01*
G01X334100Y141000D02*
X333600Y141083D01*
X333100Y141417D01*
X332767Y142000D01*
X332600Y142667D01*
X332767Y143333D01*
X333100Y143917D01*
X333600Y144250D01*
X334100Y144333D01*
X334600Y144250D01*
X335100Y143917D01*
X335433Y143333D01*
X335517Y142667D01*
X335433Y142000D01*
X335100Y141417D01*
X334600Y141083D01*
X334100Y141000D01*
G01X338283D02*
Y144333D01*
G01Y143500D02*
X338617Y143917D01*
X339117Y144250D01*
X339783Y144333D01*
X340367Y144250D01*
X340867Y143917D01*
X341117Y143333D01*
Y141000D01*
G01X345300Y140833D02*
X345133Y140917D01*
Y141083D01*
X345300Y141167D01*
X345467Y141083D01*
Y140917D01*
X345300Y140833D01*
G01X270750Y125000D02*
Y130000D01*
G01X274250D02*
Y125000D01*
G01Y127500D02*
X270750D01*
G01X276267Y125000D02*
Y130000D01*
X277933D01*
X278600Y129750D01*
X279100Y129417D01*
X279517Y128917D01*
X279850Y128333D01*
X279933Y127500D01*
X279850Y126667D01*
X279517Y126083D01*
X279100Y125583D01*
X278600Y125250D01*
X277933Y125000D01*
X276267D01*
G01X282700Y130000D02*
X284700D01*
G01X283700D02*
Y125000D01*
G01X282700D02*
X284700D01*
G01X293233D02*
Y130000D01*
X295233D01*
X295900Y129750D01*
X296400Y129167D01*
X296567Y128500D01*
X296400Y127833D01*
X295983Y127333D01*
X295233Y127083D01*
X293233D01*
G01X302333Y129583D02*
X301833Y129833D01*
X301250Y130000D01*
X300583D01*
X299833Y129750D01*
X299250Y129333D01*
X298833Y128833D01*
X298500Y128000D01*
X298417Y127250D01*
X298583Y126500D01*
X298833Y126000D01*
X299333Y125500D01*
X299917Y125167D01*
X300500Y125000D01*
X301083D01*
X301667Y125167D01*
X302167Y125417D01*
X302583Y125750D01*
G01X306767Y127667D02*
X307100Y127917D01*
X307350Y128333D01*
X307517Y128917D01*
X307350Y129417D01*
X307017Y129750D01*
X306433Y130000D01*
X304183D01*
Y125000D01*
X306933D01*
X307517Y125333D01*
X307850Y125833D01*
X308017Y126417D01*
X307850Y127000D01*
X307350Y127500D01*
X306767Y127667D01*
X304183D01*
G01X311700Y124833D02*
X311533Y124917D01*
Y125083D01*
X311700Y125167D01*
X311867Y125083D01*
Y124917D01*
X311700Y124833D01*
G01X270750Y150667D02*
X271417Y150250D01*
X272167Y150000D01*
X272833D01*
X273500Y150250D01*
X274000Y150667D01*
X274250Y151250D01*
X274083Y151833D01*
X273667Y152333D01*
X272917Y152667D01*
X271917Y152833D01*
X271333Y153167D01*
X271083Y153750D01*
X271250Y154333D01*
X271667Y154750D01*
X272250Y155000D01*
X272833D01*
X273417Y154833D01*
X273917Y154417D01*
G01X276850Y152250D02*
X279517D01*
X279267Y152833D01*
X278850Y153167D01*
X278267Y153333D01*
X277683Y153250D01*
X277183Y153000D01*
X276850Y152417D01*
X276683Y151917D01*
Y151417D01*
X276850Y150917D01*
X277267Y150417D01*
X277767Y150083D01*
X278350Y150000D01*
X278933Y150167D01*
X279517Y150667D01*
G01X282533Y150000D02*
Y153333D01*
G01Y152667D02*
X282950Y153000D01*
X283367Y153250D01*
X283950Y153333D01*
X284367Y153250D01*
X284867Y153000D01*
G01X287800Y153333D02*
X289300Y150000D01*
X290800Y153333D01*
G01X293650Y152250D02*
X296317D01*
X296067Y152833D01*
X295650Y153167D01*
X295067Y153333D01*
X294483Y153250D01*
X293983Y153000D01*
X293650Y152417D01*
X293483Y151917D01*
Y151417D01*
X293650Y150917D01*
X294067Y150417D01*
X294567Y150083D01*
X295150Y150000D01*
X295733Y150167D01*
X296317Y150667D01*
G01X299333Y150000D02*
Y153333D01*
G01Y152667D02*
X299750Y153000D01*
X300167Y153250D01*
X300750Y153333D01*
X301167Y153250D01*
X301667Y153000D01*
G01X310033Y150000D02*
Y155000D01*
X312033D01*
X312700Y154750D01*
X313200Y154167D01*
X313367Y153500D01*
X313200Y152833D01*
X312783Y152333D01*
X312033Y152083D01*
X310033D01*
G01X319133Y154583D02*
X318633Y154833D01*
X318050Y155000D01*
X317383D01*
X316633Y154750D01*
X316050Y154333D01*
X315633Y153833D01*
X315300Y153000D01*
X315217Y152250D01*
X315383Y151500D01*
X315633Y151000D01*
X316133Y150500D01*
X316717Y150167D01*
X317300Y150000D01*
X317883D01*
X318467Y150167D01*
X318967Y150417D01*
X319383Y150750D01*
G01X323567Y152667D02*
X323900Y152917D01*
X324150Y153333D01*
X324317Y153917D01*
X324150Y154417D01*
X323817Y154750D01*
X323233Y155000D01*
X320983D01*
Y150000D01*
X323733D01*
X324317Y150333D01*
X324650Y150833D01*
X324817Y151417D01*
X324650Y152000D01*
X324150Y152500D01*
X323567Y152667D01*
X320983D01*
G01X328500Y149833D02*
X328333Y149917D01*
Y150083D01*
X328500Y150167D01*
X328667Y150083D01*
Y149917D01*
X328500Y149833D01*
G01Y152083D02*
X328333Y152167D01*
Y152333D01*
X328500Y152417D01*
X328667Y152333D01*
Y152167D01*
X328500Y152083D01*
G01X332517Y150000D02*
Y155000D01*
X335683D01*
G01X334517Y152583D02*
X332517D01*
G01X339700Y150000D02*
X339200Y150083D01*
X338700Y150417D01*
X338367Y151000D01*
X338200Y151667D01*
X338367Y152333D01*
X338700Y152917D01*
X339200Y153250D01*
X339700Y153333D01*
X340200Y153250D01*
X340700Y152917D01*
X341033Y152333D01*
X341117Y151667D01*
X341033Y151000D01*
X340700Y150417D01*
X340200Y150083D01*
X339700Y150000D01*
G01X345300D02*
Y155000D01*
G01X350900Y150000D02*
Y155000D01*
G01X356500Y150000D02*
X356000Y150083D01*
X355500Y150417D01*
X355167Y151000D01*
X355000Y151667D01*
X355167Y152333D01*
X355500Y152917D01*
X356000Y153250D01*
X356500Y153333D01*
X357000Y153250D01*
X357500Y152917D01*
X357833Y152333D01*
X357917Y151667D01*
X357833Y151000D01*
X357500Y150417D01*
X357000Y150083D01*
X356500Y150000D01*
G01X360017Y153333D02*
X361017Y150000D01*
X362100Y153333D01*
X363183Y150000D01*
X364183Y153333D01*
G01X372133Y150000D02*
Y153333D01*
G01Y152667D02*
X372550Y153000D01*
X372967Y153250D01*
X373550Y153333D01*
X373967Y153250D01*
X374467Y153000D01*
G01X378900Y153333D02*
Y150000D01*
G01Y154667D02*
X378733Y154750D01*
Y154917D01*
X378900Y155000D01*
X379067Y154917D01*
Y154750D01*
X378900Y154667D01*
G01X383333Y148750D02*
X383917Y148417D01*
X384583Y148333D01*
X385167Y148417D01*
X385667Y148833D01*
X386000Y149417D01*
Y153333D01*
G01Y152667D02*
X385667Y153000D01*
X385167Y153250D01*
X384583Y153333D01*
X383917Y153167D01*
X383500Y152833D01*
X383167Y152250D01*
X383000Y151667D01*
X383083Y151167D01*
X383417Y150583D01*
X383917Y150167D01*
X384583Y150000D01*
X385083Y150083D01*
X385667Y150417D01*
X386000Y150750D01*
G01X388683Y150000D02*
Y155000D01*
G01Y152583D02*
X389100Y153000D01*
X389517Y153250D01*
X390183Y153333D01*
X390683Y153250D01*
X391267Y152917D01*
X391517Y152417D01*
Y150000D01*
G01X395700Y155000D02*
Y150000D01*
G01X394533Y153333D02*
X396867D01*
G01X405650Y150583D02*
X406067Y150250D01*
X406650Y150000D01*
X407150D01*
X407650Y150167D01*
X407983Y150417D01*
X408150Y150750D01*
X408067Y151250D01*
X407733Y151500D01*
X406233Y152000D01*
X405900Y152583D01*
X406067Y153000D01*
X406400Y153250D01*
X406900Y153333D01*
X407400Y153250D01*
X407900Y153000D01*
G01X412500Y153333D02*
Y150000D01*
G01Y154667D02*
X412333Y154750D01*
Y154917D01*
X412500Y155000D01*
X412667Y154917D01*
Y154750D01*
X412500Y154667D01*
G01X419600Y155000D02*
Y150000D01*
G01Y150750D02*
X419267Y150333D01*
X418767Y150083D01*
X418183Y150000D01*
X417517Y150167D01*
X417017Y150583D01*
X416683Y151083D01*
X416600Y151667D01*
X416683Y152250D01*
X417017Y152750D01*
X417517Y153167D01*
X418183Y153333D01*
X418767Y153250D01*
X419183Y153083D01*
X419600Y152750D01*
G01X422450Y152250D02*
X425117D01*
X424867Y152833D01*
X424450Y153167D01*
X423867Y153333D01*
X423283Y153250D01*
X422783Y153000D01*
X422450Y152417D01*
X422283Y151917D01*
Y151417D01*
X422450Y150917D01*
X422867Y150417D01*
X423367Y150083D01*
X423950Y150000D01*
X424533Y150167D01*
X425117Y150667D01*
G01X433650Y150583D02*
X434067Y150250D01*
X434650Y150000D01*
X435150D01*
X435650Y150167D01*
X435983Y150417D01*
X436150Y150750D01*
X436067Y151250D01*
X435733Y151500D01*
X434233Y152000D01*
X433900Y152583D01*
X434067Y153000D01*
X434400Y153250D01*
X434900Y153333D01*
X435400Y153250D01*
X435900Y153000D01*
G01X439000Y148333D02*
Y153333D01*
G01Y152583D02*
X439417Y153000D01*
X439833Y153250D01*
X440500Y153333D01*
X441083Y153250D01*
X441667Y152833D01*
X441917Y152250D01*
X442000Y151667D01*
X441917Y151083D01*
X441667Y150500D01*
X441167Y150167D01*
X440500Y150000D01*
X439917Y150083D01*
X439333Y150333D01*
X439000Y150667D01*
G01X444850Y152250D02*
X447517D01*
X447267Y152833D01*
X446850Y153167D01*
X446267Y153333D01*
X445683Y153250D01*
X445183Y153000D01*
X444850Y152417D01*
X444683Y151917D01*
Y151417D01*
X444850Y150917D01*
X445267Y150417D01*
X445767Y150083D01*
X446350Y150000D01*
X446933Y150167D01*
X447517Y150667D01*
G01X453033Y152917D02*
X452450Y153250D01*
X451950Y153333D01*
X451283Y153167D01*
X450783Y152833D01*
X450450Y152250D01*
X450367Y151667D01*
X450450Y151083D01*
X450783Y150583D01*
X451283Y150167D01*
X451950Y150000D01*
X452533Y150167D01*
X453033Y150500D01*
G01X462733Y149083D02*
X463067Y150167D01*
G01X468500Y153333D02*
Y150000D01*
G01Y154667D02*
X468333Y154750D01*
Y154917D01*
X468500Y155000D01*
X468667Y154917D01*
Y154750D01*
X468500Y154667D01*
G01X473600Y150000D02*
Y154250D01*
X473767Y154667D01*
X474100Y154917D01*
X474600Y155000D01*
X475100Y154833D01*
X475350Y154417D01*
G01X474350Y153000D02*
X472683D01*
G01X484050Y150583D02*
X484467Y150250D01*
X485050Y150000D01*
X485550D01*
X486050Y150167D01*
X486383Y150417D01*
X486550Y150750D01*
X486467Y151250D01*
X486133Y151500D01*
X484633Y152000D01*
X484300Y152583D01*
X484467Y153000D01*
X484800Y153250D01*
X485300Y153333D01*
X485800Y153250D01*
X486300Y153000D01*
G01X490900Y155000D02*
Y150000D01*
G01X489733Y153333D02*
X492067D01*
G01X498000Y150000D02*
Y153333D01*
G01Y152750D02*
X497667Y153083D01*
X497167Y153250D01*
X496583Y153333D01*
X496000Y153167D01*
X495500Y152833D01*
X495167Y152333D01*
X495000Y151667D01*
X495167Y151000D01*
X495500Y150500D01*
X496000Y150167D01*
X496583Y150000D01*
X497167Y150083D01*
X497667Y150333D01*
X498000Y150667D01*
G01X503433Y152917D02*
X502850Y153250D01*
X502350Y153333D01*
X501683Y153167D01*
X501183Y152833D01*
X500850Y152250D01*
X500767Y151667D01*
X500850Y151083D01*
X501183Y150583D01*
X501683Y150167D01*
X502350Y150000D01*
X502933Y150167D01*
X503433Y150500D01*
G01X506283Y150000D02*
Y155000D01*
G01X508950Y153333D02*
X506283Y151417D01*
G01X507367Y152167D02*
X509117Y150000D01*
G01X517483Y153333D02*
Y151000D01*
X517817Y150417D01*
X518317Y150083D01*
X518900Y150000D01*
X519483Y150083D01*
X519983Y150417D01*
X520317Y151000D01*
G01Y150000D02*
Y153333D01*
G01X523000Y148333D02*
Y153333D01*
G01Y152583D02*
X523417Y153000D01*
X523833Y153250D01*
X524500Y153333D01*
X525083Y153250D01*
X525667Y152833D01*
X525917Y152250D01*
X526000Y151667D01*
X525917Y151083D01*
X525667Y150500D01*
X525167Y150167D01*
X524500Y150000D01*
X523917Y150083D01*
X523333Y150333D01*
X523000Y150667D01*
G01X533617Y153333D02*
X534617Y150000D01*
X535700Y153333D01*
X536783Y150000D01*
X537783Y153333D01*
G01X541300D02*
Y150000D01*
G01Y154667D02*
X541133Y154750D01*
Y154917D01*
X541300Y155000D01*
X541467Y154917D01*
Y154750D01*
X541300Y154667D01*
G01X546900Y155000D02*
Y150000D01*
G01X545733Y153333D02*
X548067D01*
G01X551083Y150000D02*
Y155000D01*
G01Y152583D02*
X551500Y153000D01*
X551917Y153250D01*
X552583Y153333D01*
X553083Y153250D01*
X553667Y152917D01*
X553917Y152417D01*
Y150000D01*
G01X558100D02*
X557600Y150083D01*
X557100Y150417D01*
X556767Y151000D01*
X556600Y151667D01*
X556767Y152333D01*
X557100Y152917D01*
X557600Y153250D01*
X558100Y153333D01*
X558600Y153250D01*
X559100Y152917D01*
X559433Y152333D01*
X559517Y151667D01*
X559433Y151000D01*
X559100Y150417D01*
X558600Y150083D01*
X558100Y150000D01*
G01X562283Y153333D02*
Y151000D01*
X562617Y150417D01*
X563117Y150083D01*
X563700Y150000D01*
X564283Y150083D01*
X564783Y150417D01*
X565117Y151000D01*
G01Y150000D02*
Y153333D01*
G01X569300Y155000D02*
Y150000D01*
G01X568133Y153333D02*
X570467D01*
G01X272500Y170000D02*
Y165000D01*
G01X270583Y170000D02*
X274417D01*
G01X276933Y165000D02*
Y168333D01*
G01Y167667D02*
X277350Y168000D01*
X277767Y168250D01*
X278350Y168333D01*
X278767Y168250D01*
X279267Y168000D01*
G01X285200Y165000D02*
Y168333D01*
G01Y167750D02*
X284867Y168083D01*
X284367Y168250D01*
X283783Y168333D01*
X283200Y168167D01*
X282700Y167833D01*
X282367Y167333D01*
X282200Y166667D01*
X282367Y166000D01*
X282700Y165500D01*
X283200Y165167D01*
X283783Y165000D01*
X284367Y165083D01*
X284867Y165333D01*
X285200Y165667D01*
G01X290800Y170000D02*
Y165000D01*
G01Y165750D02*
X290467Y165333D01*
X289967Y165083D01*
X289383Y165000D01*
X288717Y165167D01*
X288217Y165583D01*
X287883Y166083D01*
X287800Y166667D01*
X287883Y167250D01*
X288217Y167750D01*
X288717Y168167D01*
X289383Y168333D01*
X289967Y168250D01*
X290383Y168083D01*
X290800Y167750D01*
G01X294900Y168333D02*
Y165000D01*
G01Y169667D02*
X294733Y169750D01*
Y169917D01*
X294900Y170000D01*
X295067Y169917D01*
Y169750D01*
X294900Y169667D01*
G01X300500Y170000D02*
Y165000D01*
G01X299333Y168333D02*
X301667D01*
G01X306100D02*
Y165000D01*
G01Y169667D02*
X305933Y169750D01*
Y169917D01*
X306100Y170000D01*
X306267Y169917D01*
Y169750D01*
X306100Y169667D01*
G01X311700Y165000D02*
X311200Y165083D01*
X310700Y165417D01*
X310367Y166000D01*
X310200Y166667D01*
X310367Y167333D01*
X310700Y167917D01*
X311200Y168250D01*
X311700Y168333D01*
X312200Y168250D01*
X312700Y167917D01*
X313033Y167333D01*
X313117Y166667D01*
X313033Y166000D01*
X312700Y165417D01*
X312200Y165083D01*
X311700Y165000D01*
G01X315883D02*
Y168333D01*
G01Y167500D02*
X316217Y167917D01*
X316717Y168250D01*
X317383Y168333D01*
X317967Y168250D01*
X318467Y167917D01*
X318717Y167333D01*
Y165000D01*
G01X324400D02*
Y168333D01*
G01Y167750D02*
X324067Y168083D01*
X323567Y168250D01*
X322983Y168333D01*
X322400Y168167D01*
X321900Y167833D01*
X321567Y167333D01*
X321400Y166667D01*
X321567Y166000D01*
X321900Y165500D01*
X322400Y165167D01*
X322983Y165000D01*
X323567Y165083D01*
X324067Y165333D01*
X324400Y165667D01*
G01X328500Y165000D02*
Y170000D01*
G01X338033Y165000D02*
Y170000D01*
X340033D01*
X340700Y169750D01*
X341200Y169167D01*
X341367Y168500D01*
X341200Y167833D01*
X340783Y167333D01*
X340033Y167083D01*
X338033D01*
G01X347133Y169583D02*
X346633Y169833D01*
X346050Y170000D01*
X345383D01*
X344633Y169750D01*
X344050Y169333D01*
X343633Y168833D01*
X343300Y168000D01*
X343217Y167250D01*
X343383Y166500D01*
X343633Y166000D01*
X344133Y165500D01*
X344717Y165167D01*
X345300Y165000D01*
X345883D01*
X346467Y165167D01*
X346967Y165417D01*
X347383Y165750D01*
G01X351567Y167667D02*
X351900Y167917D01*
X352150Y168333D01*
X352317Y168917D01*
X352150Y169417D01*
X351817Y169750D01*
X351233Y170000D01*
X348983D01*
Y165000D01*
X351733D01*
X352317Y165333D01*
X352650Y165833D01*
X352817Y166417D01*
X352650Y167000D01*
X352150Y167500D01*
X351567Y167667D01*
X348983D01*
G01X356500Y164833D02*
X356333Y164917D01*
Y165083D01*
X356500Y165167D01*
X356667Y165083D01*
Y164917D01*
X356500Y164833D01*
G01X264000Y135500D02*
X694500D01*
G01X264000Y160500D02*
X694500D01*
G01X262500Y237500D02*
X694500D01*
G01X262500Y290500D02*
X694500D01*
G01X270000Y374000D02*
Y369000D01*
G01X268833Y372333D02*
X271167D01*
G01X275600Y369000D02*
X275100Y369083D01*
X274600Y369417D01*
X274267Y370000D01*
X274100Y370667D01*
X274267Y371333D01*
X274600Y371917D01*
X275100Y372250D01*
X275600Y372333D01*
X276100Y372250D01*
X276600Y371917D01*
X276933Y371333D01*
X277017Y370667D01*
X276933Y370000D01*
X276600Y369417D01*
X276100Y369083D01*
X275600Y369000D01*
G01X281200D02*
Y374000D01*
G01X285550Y371250D02*
X288217D01*
X287967Y371833D01*
X287550Y372167D01*
X286967Y372333D01*
X286383Y372250D01*
X285883Y372000D01*
X285550Y371417D01*
X285383Y370917D01*
Y370417D01*
X285550Y369917D01*
X285967Y369417D01*
X286467Y369083D01*
X287050Y369000D01*
X287633Y369167D01*
X288217Y369667D01*
G01X291233Y369000D02*
Y372333D01*
G01Y371667D02*
X291650Y372000D01*
X292067Y372250D01*
X292650Y372333D01*
X293067Y372250D01*
X293567Y372000D01*
G01X299500Y369000D02*
Y372333D01*
G01Y371750D02*
X299167Y372083D01*
X298667Y372250D01*
X298083Y372333D01*
X297500Y372167D01*
X297000Y371833D01*
X296667Y371333D01*
X296500Y370667D01*
X296667Y370000D01*
X297000Y369500D01*
X297500Y369167D01*
X298083Y369000D01*
X298667Y369083D01*
X299167Y369333D01*
X299500Y369667D01*
G01X302183Y369000D02*
Y372333D01*
G01Y371500D02*
X302517Y371917D01*
X303017Y372250D01*
X303683Y372333D01*
X304267Y372250D01*
X304767Y371917D01*
X305017Y371333D01*
Y369000D01*
G01X310533Y371917D02*
X309950Y372250D01*
X309450Y372333D01*
X308783Y372167D01*
X308283Y371833D01*
X307950Y371250D01*
X307867Y370667D01*
X307950Y370083D01*
X308283Y369583D01*
X308783Y369167D01*
X309450Y369000D01*
X310033Y369167D01*
X310533Y369500D01*
G01X313550Y371250D02*
X316217D01*
X315967Y371833D01*
X315550Y372167D01*
X314967Y372333D01*
X314383Y372250D01*
X313883Y372000D01*
X313550Y371417D01*
X313383Y370917D01*
Y370417D01*
X313550Y369917D01*
X313967Y369417D01*
X314467Y369083D01*
X315050Y369000D01*
X315633Y369167D01*
X316217Y369667D01*
G01X326000Y374000D02*
Y369000D01*
G01X324833Y372333D02*
X327167D01*
G01X333100Y369000D02*
Y372333D01*
G01Y371750D02*
X332767Y372083D01*
X332267Y372250D01*
X331683Y372333D01*
X331100Y372167D01*
X330600Y371833D01*
X330267Y371333D01*
X330100Y370667D01*
X330267Y370000D01*
X330600Y369500D01*
X331100Y369167D01*
X331683Y369000D01*
X332267Y369083D01*
X332767Y369333D01*
X333100Y369667D01*
G01X335700Y369000D02*
Y374000D01*
G01Y371500D02*
X336117Y372000D01*
X336617Y372250D01*
X337117Y372333D01*
X337867Y372167D01*
X338367Y371833D01*
X338700Y371250D01*
Y370583D01*
X338533Y369917D01*
X338200Y369417D01*
X337617Y369083D01*
X337117Y369000D01*
X336617Y369083D01*
X336117Y369333D01*
X335700Y369750D01*
G01X342800Y369000D02*
Y374000D01*
G01X347150Y371250D02*
X349817D01*
X349567Y371833D01*
X349150Y372167D01*
X348567Y372333D01*
X347983Y372250D01*
X347483Y372000D01*
X347150Y371417D01*
X346983Y370917D01*
Y370417D01*
X347150Y369917D01*
X347567Y369417D01*
X348067Y369083D01*
X348650Y369000D01*
X349233Y369167D01*
X349817Y369667D01*
G01X354000Y368833D02*
X353833Y368917D01*
Y369083D01*
X354000Y369167D01*
X354167Y369083D01*
Y368917D01*
X354000Y368833D01*
G01X268667Y379750D02*
X269250Y379417D01*
X269750Y379333D01*
X270417Y379500D01*
X270917Y379917D01*
X271167Y380667D01*
Y384333D01*
G01Y385667D02*
X271000Y385750D01*
Y385917D01*
X271167Y386000D01*
X271333Y385917D01*
Y385750D01*
X271167Y385667D01*
G01X274183Y384333D02*
Y382000D01*
X274517Y381417D01*
X275017Y381083D01*
X275600Y381000D01*
X276183Y381083D01*
X276683Y381417D01*
X277017Y382000D01*
G01Y381000D02*
Y384333D01*
G01X279783Y381000D02*
Y384333D01*
G01Y383500D02*
X280117Y383917D01*
X280617Y384250D01*
X281283Y384333D01*
X281867Y384250D01*
X282367Y383917D01*
X282617Y383333D01*
Y381000D01*
G01X288133Y383917D02*
X287550Y384250D01*
X287050Y384333D01*
X286383Y384167D01*
X285883Y383833D01*
X285550Y383250D01*
X285467Y382667D01*
X285550Y382083D01*
X285883Y381583D01*
X286383Y381167D01*
X287050Y381000D01*
X287633Y381167D01*
X288133Y381500D01*
G01X292400Y386000D02*
Y381000D01*
G01X291233Y384333D02*
X293567D01*
G01X298000D02*
Y381000D01*
G01Y385667D02*
X297833Y385750D01*
Y385917D01*
X298000Y386000D01*
X298167Y385917D01*
Y385750D01*
X298000Y385667D01*
G01X303600Y381000D02*
X303100Y381083D01*
X302600Y381417D01*
X302267Y382000D01*
X302100Y382667D01*
X302267Y383333D01*
X302600Y383917D01*
X303100Y384250D01*
X303600Y384333D01*
X304100Y384250D01*
X304600Y383917D01*
X304933Y383333D01*
X305017Y382667D01*
X304933Y382000D01*
X304600Y381417D01*
X304100Y381083D01*
X303600Y381000D01*
G01X307783D02*
Y384333D01*
G01Y383500D02*
X308117Y383917D01*
X308617Y384250D01*
X309283Y384333D01*
X309867Y384250D01*
X310367Y383917D01*
X310617Y383333D01*
Y381000D01*
G01X318900D02*
Y386000D01*
G01Y383500D02*
X319317Y384000D01*
X319817Y384250D01*
X320317Y384333D01*
X321067Y384167D01*
X321567Y383833D01*
X321900Y383250D01*
Y382583D01*
X321733Y381917D01*
X321400Y381417D01*
X320817Y381083D01*
X320317Y381000D01*
X319817Y381083D01*
X319317Y381333D01*
X318900Y381750D01*
G01X324750Y383250D02*
X327417D01*
X327167Y383833D01*
X326750Y384167D01*
X326167Y384333D01*
X325583Y384250D01*
X325083Y384000D01*
X324750Y383417D01*
X324583Y382917D01*
Y382417D01*
X324750Y381917D01*
X325167Y381417D01*
X325667Y381083D01*
X326250Y381000D01*
X326833Y381167D01*
X327417Y381667D01*
G01X331600Y381000D02*
Y386000D01*
G01X337200Y381000D02*
X336700Y381083D01*
X336200Y381417D01*
X335867Y382000D01*
X335700Y382667D01*
X335867Y383333D01*
X336200Y383917D01*
X336700Y384250D01*
X337200Y384333D01*
X337700Y384250D01*
X338200Y383917D01*
X338533Y383333D01*
X338617Y382667D01*
X338533Y382000D01*
X338200Y381417D01*
X337700Y381083D01*
X337200Y381000D01*
G01X340717Y384333D02*
X341717Y381000D01*
X342800Y384333D01*
X343883Y381000D01*
X344883Y384333D01*
G01X354000Y386000D02*
Y381000D01*
G01X352833Y384333D02*
X355167D01*
G01X358183Y381000D02*
Y386000D01*
G01Y383583D02*
X358600Y384000D01*
X359017Y384250D01*
X359683Y384333D01*
X360183Y384250D01*
X360767Y383917D01*
X361017Y383417D01*
Y381000D01*
G01X363950Y383250D02*
X366617D01*
X366367Y383833D01*
X365950Y384167D01*
X365367Y384333D01*
X364783Y384250D01*
X364283Y384000D01*
X363950Y383417D01*
X363783Y382917D01*
Y382417D01*
X363950Y381917D01*
X364367Y381417D01*
X364867Y381083D01*
X365450Y381000D01*
X366033Y381167D01*
X366617Y381667D01*
G01X373900Y381000D02*
Y384333D01*
G01Y383417D02*
X374150Y383833D01*
X374567Y384167D01*
X375150Y384333D01*
X375733Y384167D01*
X376150Y383833D01*
X376400Y383417D01*
Y381000D01*
G01Y383417D02*
X376650Y383833D01*
X377067Y384167D01*
X377650Y384333D01*
X378233Y384167D01*
X378650Y383833D01*
X378900Y383333D01*
Y381000D01*
G01X382000Y384333D02*
Y381000D01*
G01Y385667D02*
X381833Y385750D01*
Y385917D01*
X382000Y386000D01*
X382167Y385917D01*
Y385750D01*
X382000Y385667D01*
G01X386183Y381000D02*
Y384333D01*
G01Y383500D02*
X386517Y383917D01*
X387017Y384250D01*
X387683Y384333D01*
X388267Y384250D01*
X388767Y383917D01*
X389017Y383333D01*
Y381000D01*
G01X400133Y383917D02*
X399550Y384250D01*
X399050Y384333D01*
X398383Y384167D01*
X397883Y383833D01*
X397550Y383250D01*
X397467Y382667D01*
X397550Y382083D01*
X397883Y381583D01*
X398383Y381167D01*
X399050Y381000D01*
X399633Y381167D01*
X400133Y381500D01*
G01X404400Y381000D02*
X403900Y381083D01*
X403400Y381417D01*
X403067Y382000D01*
X402900Y382667D01*
X403067Y383333D01*
X403400Y383917D01*
X403900Y384250D01*
X404400Y384333D01*
X404900Y384250D01*
X405400Y383917D01*
X405733Y383333D01*
X405817Y382667D01*
X405733Y382000D01*
X405400Y381417D01*
X404900Y381083D01*
X404400Y381000D01*
G01X408583D02*
Y384333D01*
G01Y383500D02*
X408917Y383917D01*
X409417Y384250D01*
X410083Y384333D01*
X410667Y384250D01*
X411167Y383917D01*
X411417Y383333D01*
Y381000D01*
G01X417100Y386000D02*
Y381000D01*
G01Y381750D02*
X416767Y381333D01*
X416267Y381083D01*
X415683Y381000D01*
X415017Y381167D01*
X414517Y381583D01*
X414183Y382083D01*
X414100Y382667D01*
X414183Y383250D01*
X414517Y383750D01*
X415017Y384167D01*
X415683Y384333D01*
X416267Y384250D01*
X416683Y384083D01*
X417100Y383750D01*
G01X419783Y384333D02*
Y382000D01*
X420117Y381417D01*
X420617Y381083D01*
X421200Y381000D01*
X421783Y381083D01*
X422283Y381417D01*
X422617Y382000D01*
G01Y381000D02*
Y384333D01*
G01X428133Y383917D02*
X427550Y384250D01*
X427050Y384333D01*
X426383Y384167D01*
X425883Y383833D01*
X425550Y383250D01*
X425467Y382667D01*
X425550Y382083D01*
X425883Y381583D01*
X426383Y381167D01*
X427050Y381000D01*
X427633Y381167D01*
X428133Y381500D01*
G01X432400Y386000D02*
Y381000D01*
G01X431233Y384333D02*
X433567D01*
G01X438000Y381000D02*
X437500Y381083D01*
X437000Y381417D01*
X436667Y382000D01*
X436500Y382667D01*
X436667Y383333D01*
X437000Y383917D01*
X437500Y384250D01*
X438000Y384333D01*
X438500Y384250D01*
X439000Y383917D01*
X439333Y383333D01*
X439417Y382667D01*
X439333Y382000D01*
X439000Y381417D01*
X438500Y381083D01*
X438000Y381000D01*
G01X442433D02*
Y384333D01*
G01Y383667D02*
X442850Y384000D01*
X443267Y384250D01*
X443850Y384333D01*
X444267Y384250D01*
X444767Y384000D01*
G01X452717Y384333D02*
X453717Y381000D01*
X454800Y384333D01*
X455883Y381000D01*
X456883Y384333D01*
G01X460400D02*
Y381000D01*
G01Y385667D02*
X460233Y385750D01*
Y385917D01*
X460400Y386000D01*
X460567Y385917D01*
Y385750D01*
X460400Y385667D01*
G01X467500Y386000D02*
Y381000D01*
G01Y381750D02*
X467167Y381333D01*
X466667Y381083D01*
X466083Y381000D01*
X465417Y381167D01*
X464917Y381583D01*
X464583Y382083D01*
X464500Y382667D01*
X464583Y383250D01*
X464917Y383750D01*
X465417Y384167D01*
X466083Y384333D01*
X466667Y384250D01*
X467083Y384083D01*
X467500Y383750D01*
G01X471600Y386000D02*
Y381000D01*
G01X470433Y384333D02*
X472767D01*
G01X475783Y381000D02*
Y386000D01*
G01Y383583D02*
X476200Y384000D01*
X476617Y384250D01*
X477283Y384333D01*
X477783Y384250D01*
X478367Y383917D01*
X478617Y383417D01*
Y381000D01*
G01X487150Y381583D02*
X487567Y381250D01*
X488150Y381000D01*
X488650D01*
X489150Y381167D01*
X489483Y381417D01*
X489650Y381750D01*
X489567Y382250D01*
X489233Y382500D01*
X487733Y383000D01*
X487400Y383583D01*
X487567Y384000D01*
X487900Y384250D01*
X488400Y384333D01*
X488900Y384250D01*
X489400Y384000D01*
G01X492500Y379333D02*
Y384333D01*
G01Y383583D02*
X492917Y384000D01*
X493333Y384250D01*
X494000Y384333D01*
X494583Y384250D01*
X495167Y383833D01*
X495417Y383250D01*
X495500Y382667D01*
X495417Y382083D01*
X495167Y381500D01*
X494667Y381167D01*
X494000Y381000D01*
X493417Y381083D01*
X492833Y381333D01*
X492500Y381667D01*
G01X498350Y383250D02*
X501017D01*
X500767Y383833D01*
X500350Y384167D01*
X499767Y384333D01*
X499183Y384250D01*
X498683Y384000D01*
X498350Y383417D01*
X498183Y382917D01*
Y382417D01*
X498350Y381917D01*
X498767Y381417D01*
X499267Y381083D01*
X499850Y381000D01*
X500433Y381167D01*
X501017Y381667D01*
G01X506533Y383917D02*
X505950Y384250D01*
X505450Y384333D01*
X504783Y384167D01*
X504283Y383833D01*
X503950Y383250D01*
X503867Y382667D01*
X503950Y382083D01*
X504283Y381583D01*
X504783Y381167D01*
X505450Y381000D01*
X506033Y381167D01*
X506533Y381500D01*
G01X510800Y384333D02*
Y381000D01*
G01Y385667D02*
X510633Y385750D01*
Y385917D01*
X510800Y386000D01*
X510967Y385917D01*
Y385750D01*
X510800Y385667D01*
G01X515900Y381000D02*
Y385250D01*
X516067Y385667D01*
X516400Y385917D01*
X516900Y386000D01*
X517400Y385833D01*
X517650Y385417D01*
G01X516650Y384000D02*
X514983D01*
G01X522000Y384333D02*
Y381000D01*
G01Y385667D02*
X521833Y385750D01*
Y385917D01*
X522000Y386000D01*
X522167Y385917D01*
Y385750D01*
X522000Y385667D01*
G01X526350Y383250D02*
X529017D01*
X528767Y383833D01*
X528350Y384167D01*
X527767Y384333D01*
X527183Y384250D01*
X526683Y384000D01*
X526350Y383417D01*
X526183Y382917D01*
Y382417D01*
X526350Y381917D01*
X526767Y381417D01*
X527267Y381083D01*
X527850Y381000D01*
X528433Y381167D01*
X529017Y381667D01*
G01X534700Y386000D02*
Y381000D01*
G01Y381750D02*
X534367Y381333D01*
X533867Y381083D01*
X533283Y381000D01*
X532617Y381167D01*
X532117Y381583D01*
X531783Y382083D01*
X531700Y382667D01*
X531783Y383250D01*
X532117Y383750D01*
X532617Y384167D01*
X533283Y384333D01*
X533867Y384250D01*
X534283Y384083D01*
X534700Y383750D01*
G01X544400Y381000D02*
X543900Y381083D01*
X543400Y381417D01*
X543067Y382000D01*
X542900Y382667D01*
X543067Y383333D01*
X543400Y383917D01*
X543900Y384250D01*
X544400Y384333D01*
X544900Y384250D01*
X545400Y383917D01*
X545733Y383333D01*
X545817Y382667D01*
X545733Y382000D01*
X545400Y381417D01*
X544900Y381083D01*
X544400Y381000D01*
G01X548583D02*
Y384333D01*
G01Y383500D02*
X548917Y383917D01*
X549417Y384250D01*
X550083Y384333D01*
X550667Y384250D01*
X551167Y383917D01*
X551417Y383333D01*
Y381000D01*
G01X561200Y386000D02*
Y381000D01*
G01X560033Y384333D02*
X562367D01*
G01X565383Y381000D02*
Y386000D01*
G01Y383583D02*
X565800Y384000D01*
X566217Y384250D01*
X566883Y384333D01*
X567383Y384250D01*
X567967Y383917D01*
X568217Y383417D01*
Y381000D01*
G01X571150Y383250D02*
X573817D01*
X573567Y383833D01*
X573150Y384167D01*
X572567Y384333D01*
X571983Y384250D01*
X571483Y384000D01*
X571150Y383417D01*
X570983Y382917D01*
Y382417D01*
X571150Y381917D01*
X571567Y381417D01*
X572067Y381083D01*
X572650Y381000D01*
X573233Y381167D01*
X573817Y381667D01*
G01X268250Y391500D02*
Y396500D01*
G01X271750D02*
Y391500D01*
G01Y394000D02*
X268250D01*
G01X275600Y391500D02*
X275100Y391583D01*
X274600Y391917D01*
X274267Y392500D01*
X274100Y393167D01*
X274267Y393833D01*
X274600Y394417D01*
X275100Y394750D01*
X275600Y394833D01*
X276100Y394750D01*
X276600Y394417D01*
X276933Y393833D01*
X277017Y393167D01*
X276933Y392500D01*
X276600Y391917D01*
X276100Y391583D01*
X275600Y391500D01*
G01X279117Y394833D02*
X280117Y391500D01*
X281200Y394833D01*
X282283Y391500D01*
X283283Y394833D01*
G01X285550Y393750D02*
X288217D01*
X287967Y394333D01*
X287550Y394667D01*
X286967Y394833D01*
X286383Y394750D01*
X285883Y394500D01*
X285550Y393917D01*
X285383Y393417D01*
Y392917D01*
X285550Y392417D01*
X285967Y391917D01*
X286467Y391583D01*
X287050Y391500D01*
X287633Y391667D01*
X288217Y392167D01*
G01X290900Y394833D02*
X292400Y391500D01*
X293900Y394833D01*
G01X296750Y393750D02*
X299417D01*
X299167Y394333D01*
X298750Y394667D01*
X298167Y394833D01*
X297583Y394750D01*
X297083Y394500D01*
X296750Y393917D01*
X296583Y393417D01*
Y392917D01*
X296750Y392417D01*
X297167Y391917D01*
X297667Y391583D01*
X298250Y391500D01*
X298833Y391667D01*
X299417Y392167D01*
G01X302433Y391500D02*
Y394833D01*
G01Y394167D02*
X302850Y394500D01*
X303267Y394750D01*
X303850Y394833D01*
X304267Y394750D01*
X304767Y394500D01*
G01X309033Y390583D02*
X309367Y391667D01*
G01X314800Y396500D02*
Y391500D01*
G01X313633Y394833D02*
X315967D01*
G01X318983Y391500D02*
Y396500D01*
G01Y394083D02*
X319400Y394500D01*
X319817Y394750D01*
X320483Y394833D01*
X320983Y394750D01*
X321567Y394417D01*
X321817Y393917D01*
Y391500D01*
G01X324750Y393750D02*
X327417D01*
X327167Y394333D01*
X326750Y394667D01*
X326167Y394833D01*
X325583Y394750D01*
X325083Y394500D01*
X324750Y393917D01*
X324583Y393417D01*
Y392917D01*
X324750Y392417D01*
X325167Y391917D01*
X325667Y391583D01*
X326250Y391500D01*
X326833Y391667D01*
X327417Y392167D01*
G01X337200Y396500D02*
Y391500D01*
G01X336033Y394833D02*
X338367D01*
G01X344300Y391500D02*
Y394833D01*
G01Y394250D02*
X343967Y394583D01*
X343467Y394750D01*
X342883Y394833D01*
X342300Y394667D01*
X341800Y394333D01*
X341467Y393833D01*
X341300Y393167D01*
X341467Y392500D01*
X341800Y392000D01*
X342300Y391667D01*
X342883Y391500D01*
X343467Y391583D01*
X343967Y391833D01*
X344300Y392167D01*
G01X346983Y391500D02*
Y394833D01*
G01Y394000D02*
X347317Y394417D01*
X347817Y394750D01*
X348483Y394833D01*
X349067Y394750D01*
X349567Y394417D01*
X349817Y393833D01*
Y391500D01*
G01X352833Y390250D02*
X353417Y389917D01*
X354083Y389833D01*
X354667Y389917D01*
X355167Y390333D01*
X355500Y390917D01*
Y394833D01*
G01Y394167D02*
X355167Y394500D01*
X354667Y394750D01*
X354083Y394833D01*
X353417Y394667D01*
X353000Y394333D01*
X352667Y393750D01*
X352500Y393167D01*
X352583Y392667D01*
X352917Y392083D01*
X353417Y391667D01*
X354083Y391500D01*
X354583Y391583D01*
X355167Y391917D01*
X355500Y392250D01*
G01X358350Y393750D02*
X361017D01*
X360767Y394333D01*
X360350Y394667D01*
X359767Y394833D01*
X359183Y394750D01*
X358683Y394500D01*
X358350Y393917D01*
X358183Y393417D01*
Y392917D01*
X358350Y392417D01*
X358767Y391917D01*
X359267Y391583D01*
X359850Y391500D01*
X360433Y391667D01*
X361017Y392167D01*
G01X363783Y391500D02*
Y394833D01*
G01Y394000D02*
X364117Y394417D01*
X364617Y394750D01*
X365283Y394833D01*
X365867Y394750D01*
X366367Y394417D01*
X366617Y393833D01*
Y391500D01*
G01X372133Y394417D02*
X371550Y394750D01*
X371050Y394833D01*
X370383Y394667D01*
X369883Y394333D01*
X369550Y393750D01*
X369467Y393167D01*
X369550Y392583D01*
X369883Y392083D01*
X370383Y391667D01*
X371050Y391500D01*
X371633Y391667D01*
X372133Y392000D01*
G01X374650Y390000D02*
X375150Y389833D01*
X375817Y390000D01*
X376233Y390333D01*
X376567Y390750D01*
X377067Y392083D01*
X378150Y394833D01*
G01X375483D02*
X377067Y392083D01*
G01X386350D02*
X386767Y391750D01*
X387350Y391500D01*
X387850D01*
X388350Y391667D01*
X388683Y391917D01*
X388850Y392250D01*
X388767Y392750D01*
X388433Y393000D01*
X386933Y393500D01*
X386600Y394083D01*
X386767Y394500D01*
X387100Y394750D01*
X387600Y394833D01*
X388100Y394750D01*
X388600Y394500D01*
G01X391783Y391500D02*
Y396500D01*
G01Y394083D02*
X392200Y394500D01*
X392617Y394750D01*
X393283Y394833D01*
X393783Y394750D01*
X394367Y394417D01*
X394617Y393917D01*
Y391500D01*
G01X398800D02*
X398300Y391583D01*
X397800Y391917D01*
X397467Y392500D01*
X397300Y393167D01*
X397467Y393833D01*
X397800Y394417D01*
X398300Y394750D01*
X398800Y394833D01*
X399300Y394750D01*
X399800Y394417D01*
X400133Y393833D01*
X400217Y393167D01*
X400133Y392500D01*
X399800Y391917D01*
X399300Y391583D01*
X398800Y391500D01*
G01X402983Y394833D02*
Y392500D01*
X403317Y391917D01*
X403817Y391583D01*
X404400Y391500D01*
X404983Y391583D01*
X405483Y391917D01*
X405817Y392500D01*
G01Y391500D02*
Y394833D01*
G01X410000Y391500D02*
Y396500D01*
G01X417100D02*
Y391500D01*
G01Y392250D02*
X416767Y391833D01*
X416267Y391583D01*
X415683Y391500D01*
X415017Y391667D01*
X414517Y392083D01*
X414183Y392583D01*
X414100Y393167D01*
X414183Y393750D01*
X414517Y394250D01*
X415017Y394667D01*
X415683Y394833D01*
X416267Y394750D01*
X416683Y394583D01*
X417100Y394250D01*
G01X425383Y391500D02*
Y394833D01*
G01Y394000D02*
X425717Y394417D01*
X426217Y394750D01*
X426883Y394833D01*
X427467Y394750D01*
X427967Y394417D01*
X428217Y393833D01*
Y391500D01*
G01X432400D02*
X431900Y391583D01*
X431400Y391917D01*
X431067Y392500D01*
X430900Y393167D01*
X431067Y393833D01*
X431400Y394417D01*
X431900Y394750D01*
X432400Y394833D01*
X432900Y394750D01*
X433400Y394417D01*
X433733Y393833D01*
X433817Y393167D01*
X433733Y392500D01*
X433400Y391917D01*
X432900Y391583D01*
X432400Y391500D01*
G01X438000Y396500D02*
Y391500D01*
G01X436833Y394833D02*
X439167D01*
G01X448033Y391500D02*
Y394833D01*
G01Y394167D02*
X448450Y394500D01*
X448867Y394750D01*
X449450Y394833D01*
X449867Y394750D01*
X450367Y394500D01*
G01X453550Y393750D02*
X456217D01*
X455967Y394333D01*
X455550Y394667D01*
X454967Y394833D01*
X454383Y394750D01*
X453883Y394500D01*
X453550Y393917D01*
X453383Y393417D01*
Y392917D01*
X453550Y392417D01*
X453967Y391917D01*
X454467Y391583D01*
X455050Y391500D01*
X455633Y391667D01*
X456217Y392167D01*
G01X461900Y396500D02*
Y391500D01*
G01Y392250D02*
X461567Y391833D01*
X461067Y391583D01*
X460483Y391500D01*
X459817Y391667D01*
X459317Y392083D01*
X458983Y392583D01*
X458900Y393167D01*
X458983Y393750D01*
X459317Y394250D01*
X459817Y394667D01*
X460483Y394833D01*
X461067Y394750D01*
X461483Y394583D01*
X461900Y394250D01*
G01X464583Y394833D02*
Y392500D01*
X464917Y391917D01*
X465417Y391583D01*
X466000Y391500D01*
X466583Y391583D01*
X467083Y391917D01*
X467417Y392500D01*
G01Y391500D02*
Y394833D01*
G01X472933Y394417D02*
X472350Y394750D01*
X471850Y394833D01*
X471183Y394667D01*
X470683Y394333D01*
X470350Y393750D01*
X470267Y393167D01*
X470350Y392583D01*
X470683Y392083D01*
X471183Y391667D01*
X471850Y391500D01*
X472433Y391667D01*
X472933Y392000D01*
G01X475950Y393750D02*
X478617D01*
X478367Y394333D01*
X477950Y394667D01*
X477367Y394833D01*
X476783Y394750D01*
X476283Y394500D01*
X475950Y393917D01*
X475783Y393417D01*
Y392917D01*
X475950Y392417D01*
X476367Y391917D01*
X476867Y391583D01*
X477450Y391500D01*
X478033Y391667D01*
X478617Y392167D01*
G01X488400Y396500D02*
Y391500D01*
G01X487233Y394833D02*
X489567D01*
G01X492583Y391500D02*
Y396500D01*
G01Y394083D02*
X493000Y394500D01*
X493417Y394750D01*
X494083Y394833D01*
X494583Y394750D01*
X495167Y394417D01*
X495417Y393917D01*
Y391500D01*
G01X498350Y393750D02*
X501017D01*
X500767Y394333D01*
X500350Y394667D01*
X499767Y394833D01*
X499183Y394750D01*
X498683Y394500D01*
X498350Y393917D01*
X498183Y393417D01*
Y392917D01*
X498350Y392417D01*
X498767Y391917D01*
X499267Y391583D01*
X499850Y391500D01*
X500433Y391667D01*
X501017Y392167D01*
G01X510800Y391500D02*
Y396500D01*
G01X517900Y391500D02*
Y394833D01*
G01Y394250D02*
X517567Y394583D01*
X517067Y394750D01*
X516483Y394833D01*
X515900Y394667D01*
X515400Y394333D01*
X515067Y393833D01*
X514900Y393167D01*
X515067Y392500D01*
X515400Y392000D01*
X515900Y391667D01*
X516483Y391500D01*
X517067Y391583D01*
X517567Y391833D01*
X517900Y392167D01*
G01X520583Y391500D02*
Y394833D01*
G01Y394000D02*
X520917Y394417D01*
X521417Y394750D01*
X522083Y394833D01*
X522667Y394750D01*
X523167Y394417D01*
X523417Y393833D01*
Y391500D01*
G01X529100Y396500D02*
Y391500D01*
G01Y392250D02*
X528767Y391833D01*
X528267Y391583D01*
X527683Y391500D01*
X527017Y391667D01*
X526517Y392083D01*
X526183Y392583D01*
X526100Y393167D01*
X526183Y393750D01*
X526517Y394250D01*
X527017Y394667D01*
X527683Y394833D01*
X528267Y394750D01*
X528683Y394583D01*
X529100Y394250D01*
G01X531700Y391333D02*
X534700Y396500D01*
G01X540133Y394417D02*
X539550Y394750D01*
X539050Y394833D01*
X538383Y394667D01*
X537883Y394333D01*
X537550Y393750D01*
X537467Y393167D01*
X537550Y392583D01*
X537883Y392083D01*
X538383Y391667D01*
X539050Y391500D01*
X539633Y391667D01*
X540133Y392000D01*
G01X544400Y391500D02*
X543900Y391583D01*
X543400Y391917D01*
X543067Y392500D01*
X542900Y393167D01*
X543067Y393833D01*
X543400Y394417D01*
X543900Y394750D01*
X544400Y394833D01*
X544900Y394750D01*
X545400Y394417D01*
X545733Y393833D01*
X545817Y393167D01*
X545733Y392500D01*
X545400Y391917D01*
X544900Y391583D01*
X544400Y391500D01*
G01X548583D02*
Y394833D01*
G01Y394000D02*
X548917Y394417D01*
X549417Y394750D01*
X550083Y394833D01*
X550667Y394750D01*
X551167Y394417D01*
X551417Y393833D01*
Y391500D01*
G01X557100Y396500D02*
Y391500D01*
G01Y392250D02*
X556767Y391833D01*
X556267Y391583D01*
X555683Y391500D01*
X555017Y391667D01*
X554517Y392083D01*
X554183Y392583D01*
X554100Y393167D01*
X554183Y393750D01*
X554517Y394250D01*
X555017Y394667D01*
X555683Y394833D01*
X556267Y394750D01*
X556683Y394583D01*
X557100Y394250D01*
G01X559783Y394833D02*
Y392500D01*
X560117Y391917D01*
X560617Y391583D01*
X561200Y391500D01*
X561783Y391583D01*
X562283Y391917D01*
X562617Y392500D01*
G01Y391500D02*
Y394833D01*
G01X568133Y394417D02*
X567550Y394750D01*
X567050Y394833D01*
X566383Y394667D01*
X565883Y394333D01*
X565550Y393750D01*
X565467Y393167D01*
X565550Y392583D01*
X565883Y392083D01*
X566383Y391667D01*
X567050Y391500D01*
X567633Y391667D01*
X568133Y392000D01*
G01X572400Y396500D02*
Y391500D01*
G01X571233Y394833D02*
X573567D01*
G01X578000Y391500D02*
X577500Y391583D01*
X577000Y391917D01*
X576667Y392500D01*
X576500Y393167D01*
X576667Y393833D01*
X577000Y394417D01*
X577500Y394750D01*
X578000Y394833D01*
X578500Y394750D01*
X579000Y394417D01*
X579333Y393833D01*
X579417Y393167D01*
X579333Y392500D01*
X579000Y391917D01*
X578500Y391583D01*
X578000Y391500D01*
G01X582433D02*
Y394833D01*
G01Y394167D02*
X582850Y394500D01*
X583267Y394750D01*
X583850Y394833D01*
X584267Y394750D01*
X584767Y394500D01*
G01X271500Y402000D02*
Y405333D01*
G01Y404750D02*
X271167Y405083D01*
X270667Y405250D01*
X270083Y405333D01*
X269500Y405167D01*
X269000Y404833D01*
X268667Y404333D01*
X268500Y403667D01*
X268667Y403000D01*
X269000Y402500D01*
X269500Y402167D01*
X270083Y402000D01*
X270667Y402083D01*
X271167Y402333D01*
X271500Y402667D01*
G01X276933Y404917D02*
X276350Y405250D01*
X275850Y405333D01*
X275183Y405167D01*
X274683Y404833D01*
X274350Y404250D01*
X274267Y403667D01*
X274350Y403083D01*
X274683Y402583D01*
X275183Y402167D01*
X275850Y402000D01*
X276433Y402167D01*
X276933Y402500D01*
G01X282533Y404917D02*
X281950Y405250D01*
X281450Y405333D01*
X280783Y405167D01*
X280283Y404833D01*
X279950Y404250D01*
X279867Y403667D01*
X279950Y403083D01*
X280283Y402583D01*
X280783Y402167D01*
X281450Y402000D01*
X282033Y402167D01*
X282533Y402500D01*
G01X285550Y404250D02*
X288217D01*
X287967Y404833D01*
X287550Y405167D01*
X286967Y405333D01*
X286383Y405250D01*
X285883Y405000D01*
X285550Y404417D01*
X285383Y403917D01*
Y403417D01*
X285550Y402917D01*
X285967Y402417D01*
X286467Y402083D01*
X287050Y402000D01*
X287633Y402167D01*
X288217Y402667D01*
G01X290900Y400333D02*
Y405333D01*
G01Y404583D02*
X291317Y405000D01*
X291733Y405250D01*
X292400Y405333D01*
X292983Y405250D01*
X293567Y404833D01*
X293817Y404250D01*
X293900Y403667D01*
X293817Y403083D01*
X293567Y402500D01*
X293067Y402167D01*
X292400Y402000D01*
X291817Y402083D01*
X291233Y402333D01*
X290900Y402667D01*
G01X298000Y407000D02*
Y402000D01*
G01X296833Y405333D02*
X299167D01*
G01X305100Y402000D02*
Y405333D01*
G01Y404750D02*
X304767Y405083D01*
X304267Y405250D01*
X303683Y405333D01*
X303100Y405167D01*
X302600Y404833D01*
X302267Y404333D01*
X302100Y403667D01*
X302267Y403000D01*
X302600Y402500D01*
X303100Y402167D01*
X303683Y402000D01*
X304267Y402083D01*
X304767Y402333D01*
X305100Y402667D01*
G01X307700Y402000D02*
Y407000D01*
G01Y404500D02*
X308117Y405000D01*
X308617Y405250D01*
X309117Y405333D01*
X309867Y405167D01*
X310367Y404833D01*
X310700Y404250D01*
Y403583D01*
X310533Y402917D01*
X310200Y402417D01*
X309617Y402083D01*
X309117Y402000D01*
X308617Y402083D01*
X308117Y402333D01*
X307700Y402750D01*
G01X314800Y402000D02*
Y407000D01*
G01X319150Y404250D02*
X321817D01*
X321567Y404833D01*
X321150Y405167D01*
X320567Y405333D01*
X319983Y405250D01*
X319483Y405000D01*
X319150Y404417D01*
X318983Y403917D01*
Y403417D01*
X319150Y402917D01*
X319567Y402417D01*
X320067Y402083D01*
X320650Y402000D01*
X321233Y402167D01*
X321817Y402667D01*
G01X326000Y401833D02*
X325833Y401917D01*
Y402083D01*
X326000Y402167D01*
X326167Y402083D01*
Y401917D01*
X326000Y401833D01*
G01X270000Y417500D02*
Y412500D01*
G01X268083Y417500D02*
X271917D01*
G01X274183Y412500D02*
Y417500D01*
G01Y415083D02*
X274600Y415500D01*
X275017Y415750D01*
X275683Y415833D01*
X276183Y415750D01*
X276767Y415417D01*
X277017Y414917D01*
Y412500D01*
G01X279950Y414750D02*
X282617D01*
X282367Y415333D01*
X281950Y415667D01*
X281367Y415833D01*
X280783Y415750D01*
X280283Y415500D01*
X279950Y414917D01*
X279783Y414417D01*
Y413917D01*
X279950Y413417D01*
X280367Y412917D01*
X280867Y412583D01*
X281450Y412500D01*
X282033Y412667D01*
X282617Y413167D01*
G01X290900Y412500D02*
Y417500D01*
G01Y415000D02*
X291317Y415500D01*
X291817Y415750D01*
X292317Y415833D01*
X293067Y415667D01*
X293567Y415333D01*
X293900Y414750D01*
Y414083D01*
X293733Y413417D01*
X293400Y412917D01*
X292817Y412583D01*
X292317Y412500D01*
X291817Y412583D01*
X291317Y412833D01*
X290900Y413250D01*
G01X296833Y412500D02*
Y415833D01*
G01Y415167D02*
X297250Y415500D01*
X297667Y415750D01*
X298250Y415833D01*
X298667Y415750D01*
X299167Y415500D01*
G01X302350Y414750D02*
X305017D01*
X304767Y415333D01*
X304350Y415667D01*
X303767Y415833D01*
X303183Y415750D01*
X302683Y415500D01*
X302350Y414917D01*
X302183Y414417D01*
Y413917D01*
X302350Y413417D01*
X302767Y412917D01*
X303267Y412583D01*
X303850Y412500D01*
X304433Y412667D01*
X305017Y413167D01*
G01X310700Y412500D02*
Y415833D01*
G01Y415250D02*
X310367Y415583D01*
X309867Y415750D01*
X309283Y415833D01*
X308700Y415667D01*
X308200Y415333D01*
X307867Y414833D01*
X307700Y414167D01*
X307867Y413500D01*
X308200Y413000D01*
X308700Y412667D01*
X309283Y412500D01*
X309867Y412583D01*
X310367Y412833D01*
X310700Y413167D01*
G01X313383Y412500D02*
Y417500D01*
G01X316050Y415833D02*
X313383Y413917D01*
G01X314467Y414667D02*
X316217Y412500D01*
G01X320400D02*
X319900Y412583D01*
X319400Y412917D01*
X319067Y413500D01*
X318900Y414167D01*
X319067Y414833D01*
X319400Y415417D01*
X319900Y415750D01*
X320400Y415833D01*
X320900Y415750D01*
X321400Y415417D01*
X321733Y414833D01*
X321817Y414167D01*
X321733Y413500D01*
X321400Y412917D01*
X320900Y412583D01*
X320400Y412500D01*
G01X324583Y415833D02*
Y413500D01*
X324917Y412917D01*
X325417Y412583D01*
X326000Y412500D01*
X326583Y412583D01*
X327083Y412917D01*
X327417Y413500D01*
G01Y412500D02*
Y415833D01*
G01X331600Y417500D02*
Y412500D01*
G01X330433Y415833D02*
X332767D01*
G01X342800D02*
Y412500D01*
G01Y417167D02*
X342633Y417250D01*
Y417417D01*
X342800Y417500D01*
X342967Y417417D01*
Y417250D01*
X342800Y417167D01*
G01X347150Y413083D02*
X347567Y412750D01*
X348150Y412500D01*
X348650D01*
X349150Y412667D01*
X349483Y412917D01*
X349650Y413250D01*
X349567Y413750D01*
X349233Y414000D01*
X347733Y414500D01*
X347400Y415083D01*
X347567Y415500D01*
X347900Y415750D01*
X348400Y415833D01*
X348900Y415750D01*
X349400Y415500D01*
G01X358183Y412500D02*
Y415833D01*
G01Y415000D02*
X358517Y415417D01*
X359017Y415750D01*
X359683Y415833D01*
X360267Y415750D01*
X360767Y415417D01*
X361017Y414833D01*
Y412500D01*
G01X365200D02*
X364700Y412583D01*
X364200Y412917D01*
X363867Y413500D01*
X363700Y414167D01*
X363867Y414833D01*
X364200Y415417D01*
X364700Y415750D01*
X365200Y415833D01*
X365700Y415750D01*
X366200Y415417D01*
X366533Y414833D01*
X366617Y414167D01*
X366533Y413500D01*
X366200Y412917D01*
X365700Y412583D01*
X365200Y412500D01*
G01X370800Y417500D02*
Y412500D01*
G01X369633Y415833D02*
X371967D01*
G01X383500Y412500D02*
Y415833D01*
G01Y415250D02*
X383167Y415583D01*
X382667Y415750D01*
X382083Y415833D01*
X381500Y415667D01*
X381000Y415333D01*
X380667Y414833D01*
X380500Y414167D01*
X380667Y413500D01*
X381000Y413000D01*
X381500Y412667D01*
X382083Y412500D01*
X382667Y412583D01*
X383167Y412833D01*
X383500Y413167D01*
G01X387600Y412500D02*
Y417500D01*
G01X393200Y412500D02*
Y417500D01*
G01X398800Y412500D02*
X398300Y412583D01*
X397800Y412917D01*
X397467Y413500D01*
X397300Y414167D01*
X397467Y414833D01*
X397800Y415417D01*
X398300Y415750D01*
X398800Y415833D01*
X399300Y415750D01*
X399800Y415417D01*
X400133Y414833D01*
X400217Y414167D01*
X400133Y413500D01*
X399800Y412917D01*
X399300Y412583D01*
X398800Y412500D01*
G01X402317Y415833D02*
X403317Y412500D01*
X404400Y415833D01*
X405483Y412500D01*
X406483Y415833D01*
G01X408750Y414750D02*
X411417D01*
X411167Y415333D01*
X410750Y415667D01*
X410167Y415833D01*
X409583Y415750D01*
X409083Y415500D01*
X408750Y414917D01*
X408583Y414417D01*
Y413917D01*
X408750Y413417D01*
X409167Y412917D01*
X409667Y412583D01*
X410250Y412500D01*
X410833Y412667D01*
X411417Y413167D01*
G01X417100Y417500D02*
Y412500D01*
G01Y413250D02*
X416767Y412833D01*
X416267Y412583D01*
X415683Y412500D01*
X415017Y412667D01*
X414517Y413083D01*
X414183Y413583D01*
X414100Y414167D01*
X414183Y414750D01*
X414517Y415250D01*
X415017Y415667D01*
X415683Y415833D01*
X416267Y415750D01*
X416683Y415583D01*
X417100Y415250D01*
G01X421033Y411583D02*
X421367Y412667D01*
G01X436500Y412500D02*
Y417500D01*
G01Y415000D02*
X436917Y415500D01*
X437417Y415750D01*
X437917Y415833D01*
X438667Y415667D01*
X439167Y415333D01*
X439500Y414750D01*
Y414083D01*
X439333Y413417D01*
X439000Y412917D01*
X438417Y412583D01*
X437917Y412500D01*
X437417Y412583D01*
X436917Y412833D01*
X436500Y413250D01*
G01X442183Y415833D02*
Y413500D01*
X442517Y412917D01*
X443017Y412583D01*
X443600Y412500D01*
X444183Y412583D01*
X444683Y412917D01*
X445017Y413500D01*
G01Y412500D02*
Y415833D01*
G01X449200Y417500D02*
Y412500D01*
G01X448033Y415833D02*
X450367D01*
G01X461900Y412500D02*
Y415833D01*
G01Y415250D02*
X461567Y415583D01*
X461067Y415750D01*
X460483Y415833D01*
X459900Y415667D01*
X459400Y415333D01*
X459067Y414833D01*
X458900Y414167D01*
X459067Y413500D01*
X459400Y413000D01*
X459900Y412667D01*
X460483Y412500D01*
X461067Y412583D01*
X461567Y412833D01*
X461900Y413167D01*
G01X464583Y412500D02*
Y415833D01*
G01Y415000D02*
X464917Y415417D01*
X465417Y415750D01*
X466083Y415833D01*
X466667Y415750D01*
X467167Y415417D01*
X467417Y414833D01*
Y412500D01*
G01X470183D02*
Y415833D01*
G01Y415000D02*
X470517Y415417D01*
X471017Y415750D01*
X471683Y415833D01*
X472267Y415750D01*
X472767Y415417D01*
X473017Y414833D01*
Y412500D01*
G01X475783Y415833D02*
Y413500D01*
X476117Y412917D01*
X476617Y412583D01*
X477200Y412500D01*
X477783Y412583D01*
X478283Y412917D01*
X478617Y413500D01*
G01Y412500D02*
Y415833D01*
G01X484300Y412500D02*
Y415833D01*
G01Y415250D02*
X483967Y415583D01*
X483467Y415750D01*
X482883Y415833D01*
X482300Y415667D01*
X481800Y415333D01*
X481467Y414833D01*
X481300Y414167D01*
X481467Y413500D01*
X481800Y413000D01*
X482300Y412667D01*
X482883Y412500D01*
X483467Y412583D01*
X483967Y412833D01*
X484300Y413167D01*
G01X488400Y412500D02*
Y417500D01*
G01X498433Y412500D02*
Y415833D01*
G01Y415167D02*
X498850Y415500D01*
X499267Y415750D01*
X499850Y415833D01*
X500267Y415750D01*
X500767Y415500D01*
G01X505200Y415833D02*
Y412500D01*
G01Y417167D02*
X505033Y417250D01*
Y417417D01*
X505200Y417500D01*
X505367Y417417D01*
Y417250D01*
X505200Y417167D01*
G01X509383Y412500D02*
Y415833D01*
G01Y415000D02*
X509717Y415417D01*
X510217Y415750D01*
X510883Y415833D01*
X511467Y415750D01*
X511967Y415417D01*
X512217Y414833D01*
Y412500D01*
G01X515233Y411250D02*
X515817Y410917D01*
X516483Y410833D01*
X517067Y410917D01*
X517567Y411333D01*
X517900Y411917D01*
Y415833D01*
G01Y415167D02*
X517567Y415500D01*
X517067Y415750D01*
X516483Y415833D01*
X515817Y415667D01*
X515400Y415333D01*
X515067Y414750D01*
X514900Y414167D01*
X514983Y413667D01*
X515317Y413083D01*
X515817Y412667D01*
X516483Y412500D01*
X516983Y412583D01*
X517567Y412917D01*
X517900Y413250D01*
G01X527600Y417500D02*
Y412500D01*
G01X526433Y415833D02*
X528767D01*
G01X534700Y412500D02*
Y415833D01*
G01Y415250D02*
X534367Y415583D01*
X533867Y415750D01*
X533283Y415833D01*
X532700Y415667D01*
X532200Y415333D01*
X531867Y414833D01*
X531700Y414167D01*
X531867Y413500D01*
X532200Y413000D01*
X532700Y412667D01*
X533283Y412500D01*
X533867Y412583D01*
X534367Y412833D01*
X534700Y413167D01*
G01X537383Y412500D02*
Y415833D01*
G01Y415000D02*
X537717Y415417D01*
X538217Y415750D01*
X538883Y415833D01*
X539467Y415750D01*
X539967Y415417D01*
X540217Y414833D01*
Y412500D01*
G01X543233Y411250D02*
X543817Y410917D01*
X544483Y410833D01*
X545067Y410917D01*
X545567Y411333D01*
X545900Y411917D01*
Y415833D01*
G01Y415167D02*
X545567Y415500D01*
X545067Y415750D01*
X544483Y415833D01*
X543817Y415667D01*
X543400Y415333D01*
X543067Y414750D01*
X542900Y414167D01*
X542983Y413667D01*
X543317Y413083D01*
X543817Y412667D01*
X544483Y412500D01*
X544983Y412583D01*
X545567Y412917D01*
X545900Y413250D01*
G01X548750Y414750D02*
X551417D01*
X551167Y415333D01*
X550750Y415667D01*
X550167Y415833D01*
X549583Y415750D01*
X549083Y415500D01*
X548750Y414917D01*
X548583Y414417D01*
Y413917D01*
X548750Y413417D01*
X549167Y412917D01*
X549667Y412583D01*
X550250Y412500D01*
X550833Y412667D01*
X551417Y413167D01*
G01X554183Y412500D02*
Y415833D01*
G01Y415000D02*
X554517Y415417D01*
X555017Y415750D01*
X555683Y415833D01*
X556267Y415750D01*
X556767Y415417D01*
X557017Y414833D01*
Y412500D01*
G01X562533Y415417D02*
X561950Y415750D01*
X561450Y415833D01*
X560783Y415667D01*
X560283Y415333D01*
X559950Y414750D01*
X559867Y414167D01*
X559950Y413583D01*
X560283Y413083D01*
X560783Y412667D01*
X561450Y412500D01*
X562033Y412667D01*
X562533Y413000D01*
G01X565050Y411000D02*
X565550Y410833D01*
X566217Y411000D01*
X566633Y411333D01*
X566967Y411750D01*
X567467Y413083D01*
X568550Y415833D01*
G01X565883D02*
X567467Y413083D01*
G01X578000Y415833D02*
Y412500D01*
G01Y417167D02*
X577833Y417250D01*
Y417417D01*
X578000Y417500D01*
X578167Y417417D01*
Y417250D01*
X578000Y417167D01*
G01X582350Y413083D02*
X582767Y412750D01*
X583350Y412500D01*
X583850D01*
X584350Y412667D01*
X584683Y412917D01*
X584850Y413250D01*
X584767Y413750D01*
X584433Y414000D01*
X582933Y414500D01*
X582600Y415083D01*
X582767Y415500D01*
X583100Y415750D01*
X583600Y415833D01*
X584100Y415750D01*
X584600Y415500D01*
G01X273000Y437500D02*
Y432500D01*
G01Y433250D02*
X272667Y432833D01*
X272167Y432583D01*
X271583Y432500D01*
X270917Y432667D01*
X270417Y433083D01*
X270083Y433583D01*
X270000Y434167D01*
X270083Y434750D01*
X270417Y435250D01*
X270917Y435667D01*
X271583Y435833D01*
X272167Y435750D01*
X272583Y435583D01*
X273000Y435250D01*
G01X275850Y434750D02*
X278517D01*
X278267Y435333D01*
X277850Y435667D01*
X277267Y435833D01*
X276683Y435750D01*
X276183Y435500D01*
X275850Y434917D01*
X275683Y434417D01*
Y433917D01*
X275850Y433417D01*
X276267Y432917D01*
X276767Y432583D01*
X277350Y432500D01*
X277933Y432667D01*
X278517Y433167D01*
G01X281200Y430833D02*
Y435833D01*
G01Y435083D02*
X281617Y435500D01*
X282033Y435750D01*
X282700Y435833D01*
X283283Y435750D01*
X283867Y435333D01*
X284117Y434750D01*
X284200Y434167D01*
X284117Y433583D01*
X283867Y433000D01*
X283367Y432667D01*
X282700Y432500D01*
X282117Y432583D01*
X281533Y432833D01*
X281200Y433167D01*
G01X288300Y437500D02*
Y432500D01*
G01X287133Y435833D02*
X289467D01*
G01X292483Y432500D02*
Y437500D01*
G01Y435083D02*
X292900Y435500D01*
X293317Y435750D01*
X293983Y435833D01*
X294483Y435750D01*
X295067Y435417D01*
X295317Y434917D01*
Y432500D01*
G01X305100Y437500D02*
Y432500D01*
G01X303933Y435833D02*
X306267D01*
G01X310700Y432500D02*
X310200Y432583D01*
X309700Y432917D01*
X309367Y433500D01*
X309200Y434167D01*
X309367Y434833D01*
X309700Y435417D01*
X310200Y435750D01*
X310700Y435833D01*
X311200Y435750D01*
X311700Y435417D01*
X312033Y434833D01*
X312117Y434167D01*
X312033Y433500D01*
X311700Y432917D01*
X311200Y432583D01*
X310700Y432500D01*
G01X316300D02*
Y437500D01*
G01X320650Y434750D02*
X323317D01*
X323067Y435333D01*
X322650Y435667D01*
X322067Y435833D01*
X321483Y435750D01*
X320983Y435500D01*
X320650Y434917D01*
X320483Y434417D01*
Y433917D01*
X320650Y433417D01*
X321067Y432917D01*
X321567Y432583D01*
X322150Y432500D01*
X322733Y432667D01*
X323317Y433167D01*
G01X326333Y432500D02*
Y435833D01*
G01Y435167D02*
X326750Y435500D01*
X327167Y435750D01*
X327750Y435833D01*
X328167Y435750D01*
X328667Y435500D01*
G01X334600Y432500D02*
Y435833D01*
G01Y435250D02*
X334267Y435583D01*
X333767Y435750D01*
X333183Y435833D01*
X332600Y435667D01*
X332100Y435333D01*
X331767Y434833D01*
X331600Y434167D01*
X331767Y433500D01*
X332100Y433000D01*
X332600Y432667D01*
X333183Y432500D01*
X333767Y432583D01*
X334267Y432833D01*
X334600Y433167D01*
G01X337283Y432500D02*
Y435833D01*
G01Y435000D02*
X337617Y435417D01*
X338117Y435750D01*
X338783Y435833D01*
X339367Y435750D01*
X339867Y435417D01*
X340117Y434833D01*
Y432500D01*
G01X345633Y435417D02*
X345050Y435750D01*
X344550Y435833D01*
X343883Y435667D01*
X343383Y435333D01*
X343050Y434750D01*
X342967Y434167D01*
X343050Y433583D01*
X343383Y433083D01*
X343883Y432667D01*
X344550Y432500D01*
X345133Y432667D01*
X345633Y433000D01*
G01X348650Y434750D02*
X351317D01*
X351067Y435333D01*
X350650Y435667D01*
X350067Y435833D01*
X349483Y435750D01*
X348983Y435500D01*
X348650Y434917D01*
X348483Y434417D01*
Y433917D01*
X348650Y433417D01*
X349067Y432917D01*
X349567Y432583D01*
X350150Y432500D01*
X350733Y432667D01*
X351317Y433167D01*
G01X262500Y397000D02*
Y679000D01*
G01X270750Y453500D02*
Y458500D01*
G01X274250D02*
Y453500D01*
G01Y456000D02*
X270750D01*
G01X278100Y453500D02*
X277600Y453583D01*
X277100Y453917D01*
X276767Y454500D01*
X276600Y455167D01*
X276767Y455833D01*
X277100Y456417D01*
X277600Y456750D01*
X278100Y456833D01*
X278600Y456750D01*
X279100Y456417D01*
X279433Y455833D01*
X279517Y455167D01*
X279433Y454500D01*
X279100Y453917D01*
X278600Y453583D01*
X278100Y453500D01*
G01X283700D02*
Y458500D01*
G01X288050Y455750D02*
X290717D01*
X290467Y456333D01*
X290050Y456667D01*
X289467Y456833D01*
X288883Y456750D01*
X288383Y456500D01*
X288050Y455917D01*
X287883Y455417D01*
Y454917D01*
X288050Y454417D01*
X288467Y453917D01*
X288967Y453583D01*
X289550Y453500D01*
X290133Y453667D01*
X290717Y454167D01*
G01X298000Y458500D02*
X299167Y453500D01*
X300500Y458500D01*
X301833Y453500D01*
X303000Y458500D01*
G01X307600Y453500D02*
Y456833D01*
G01Y456250D02*
X307267Y456583D01*
X306767Y456750D01*
X306183Y456833D01*
X305600Y456667D01*
X305100Y456333D01*
X304767Y455833D01*
X304600Y455167D01*
X304767Y454500D01*
X305100Y454000D01*
X305600Y453667D01*
X306183Y453500D01*
X306767Y453583D01*
X307267Y453833D01*
X307600Y454167D01*
G01X311700Y453500D02*
Y458500D01*
G01X317300Y453500D02*
Y458500D01*
G01X326833Y453500D02*
Y458500D01*
X328917D01*
X329583Y458250D01*
X330000Y457917D01*
X330167Y457250D01*
X330000Y456583D01*
X329500Y456167D01*
X328917Y455917D01*
X326833D01*
G01X328917D02*
X330167Y453500D01*
G01X334100D02*
X333600Y453583D01*
X333100Y453917D01*
X332767Y454500D01*
X332600Y455167D01*
X332767Y455833D01*
X333100Y456417D01*
X333600Y456750D01*
X334100Y456833D01*
X334600Y456750D01*
X335100Y456417D01*
X335433Y455833D01*
X335517Y455167D01*
X335433Y454500D01*
X335100Y453917D01*
X334600Y453583D01*
X334100Y453500D01*
G01X338283Y456833D02*
Y454500D01*
X338617Y453917D01*
X339117Y453583D01*
X339700Y453500D01*
X340283Y453583D01*
X340783Y453917D01*
X341117Y454500D01*
G01Y453500D02*
Y456833D01*
G01X344133Y452250D02*
X344717Y451917D01*
X345383Y451833D01*
X345967Y451917D01*
X346467Y452333D01*
X346800Y452917D01*
Y456833D01*
G01Y456167D02*
X346467Y456500D01*
X345967Y456750D01*
X345383Y456833D01*
X344717Y456667D01*
X344300Y456333D01*
X343967Y455750D01*
X343800Y455167D01*
X343883Y454667D01*
X344217Y454083D01*
X344717Y453667D01*
X345383Y453500D01*
X345883Y453583D01*
X346467Y453917D01*
X346800Y454250D01*
G01X349483Y453500D02*
Y458500D01*
G01Y456083D02*
X349900Y456500D01*
X350317Y456750D01*
X350983Y456833D01*
X351483Y456750D01*
X352067Y456417D01*
X352317Y455917D01*
Y453500D01*
G01X355083D02*
Y456833D01*
G01Y456000D02*
X355417Y456417D01*
X355917Y456750D01*
X356583Y456833D01*
X357167Y456750D01*
X357667Y456417D01*
X357917Y455833D01*
Y453500D01*
G01X360850Y455750D02*
X363517D01*
X363267Y456333D01*
X362850Y456667D01*
X362267Y456833D01*
X361683Y456750D01*
X361183Y456500D01*
X360850Y455917D01*
X360683Y455417D01*
Y454917D01*
X360850Y454417D01*
X361267Y453917D01*
X361767Y453583D01*
X362350Y453500D01*
X362933Y453667D01*
X363517Y454167D01*
G01X366450Y454083D02*
X366867Y453750D01*
X367450Y453500D01*
X367950D01*
X368450Y453667D01*
X368783Y453917D01*
X368950Y454250D01*
X368867Y454750D01*
X368533Y455000D01*
X367033Y455500D01*
X366700Y456083D01*
X366867Y456500D01*
X367200Y456750D01*
X367700Y456833D01*
X368200Y456750D01*
X368700Y456500D01*
G01X372050Y454083D02*
X372467Y453750D01*
X373050Y453500D01*
X373550D01*
X374050Y453667D01*
X374383Y453917D01*
X374550Y454250D01*
X374467Y454750D01*
X374133Y455000D01*
X372633Y455500D01*
X372300Y456083D01*
X372467Y456500D01*
X372800Y456750D01*
X373300Y456833D01*
X373800Y456750D01*
X374300Y456500D01*
G01X272500Y470000D02*
X271833Y470083D01*
X271250Y470417D01*
X270750Y470917D01*
X270417Y471500D01*
X270250Y472167D01*
Y472833D01*
X270417Y473500D01*
X270750Y474083D01*
X271250Y474583D01*
X271833Y474917D01*
X272500Y475000D01*
X273167Y474917D01*
X273750Y474583D01*
X274250Y474083D01*
X274583Y473500D01*
X274750Y472833D01*
Y472167D01*
X274583Y471500D01*
X274250Y470917D01*
X273750Y470417D01*
X273167Y470083D01*
X272500Y470000D01*
G01X278100Y475000D02*
Y470000D01*
G01X276933Y473333D02*
X279267D01*
G01X282283Y470000D02*
Y475000D01*
G01Y472583D02*
X282700Y473000D01*
X283117Y473250D01*
X283783Y473333D01*
X284283Y473250D01*
X284867Y472917D01*
X285117Y472417D01*
Y470000D01*
G01X288050Y472250D02*
X290717D01*
X290467Y472833D01*
X290050Y473167D01*
X289467Y473333D01*
X288883Y473250D01*
X288383Y473000D01*
X288050Y472417D01*
X287883Y471917D01*
Y471417D01*
X288050Y470917D01*
X288467Y470417D01*
X288967Y470083D01*
X289550Y470000D01*
X290133Y470167D01*
X290717Y470667D01*
G01X293733Y470000D02*
Y473333D01*
G01Y472667D02*
X294150Y473000D01*
X294567Y473250D01*
X295150Y473333D01*
X295567Y473250D01*
X296067Y473000D01*
G01X299250Y470583D02*
X299667Y470250D01*
X300250Y470000D01*
X300750D01*
X301250Y470167D01*
X301583Y470417D01*
X301750Y470750D01*
X301667Y471250D01*
X301333Y471500D01*
X299833Y472000D01*
X299500Y472583D01*
X299667Y473000D01*
X300000Y473250D01*
X300500Y473333D01*
X301000Y473250D01*
X301500Y473000D01*
G01X311283Y468333D02*
X310450Y469167D01*
X310033Y470000D01*
Y473333D01*
X310450Y474167D01*
X311283Y475000D01*
G01X317300Y470000D02*
Y475000D01*
G01X322900Y473333D02*
Y470000D01*
G01Y474667D02*
X322733Y474750D01*
Y474917D01*
X322900Y475000D01*
X323067Y474917D01*
Y474750D01*
X322900Y474667D01*
G01X327083Y470000D02*
Y475000D01*
G01X329750Y473333D02*
X327083Y471417D01*
G01X328167Y472167D02*
X329917Y470000D01*
G01X332850Y472250D02*
X335517D01*
X335267Y472833D01*
X334850Y473167D01*
X334267Y473333D01*
X333683Y473250D01*
X333183Y473000D01*
X332850Y472417D01*
X332683Y471917D01*
Y471417D01*
X332850Y470917D01*
X333267Y470417D01*
X333767Y470083D01*
X334350Y470000D01*
X334933Y470167D01*
X335517Y470667D01*
G01X344050Y472250D02*
X346717D01*
X346467Y472833D01*
X346050Y473167D01*
X345467Y473333D01*
X344883Y473250D01*
X344383Y473000D01*
X344050Y472417D01*
X343883Y471917D01*
Y471417D01*
X344050Y470917D01*
X344467Y470417D01*
X344967Y470083D01*
X345550Y470000D01*
X346133Y470167D01*
X346717Y470667D01*
G01X350900Y470000D02*
Y475000D01*
G01X356500Y470000D02*
Y475000D01*
G01X362100Y473333D02*
Y470000D01*
G01Y474667D02*
X361933Y474750D01*
Y474917D01*
X362100Y475000D01*
X362267Y474917D01*
Y474750D01*
X362100Y474667D01*
G01X366200Y468333D02*
Y473333D01*
G01Y472583D02*
X366617Y473000D01*
X367033Y473250D01*
X367700Y473333D01*
X368283Y473250D01*
X368867Y472833D01*
X369117Y472250D01*
X369200Y471667D01*
X369117Y471083D01*
X368867Y470500D01*
X368367Y470167D01*
X367700Y470000D01*
X367117Y470083D01*
X366533Y470333D01*
X366200Y470667D01*
G01X372050Y470583D02*
X372467Y470250D01*
X373050Y470000D01*
X373550D01*
X374050Y470167D01*
X374383Y470417D01*
X374550Y470750D01*
X374467Y471250D01*
X374133Y471500D01*
X372633Y472000D01*
X372300Y472583D01*
X372467Y473000D01*
X372800Y473250D01*
X373300Y473333D01*
X373800Y473250D01*
X374300Y473000D01*
G01X377650Y472250D02*
X380317D01*
X380067Y472833D01*
X379650Y473167D01*
X379067Y473333D01*
X378483Y473250D01*
X377983Y473000D01*
X377650Y472417D01*
X377483Y471917D01*
Y471417D01*
X377650Y470917D01*
X378067Y470417D01*
X378567Y470083D01*
X379150Y470000D01*
X379733Y470167D01*
X380317Y470667D01*
G01X391600Y470000D02*
Y473333D01*
G01Y472750D02*
X391267Y473083D01*
X390767Y473250D01*
X390183Y473333D01*
X389600Y473167D01*
X389100Y472833D01*
X388767Y472333D01*
X388600Y471667D01*
X388767Y471000D01*
X389100Y470500D01*
X389600Y470167D01*
X390183Y470000D01*
X390767Y470083D01*
X391267Y470333D01*
X391600Y470667D01*
G01X394283Y470000D02*
Y473333D01*
G01Y472500D02*
X394617Y472917D01*
X395117Y473250D01*
X395783Y473333D01*
X396367Y473250D01*
X396867Y472917D01*
X397117Y472333D01*
Y470000D01*
G01X402800Y475000D02*
Y470000D01*
G01Y470750D02*
X402467Y470333D01*
X401967Y470083D01*
X401383Y470000D01*
X400717Y470167D01*
X400217Y470583D01*
X399883Y471083D01*
X399800Y471667D01*
X399883Y472250D01*
X400217Y472750D01*
X400717Y473167D01*
X401383Y473333D01*
X401967Y473250D01*
X402383Y473083D01*
X402800Y472750D01*
G01X412500Y470000D02*
X412000Y470083D01*
X411500Y470417D01*
X411167Y471000D01*
X411000Y471667D01*
X411167Y472333D01*
X411500Y472917D01*
X412000Y473250D01*
X412500Y473333D01*
X413000Y473250D01*
X413500Y472917D01*
X413833Y472333D01*
X413917Y471667D01*
X413833Y471000D01*
X413500Y470417D01*
X413000Y470083D01*
X412500Y470000D01*
G01X418100Y475000D02*
Y470000D01*
G01X416933Y473333D02*
X419267D01*
G01X422283Y470000D02*
Y475000D01*
G01Y472583D02*
X422700Y473000D01*
X423117Y473250D01*
X423783Y473333D01*
X424283Y473250D01*
X424867Y472917D01*
X425117Y472417D01*
Y470000D01*
G01X428050Y472250D02*
X430717D01*
X430467Y472833D01*
X430050Y473167D01*
X429467Y473333D01*
X428883Y473250D01*
X428383Y473000D01*
X428050Y472417D01*
X427883Y471917D01*
Y471417D01*
X428050Y470917D01*
X428467Y470417D01*
X428967Y470083D01*
X429550Y470000D01*
X430133Y470167D01*
X430717Y470667D01*
G01X433733Y470000D02*
Y473333D01*
G01Y472667D02*
X434150Y473000D01*
X434567Y473250D01*
X435150Y473333D01*
X435567Y473250D01*
X436067Y473000D01*
G01X439250Y470583D02*
X439667Y470250D01*
X440250Y470000D01*
X440750D01*
X441250Y470167D01*
X441583Y470417D01*
X441750Y470750D01*
X441667Y471250D01*
X441333Y471500D01*
X439833Y472000D01*
X439500Y472583D01*
X439667Y473000D01*
X440000Y473250D01*
X440500Y473333D01*
X441000Y473250D01*
X441500Y473000D01*
G01X446517Y468333D02*
X447350Y469167D01*
X447767Y470000D01*
Y473333D01*
X447350Y474167D01*
X446517Y475000D01*
G01X270833Y485000D02*
Y490000D01*
X272833D01*
X273500Y489750D01*
X274000Y489167D01*
X274167Y488500D01*
X274000Y487833D01*
X273583Y487333D01*
X272833Y487083D01*
X270833D01*
G01X278100Y490000D02*
Y485000D01*
G01X276183Y490000D02*
X280017D01*
G01X281950Y485000D02*
Y490000D01*
G01X285450D02*
Y485000D01*
G01Y487500D02*
X281950D01*
G01X287800Y484833D02*
X290800Y490000D01*
G01X292983Y485000D02*
Y490000D01*
X296817Y485000D01*
Y490000D01*
G01X298833Y485000D02*
Y490000D01*
X300833D01*
X301500Y489750D01*
X302000Y489167D01*
X302167Y488500D01*
X302000Y487833D01*
X301583Y487333D01*
X300833Y487083D01*
X298833D01*
G01X306100Y490000D02*
Y485000D01*
G01X304183Y490000D02*
X308017D01*
G01X309950Y485000D02*
Y490000D01*
G01X313450D02*
Y485000D01*
G01Y487500D02*
X309950D01*
G01X321233Y485000D02*
X324567Y486667D01*
X321233Y488333D01*
G01X327417Y485917D02*
X329583D01*
G01Y487417D02*
X327417D01*
G01X332267Y485750D02*
X332767Y485333D01*
X333350Y485083D01*
X334100Y485000D01*
X334850Y485167D01*
X335433Y485500D01*
X335850Y486083D01*
X335933Y486750D01*
X335767Y487417D01*
X335350Y487833D01*
X334767Y488167D01*
X334183Y488250D01*
X333600Y488167D01*
X332850Y487833D01*
X333100Y490000D01*
X335350D01*
G01X342800Y485000D02*
Y488333D01*
G01Y487417D02*
X343050Y487833D01*
X343467Y488167D01*
X344050Y488333D01*
X344633Y488167D01*
X345050Y487833D01*
X345300Y487417D01*
Y485000D01*
G01Y487417D02*
X345550Y487833D01*
X345967Y488167D01*
X346550Y488333D01*
X347133Y488167D01*
X347550Y487833D01*
X347800Y487333D01*
Y485000D01*
G01X348400D02*
Y488333D01*
G01Y487417D02*
X348650Y487833D01*
X349067Y488167D01*
X349650Y488333D01*
X350233Y488167D01*
X350650Y487833D01*
X350900Y487417D01*
Y485000D01*
G01Y487417D02*
X351150Y487833D01*
X351567Y488167D01*
X352150Y488333D01*
X352733Y488167D01*
X353150Y487833D01*
X353400Y487333D01*
Y485000D01*
G01X270583Y498500D02*
Y503500D01*
X274417Y498500D01*
Y503500D01*
G01X276433Y498500D02*
Y503500D01*
X278433D01*
X279100Y503250D01*
X279600Y502667D01*
X279767Y502000D01*
X279600Y501333D01*
X279183Y500833D01*
X278433Y500583D01*
X276433D01*
G01X283700Y503500D02*
Y498500D01*
G01X281783Y503500D02*
X285617D01*
G01X287550Y498500D02*
Y503500D01*
G01X291050D02*
Y498500D01*
G01Y501000D02*
X287550D01*
G01X298750Y499167D02*
X299417Y498750D01*
X300167Y498500D01*
X300833D01*
X301500Y498750D01*
X302000Y499167D01*
X302250Y499750D01*
X302083Y500333D01*
X301667Y500833D01*
X300917Y501167D01*
X299917Y501333D01*
X299333Y501667D01*
X299083Y502250D01*
X299250Y502833D01*
X299667Y503250D01*
X300250Y503500D01*
X300833D01*
X301417Y503333D01*
X301917Y502917D01*
G01X306100Y501833D02*
Y498500D01*
G01Y503167D02*
X305933Y503250D01*
Y503417D01*
X306100Y503500D01*
X306267Y503417D01*
Y503250D01*
X306100Y503167D01*
G01X310450Y501833D02*
X312950D01*
X310450Y498500D01*
X312950D01*
G01X316050Y500750D02*
X318717D01*
X318467Y501333D01*
X318050Y501667D01*
X317467Y501833D01*
X316883Y501750D01*
X316383Y501500D01*
X316050Y500917D01*
X315883Y500417D01*
Y499917D01*
X316050Y499417D01*
X316467Y498917D01*
X316967Y498583D01*
X317550Y498500D01*
X318133Y498667D01*
X318717Y499167D01*
G01X326667Y499500D02*
X327167Y498917D01*
X327833Y498583D01*
X328583Y498500D01*
X329250Y498583D01*
X329917Y499000D01*
X330333Y499500D01*
X330417Y500000D01*
X330250Y500583D01*
X329667Y501000D01*
X329083Y501167D01*
X328333D01*
G01X329083D02*
X329583Y501417D01*
X330000Y501833D01*
X330167Y502333D01*
X330000Y502833D01*
X329583Y503250D01*
X328833Y503500D01*
X328083Y503417D01*
X327333Y503083D01*
G01X334100Y498333D02*
X333933Y498417D01*
Y498583D01*
X334100Y498667D01*
X334267Y498583D01*
Y498417D01*
X334100Y498333D01*
G01X337867Y499250D02*
X338367Y498833D01*
X338950Y498583D01*
X339700Y498500D01*
X340450Y498667D01*
X341033Y499000D01*
X341450Y499583D01*
X341533Y500250D01*
X341367Y500917D01*
X340950Y501333D01*
X340367Y501667D01*
X339783Y501750D01*
X339200Y501667D01*
X338450Y501333D01*
X338700Y503500D01*
X340950D01*
G01X343467Y499250D02*
X343967Y498833D01*
X344550Y498583D01*
X345300Y498500D01*
X346050Y498667D01*
X346633Y499000D01*
X347050Y499583D01*
X347133Y500250D01*
X346967Y500917D01*
X346550Y501333D01*
X345967Y501667D01*
X345383Y501750D01*
X344800Y501667D01*
X344050Y501333D01*
X344300Y503500D01*
X346550D01*
G01X348400Y498500D02*
Y501833D01*
G01Y500917D02*
X348650Y501333D01*
X349067Y501667D01*
X349650Y501833D01*
X350233Y501667D01*
X350650Y501333D01*
X350900Y500917D01*
Y498500D01*
G01Y500917D02*
X351150Y501333D01*
X351567Y501667D01*
X352150Y501833D01*
X352733Y501667D01*
X353150Y501333D01*
X353400Y500833D01*
Y498500D01*
G01X354000D02*
Y501833D01*
G01Y500917D02*
X354250Y501333D01*
X354667Y501667D01*
X355250Y501833D01*
X355833Y501667D01*
X356250Y501333D01*
X356500Y500917D01*
Y498500D01*
G01Y500917D02*
X356750Y501333D01*
X357167Y501667D01*
X357750Y501833D01*
X358333Y501667D01*
X358750Y501333D01*
X359000Y500833D01*
Y498500D01*
G01X270583Y513500D02*
Y518500D01*
X274417Y513500D01*
Y518500D01*
G01X276433Y513500D02*
Y518500D01*
X278433D01*
X279100Y518250D01*
X279600Y517667D01*
X279767Y517000D01*
X279600Y516333D01*
X279183Y515833D01*
X278433Y515583D01*
X276433D01*
G01X283700Y518500D02*
Y513500D01*
G01X281783Y518500D02*
X285617D01*
G01X287550Y513500D02*
Y518500D01*
G01X291050D02*
Y513500D01*
G01Y516000D02*
X287550D01*
G01X298750Y514167D02*
X299417Y513750D01*
X300167Y513500D01*
X300833D01*
X301500Y513750D01*
X302000Y514167D01*
X302250Y514750D01*
X302083Y515333D01*
X301667Y515833D01*
X300917Y516167D01*
X299917Y516333D01*
X299333Y516667D01*
X299083Y517250D01*
X299250Y517833D01*
X299667Y518250D01*
X300250Y518500D01*
X300833D01*
X301417Y518333D01*
X301917Y517917D01*
G01X306100Y516833D02*
Y513500D01*
G01Y518167D02*
X305933Y518250D01*
Y518417D01*
X306100Y518500D01*
X306267Y518417D01*
Y518250D01*
X306100Y518167D01*
G01X310450Y516833D02*
X312950D01*
X310450Y513500D01*
X312950D01*
G01X316050Y515750D02*
X318717D01*
X318467Y516333D01*
X318050Y516667D01*
X317467Y516833D01*
X316883Y516750D01*
X316383Y516500D01*
X316050Y515917D01*
X315883Y515417D01*
Y514917D01*
X316050Y514417D01*
X316467Y513917D01*
X316967Y513583D01*
X317550Y513500D01*
X318133Y513667D01*
X318717Y514167D01*
G01X324567Y513500D02*
X321233Y515167D01*
X324567Y516833D01*
G01X332267Y514250D02*
X332767Y513833D01*
X333350Y513583D01*
X334100Y513500D01*
X334850Y513667D01*
X335433Y514000D01*
X335850Y514583D01*
X335933Y515250D01*
X335767Y515917D01*
X335350Y516333D01*
X334767Y516667D01*
X334183Y516750D01*
X333600Y516667D01*
X332850Y516333D01*
X333100Y518500D01*
X335350D01*
G01X337200Y513500D02*
Y516833D01*
G01Y515917D02*
X337450Y516333D01*
X337867Y516667D01*
X338450Y516833D01*
X339033Y516667D01*
X339450Y516333D01*
X339700Y515917D01*
Y513500D01*
G01Y515917D02*
X339950Y516333D01*
X340367Y516667D01*
X340950Y516833D01*
X341533Y516667D01*
X341950Y516333D01*
X342200Y515833D01*
Y513500D01*
G01X342800D02*
Y516833D01*
G01Y515917D02*
X343050Y516333D01*
X343467Y516667D01*
X344050Y516833D01*
X344633Y516667D01*
X345050Y516333D01*
X345300Y515917D01*
Y513500D01*
G01Y515917D02*
X345550Y516333D01*
X345967Y516667D01*
X346550Y516833D01*
X347133Y516667D01*
X347550Y516333D01*
X347800Y515833D01*
Y513500D01*
G01X270667Y535000D02*
Y531417D01*
X271000Y530667D01*
X271667Y530167D01*
X272500Y530000D01*
X273333Y530167D01*
X274000Y530667D01*
X274333Y531417D01*
Y535000D01*
G01X276683Y530000D02*
Y533333D01*
G01Y532500D02*
X277017Y532917D01*
X277517Y533250D01*
X278183Y533333D01*
X278767Y533250D01*
X279267Y532917D01*
X279517Y532333D01*
Y530000D01*
G01X282617Y531667D02*
X284783D01*
G01X287800Y528333D02*
Y533333D01*
G01Y532583D02*
X288217Y533000D01*
X288633Y533250D01*
X289300Y533333D01*
X289883Y533250D01*
X290467Y532833D01*
X290717Y532250D01*
X290800Y531667D01*
X290717Y531083D01*
X290467Y530500D01*
X289967Y530167D01*
X289300Y530000D01*
X288717Y530083D01*
X288133Y530333D01*
X287800Y530667D01*
G01X294900Y530000D02*
Y535000D01*
G01X299083Y533333D02*
Y531000D01*
X299417Y530417D01*
X299917Y530083D01*
X300500Y530000D01*
X301083Y530083D01*
X301583Y530417D01*
X301917Y531000D01*
G01Y530000D02*
Y533333D01*
G01X304933Y528750D02*
X305517Y528417D01*
X306183Y528333D01*
X306767Y528417D01*
X307267Y528833D01*
X307600Y529417D01*
Y533333D01*
G01Y532667D02*
X307267Y533000D01*
X306767Y533250D01*
X306183Y533333D01*
X305517Y533167D01*
X305100Y532833D01*
X304767Y532250D01*
X304600Y531667D01*
X304683Y531167D01*
X305017Y530583D01*
X305517Y530167D01*
X306183Y530000D01*
X306683Y530083D01*
X307267Y530417D01*
X307600Y530750D01*
G01X310533Y528750D02*
X311117Y528417D01*
X311783Y528333D01*
X312367Y528417D01*
X312867Y528833D01*
X313200Y529417D01*
Y533333D01*
G01Y532667D02*
X312867Y533000D01*
X312367Y533250D01*
X311783Y533333D01*
X311117Y533167D01*
X310700Y532833D01*
X310367Y532250D01*
X310200Y531667D01*
X310283Y531167D01*
X310617Y530583D01*
X311117Y530167D01*
X311783Y530000D01*
X312283Y530083D01*
X312867Y530417D01*
X313200Y530750D01*
G01X316050Y532250D02*
X318717D01*
X318467Y532833D01*
X318050Y533167D01*
X317467Y533333D01*
X316883Y533250D01*
X316383Y533000D01*
X316050Y532417D01*
X315883Y531917D01*
Y531417D01*
X316050Y530917D01*
X316467Y530417D01*
X316967Y530083D01*
X317550Y530000D01*
X318133Y530167D01*
X318717Y530667D01*
G01X324400Y535000D02*
Y530000D01*
G01Y530750D02*
X324067Y530333D01*
X323567Y530083D01*
X322983Y530000D01*
X322317Y530167D01*
X321817Y530583D01*
X321483Y531083D01*
X321400Y531667D01*
X321483Y532250D01*
X321817Y532750D01*
X322317Y533167D01*
X322983Y533333D01*
X323567Y533250D01*
X323983Y533083D01*
X324400Y532750D01*
G01X332433Y530000D02*
Y535000D01*
X334433D01*
X335100Y534750D01*
X335600Y534167D01*
X335767Y533500D01*
X335600Y532833D01*
X335183Y532333D01*
X334433Y532083D01*
X332433D01*
G01X339700Y535000D02*
Y530000D01*
G01X337783Y535000D02*
X341617D01*
G01X343550Y530000D02*
Y535000D01*
G01X347050D02*
Y530000D01*
G01Y532500D02*
X343550D01*
G01X356083Y528333D02*
X355250Y529167D01*
X354833Y530000D01*
Y533333D01*
X355250Y534167D01*
X356083Y535000D01*
G01X360350Y530000D02*
Y535000D01*
G01X363850D02*
Y530000D01*
G01Y532500D02*
X360350D01*
G01X367700Y530000D02*
X367200Y530083D01*
X366700Y530417D01*
X366367Y531000D01*
X366200Y531667D01*
X366367Y532333D01*
X366700Y532917D01*
X367200Y533250D01*
X367700Y533333D01*
X368200Y533250D01*
X368700Y532917D01*
X369033Y532333D01*
X369117Y531667D01*
X369033Y531000D01*
X368700Y530417D01*
X368200Y530083D01*
X367700Y530000D01*
G01X373300D02*
Y535000D01*
G01X377650Y532250D02*
X380317D01*
X380067Y532833D01*
X379650Y533167D01*
X379067Y533333D01*
X378483Y533250D01*
X377983Y533000D01*
X377650Y532417D01*
X377483Y531917D01*
Y531417D01*
X377650Y530917D01*
X378067Y530417D01*
X378567Y530083D01*
X379150Y530000D01*
X379733Y530167D01*
X380317Y530667D01*
G01X388350D02*
X389017Y530250D01*
X389767Y530000D01*
X390433D01*
X391100Y530250D01*
X391600Y530667D01*
X391850Y531250D01*
X391683Y531833D01*
X391267Y532333D01*
X390517Y532667D01*
X389517Y532833D01*
X388933Y533167D01*
X388683Y533750D01*
X388850Y534333D01*
X389267Y534750D01*
X389850Y535000D01*
X390433D01*
X391017Y534833D01*
X391517Y534417D01*
G01X395700Y533333D02*
Y530000D01*
G01Y534667D02*
X395533Y534750D01*
Y534917D01*
X395700Y535000D01*
X395867Y534917D01*
Y534750D01*
X395700Y534667D01*
G01X400050Y533333D02*
X402550D01*
X400050Y530000D01*
X402550D01*
G01X405650Y532250D02*
X408317D01*
X408067Y532833D01*
X407650Y533167D01*
X407067Y533333D01*
X406483Y533250D01*
X405983Y533000D01*
X405650Y532417D01*
X405483Y531917D01*
Y531417D01*
X405650Y530917D01*
X406067Y530417D01*
X406567Y530083D01*
X407150Y530000D01*
X407733Y530167D01*
X408317Y530667D01*
G01X414167Y530000D02*
X410833Y531667D01*
X414167Y533333D01*
G01X418100Y530000D02*
Y535000D01*
X417100Y534000D01*
G01Y530000D02*
X419100D01*
G01X422283Y530583D02*
X422867Y530167D01*
X423533Y530000D01*
X424200Y530167D01*
X424783Y530667D01*
X425200Y531417D01*
X425367Y532167D01*
Y533083D01*
X425200Y533833D01*
X424783Y534500D01*
X424283Y534833D01*
X423700Y535000D01*
X423033Y534833D01*
X422533Y534500D01*
X422200Y534000D01*
X422033Y533333D01*
X422200Y532750D01*
X422617Y532167D01*
X423117Y531833D01*
X423700Y531750D01*
X424367Y531917D01*
X424867Y532333D01*
X425367Y533083D01*
G01X429133Y530000D02*
X429300Y531083D01*
X429550Y532000D01*
X429883Y532833D01*
X430300Y533750D01*
X430967Y535000D01*
X427633D01*
G01X432400Y530000D02*
Y533333D01*
G01Y532417D02*
X432650Y532833D01*
X433067Y533167D01*
X433650Y533333D01*
X434233Y533167D01*
X434650Y532833D01*
X434900Y532417D01*
Y530000D01*
G01Y532417D02*
X435150Y532833D01*
X435567Y533167D01*
X436150Y533333D01*
X436733Y533167D01*
X437150Y532833D01*
X437400Y532333D01*
Y530000D01*
G01X440500Y533333D02*
Y530000D01*
G01Y534667D02*
X440333Y534750D01*
Y534917D01*
X440500Y535000D01*
X440667Y534917D01*
Y534750D01*
X440500Y534667D01*
G01X446100Y530000D02*
Y535000D01*
G01X455217Y533333D02*
X456217Y530000D01*
X457300Y533333D01*
X458383Y530000D01*
X459383Y533333D01*
G01X462900D02*
Y530000D01*
G01Y534667D02*
X462733Y534750D01*
Y534917D01*
X462900Y535000D01*
X463067Y534917D01*
Y534750D01*
X462900Y534667D01*
G01X468500Y535000D02*
Y530000D01*
G01X467333Y533333D02*
X469667D01*
G01X472683Y530000D02*
Y535000D01*
G01Y532583D02*
X473100Y533000D01*
X473517Y533250D01*
X474183Y533333D01*
X474683Y533250D01*
X475267Y532917D01*
X475517Y532417D01*
Y530000D01*
G01X483550D02*
Y535000D01*
G01X487050D02*
Y530000D01*
G01Y532500D02*
X483550D01*
G01X488817Y530000D02*
X490900Y535000D01*
X492983Y530000D01*
G01X492233Y531750D02*
X489567D01*
G01X494750Y530667D02*
X495417Y530250D01*
X496167Y530000D01*
X496833D01*
X497500Y530250D01*
X498000Y530667D01*
X498250Y531250D01*
X498083Y531833D01*
X497667Y532333D01*
X496917Y532667D01*
X495917Y532833D01*
X495333Y533167D01*
X495083Y533750D01*
X495250Y534333D01*
X495667Y534750D01*
X496250Y535000D01*
X496833D01*
X497417Y534833D01*
X497917Y534417D01*
G01X500433Y535000D02*
Y530000D01*
X503767D01*
G01X511800Y528333D02*
Y533333D01*
G01Y532583D02*
X512217Y533000D01*
X512633Y533250D01*
X513300Y533333D01*
X513883Y533250D01*
X514467Y532833D01*
X514717Y532250D01*
X514800Y531667D01*
X514717Y531083D01*
X514467Y530500D01*
X513967Y530167D01*
X513300Y530000D01*
X512717Y530083D01*
X512133Y530333D01*
X511800Y530667D01*
G01X517733Y530000D02*
Y533333D01*
G01Y532667D02*
X518150Y533000D01*
X518567Y533250D01*
X519150Y533333D01*
X519567Y533250D01*
X520067Y533000D01*
G01X524500Y530000D02*
X524000Y530083D01*
X523500Y530417D01*
X523167Y531000D01*
X523000Y531667D01*
X523167Y532333D01*
X523500Y532917D01*
X524000Y533250D01*
X524500Y533333D01*
X525000Y533250D01*
X525500Y532917D01*
X525833Y532333D01*
X525917Y531667D01*
X525833Y531000D01*
X525500Y530417D01*
X525000Y530083D01*
X524500Y530000D01*
G01X531600Y535000D02*
Y530000D01*
G01Y530750D02*
X531267Y530333D01*
X530767Y530083D01*
X530183Y530000D01*
X529517Y530167D01*
X529017Y530583D01*
X528683Y531083D01*
X528600Y531667D01*
X528683Y532250D01*
X529017Y532750D01*
X529517Y533167D01*
X530183Y533333D01*
X530767Y533250D01*
X531183Y533083D01*
X531600Y532750D01*
G01X534283Y533333D02*
Y531000D01*
X534617Y530417D01*
X535117Y530083D01*
X535700Y530000D01*
X536283Y530083D01*
X536783Y530417D01*
X537117Y531000D01*
G01Y530000D02*
Y533333D01*
G01X542633Y532917D02*
X542050Y533250D01*
X541550Y533333D01*
X540883Y533167D01*
X540383Y532833D01*
X540050Y532250D01*
X539967Y531667D01*
X540050Y531083D01*
X540383Y530583D01*
X540883Y530167D01*
X541550Y530000D01*
X542133Y530167D01*
X542633Y530500D01*
G01X546900Y535000D02*
Y530000D01*
G01X545733Y533333D02*
X548067D01*
G01X551250Y530583D02*
X551667Y530250D01*
X552250Y530000D01*
X552750D01*
X553250Y530167D01*
X553583Y530417D01*
X553750Y530750D01*
X553667Y531250D01*
X553333Y531500D01*
X551833Y532000D01*
X551500Y532583D01*
X551667Y533000D01*
X552000Y533250D01*
X552500Y533333D01*
X553000Y533250D01*
X553500Y533000D01*
G01X558517Y528333D02*
X559350Y529167D01*
X559767Y530000D01*
Y533333D01*
X559350Y534167D01*
X558517Y535000D01*
G01X262500Y479000D02*
X694500D01*
G01X262500Y494000D02*
X694500D01*
G01X262500Y509000D02*
X694500D01*
G01X262500Y524000D02*
X694500D01*
G01X273000Y609000D02*
Y604000D01*
G01X271083Y609000D02*
X274917D01*
G01X277183Y604000D02*
Y609000D01*
G01Y606583D02*
X277600Y607000D01*
X278017Y607250D01*
X278683Y607333D01*
X279183Y607250D01*
X279767Y606917D01*
X280017Y606417D01*
Y604000D01*
G01X282950Y606250D02*
X285617D01*
X285367Y606833D01*
X284950Y607167D01*
X284367Y607333D01*
X283783Y607250D01*
X283283Y607000D01*
X282950Y606417D01*
X282783Y605917D01*
Y605417D01*
X282950Y604917D01*
X283367Y604417D01*
X283867Y604083D01*
X284450Y604000D01*
X285033Y604167D01*
X285617Y604667D01*
G01X288633Y604000D02*
Y607333D01*
G01Y606667D02*
X289050Y607000D01*
X289467Y607250D01*
X290050Y607333D01*
X290467Y607250D01*
X290967Y607000D01*
G01X292900Y604000D02*
Y607333D01*
G01Y606417D02*
X293150Y606833D01*
X293567Y607167D01*
X294150Y607333D01*
X294733Y607167D01*
X295150Y606833D01*
X295400Y606417D01*
Y604000D01*
G01Y606417D02*
X295650Y606833D01*
X296067Y607167D01*
X296650Y607333D01*
X297233Y607167D01*
X297650Y606833D01*
X297900Y606333D01*
Y604000D01*
G01X302500D02*
Y607333D01*
G01Y606750D02*
X302167Y607083D01*
X301667Y607250D01*
X301083Y607333D01*
X300500Y607167D01*
X300000Y606833D01*
X299667Y606333D01*
X299500Y605667D01*
X299667Y605000D01*
X300000Y604500D01*
X300500Y604167D01*
X301083Y604000D01*
X301667Y604083D01*
X302167Y604333D01*
X302500Y604667D01*
G01X306600Y604000D02*
Y609000D01*
G01X316300Y602333D02*
Y607333D01*
G01Y606583D02*
X316717Y607000D01*
X317133Y607250D01*
X317800Y607333D01*
X318383Y607250D01*
X318967Y606833D01*
X319217Y606250D01*
X319300Y605667D01*
X319217Y605083D01*
X318967Y604500D01*
X318467Y604167D01*
X317800Y604000D01*
X317217Y604083D01*
X316633Y604333D01*
X316300Y604667D01*
G01X324900Y604000D02*
Y607333D01*
G01Y606750D02*
X324567Y607083D01*
X324067Y607250D01*
X323483Y607333D01*
X322900Y607167D01*
X322400Y606833D01*
X322067Y606333D01*
X321900Y605667D01*
X322067Y605000D01*
X322400Y604500D01*
X322900Y604167D01*
X323483Y604000D01*
X324067Y604083D01*
X324567Y604333D01*
X324900Y604667D01*
G01X330500Y609000D02*
Y604000D01*
G01Y604750D02*
X330167Y604333D01*
X329667Y604083D01*
X329083Y604000D01*
X328417Y604167D01*
X327917Y604583D01*
X327583Y605083D01*
X327500Y605667D01*
X327583Y606250D01*
X327917Y606750D01*
X328417Y607167D01*
X329083Y607333D01*
X329667Y607250D01*
X330083Y607083D01*
X330500Y606750D01*
G01X341533Y606917D02*
X340950Y607250D01*
X340450Y607333D01*
X339783Y607167D01*
X339283Y606833D01*
X338950Y606250D01*
X338867Y605667D01*
X338950Y605083D01*
X339283Y604583D01*
X339783Y604167D01*
X340450Y604000D01*
X341033Y604167D01*
X341533Y604500D01*
G01X347300Y604000D02*
Y607333D01*
G01Y606750D02*
X346967Y607083D01*
X346467Y607250D01*
X345883Y607333D01*
X345300Y607167D01*
X344800Y606833D01*
X344467Y606333D01*
X344300Y605667D01*
X344467Y605000D01*
X344800Y604500D01*
X345300Y604167D01*
X345883Y604000D01*
X346467Y604083D01*
X346967Y604333D01*
X347300Y604667D01*
G01X349983Y604000D02*
Y607333D01*
G01Y606500D02*
X350317Y606917D01*
X350817Y607250D01*
X351483Y607333D01*
X352067Y607250D01*
X352567Y606917D01*
X352817Y606333D01*
Y604000D01*
G01X363933Y606917D02*
X363350Y607250D01*
X362850Y607333D01*
X362183Y607167D01*
X361683Y606833D01*
X361350Y606250D01*
X361267Y605667D01*
X361350Y605083D01*
X361683Y604583D01*
X362183Y604167D01*
X362850Y604000D01*
X363433Y604167D01*
X363933Y604500D01*
G01X366783Y604000D02*
Y609000D01*
G01Y606583D02*
X367200Y607000D01*
X367617Y607250D01*
X368283Y607333D01*
X368783Y607250D01*
X369367Y606917D01*
X369617Y606417D01*
Y604000D01*
G01X375300D02*
Y607333D01*
G01Y606750D02*
X374967Y607083D01*
X374467Y607250D01*
X373883Y607333D01*
X373300Y607167D01*
X372800Y606833D01*
X372467Y606333D01*
X372300Y605667D01*
X372467Y605000D01*
X372800Y604500D01*
X373300Y604167D01*
X373883Y604000D01*
X374467Y604083D01*
X374967Y604333D01*
X375300Y604667D01*
G01X377983Y604000D02*
Y607333D01*
G01Y606500D02*
X378317Y606917D01*
X378817Y607250D01*
X379483Y607333D01*
X380067Y607250D01*
X380567Y606917D01*
X380817Y606333D01*
Y604000D01*
G01X383833Y602750D02*
X384417Y602417D01*
X385083Y602333D01*
X385667Y602417D01*
X386167Y602833D01*
X386500Y603417D01*
Y607333D01*
G01Y606667D02*
X386167Y607000D01*
X385667Y607250D01*
X385083Y607333D01*
X384417Y607167D01*
X384000Y606833D01*
X383667Y606250D01*
X383500Y605667D01*
X383583Y605167D01*
X383917Y604583D01*
X384417Y604167D01*
X385083Y604000D01*
X385583Y604083D01*
X386167Y604417D01*
X386500Y604750D01*
G01X389350Y606250D02*
X392017D01*
X391767Y606833D01*
X391350Y607167D01*
X390767Y607333D01*
X390183Y607250D01*
X389683Y607000D01*
X389350Y606417D01*
X389183Y605917D01*
Y605417D01*
X389350Y604917D01*
X389767Y604417D01*
X390267Y604083D01*
X390850Y604000D01*
X391433Y604167D01*
X392017Y604667D01*
G01X401800Y607333D02*
Y604000D01*
G01Y608667D02*
X401633Y608750D01*
Y608917D01*
X401800Y609000D01*
X401967Y608917D01*
Y608750D01*
X401800Y608667D01*
G01X405983Y604000D02*
Y607333D01*
G01Y606500D02*
X406317Y606917D01*
X406817Y607250D01*
X407483Y607333D01*
X408067Y607250D01*
X408567Y606917D01*
X408817Y606333D01*
Y604000D01*
G01X413000Y609000D02*
Y604000D01*
G01X411833Y607333D02*
X414167D01*
G01X418600Y604000D02*
X418100Y604083D01*
X417600Y604417D01*
X417267Y605000D01*
X417100Y605667D01*
X417267Y606333D01*
X417600Y606917D01*
X418100Y607250D01*
X418600Y607333D01*
X419100Y607250D01*
X419600Y606917D01*
X419933Y606333D01*
X420017Y605667D01*
X419933Y605000D01*
X419600Y604417D01*
X419100Y604083D01*
X418600Y604000D01*
G01X429300D02*
Y608250D01*
X429467Y608667D01*
X429800Y608917D01*
X430300Y609000D01*
X430800Y608833D01*
X431050Y608417D01*
G01X430050Y607000D02*
X428383D01*
G01X433983Y607333D02*
Y605000D01*
X434317Y604417D01*
X434817Y604083D01*
X435400Y604000D01*
X435983Y604083D01*
X436483Y604417D01*
X436817Y605000D01*
G01Y604000D02*
Y607333D01*
G01X441000Y604000D02*
Y609000D01*
G01X446600Y604000D02*
Y609000D01*
G01X459133Y606917D02*
X458550Y607250D01*
X458050Y607333D01*
X457383Y607167D01*
X456883Y606833D01*
X456550Y606250D01*
X456467Y605667D01*
X456550Y605083D01*
X456883Y604583D01*
X457383Y604167D01*
X458050Y604000D01*
X458633Y604167D01*
X459133Y604500D01*
G01X463400Y604000D02*
X462900Y604083D01*
X462400Y604417D01*
X462067Y605000D01*
X461900Y605667D01*
X462067Y606333D01*
X462400Y606917D01*
X462900Y607250D01*
X463400Y607333D01*
X463900Y607250D01*
X464400Y606917D01*
X464733Y606333D01*
X464817Y605667D01*
X464733Y605000D01*
X464400Y604417D01*
X463900Y604083D01*
X463400Y604000D01*
G01X467583D02*
Y607333D01*
G01Y606500D02*
X467917Y606917D01*
X468417Y607250D01*
X469083Y607333D01*
X469667Y607250D01*
X470167Y606917D01*
X470417Y606333D01*
Y604000D01*
G01X474600Y609000D02*
Y604000D01*
G01X473433Y607333D02*
X475767D01*
G01X481700Y604000D02*
Y607333D01*
G01Y606750D02*
X481367Y607083D01*
X480867Y607250D01*
X480283Y607333D01*
X479700Y607167D01*
X479200Y606833D01*
X478867Y606333D01*
X478700Y605667D01*
X478867Y605000D01*
X479200Y604500D01*
X479700Y604167D01*
X480283Y604000D01*
X480867Y604083D01*
X481367Y604333D01*
X481700Y604667D01*
G01X487133Y606917D02*
X486550Y607250D01*
X486050Y607333D01*
X485383Y607167D01*
X484883Y606833D01*
X484550Y606250D01*
X484467Y605667D01*
X484550Y605083D01*
X484883Y604583D01*
X485383Y604167D01*
X486050Y604000D01*
X486633Y604167D01*
X487133Y604500D01*
G01X491400Y609000D02*
Y604000D01*
G01X490233Y607333D02*
X492567D01*
G01X270417Y588500D02*
X272500Y593500D01*
X274583Y588500D01*
G01X273833Y590250D02*
X271167D01*
G01X276683Y588500D02*
Y591833D01*
G01Y591000D02*
X277017Y591417D01*
X277517Y591750D01*
X278183Y591833D01*
X278767Y591750D01*
X279267Y591417D01*
X279517Y590833D01*
Y588500D01*
G01X281950Y587000D02*
X282450Y586833D01*
X283117Y587000D01*
X283533Y587333D01*
X283867Y587750D01*
X284367Y589083D01*
X285450Y591833D01*
G01X282783D02*
X284367Y589083D01*
G01X293483Y588500D02*
Y593500D01*
G01Y591083D02*
X293900Y591500D01*
X294317Y591750D01*
X294983Y591833D01*
X295483Y591750D01*
X296067Y591417D01*
X296317Y590917D01*
Y588500D01*
G01X300500D02*
X300000Y588583D01*
X299500Y588917D01*
X299167Y589500D01*
X299000Y590167D01*
X299167Y590833D01*
X299500Y591417D01*
X300000Y591750D01*
X300500Y591833D01*
X301000Y591750D01*
X301500Y591417D01*
X301833Y590833D01*
X301917Y590167D01*
X301833Y589500D01*
X301500Y588917D01*
X301000Y588583D01*
X300500Y588500D01*
G01X306100D02*
Y593500D01*
G01X310450Y590750D02*
X313117D01*
X312867Y591333D01*
X312450Y591667D01*
X311867Y591833D01*
X311283Y591750D01*
X310783Y591500D01*
X310450Y590917D01*
X310283Y590417D01*
Y589917D01*
X310450Y589417D01*
X310867Y588917D01*
X311367Y588583D01*
X311950Y588500D01*
X312533Y588667D01*
X313117Y589167D01*
G01X322900Y593500D02*
Y588500D01*
G01X321733Y591833D02*
X324067D01*
G01X328500Y588500D02*
X328000Y588583D01*
X327500Y588917D01*
X327167Y589500D01*
X327000Y590167D01*
X327167Y590833D01*
X327500Y591417D01*
X328000Y591750D01*
X328500Y591833D01*
X329000Y591750D01*
X329500Y591417D01*
X329833Y590833D01*
X329917Y590167D01*
X329833Y589500D01*
X329500Y588917D01*
X329000Y588583D01*
X328500Y588500D01*
G01X338283D02*
Y593500D01*
G01Y591083D02*
X338700Y591500D01*
X339117Y591750D01*
X339783Y591833D01*
X340283Y591750D01*
X340867Y591417D01*
X341117Y590917D01*
Y588500D01*
G01X345300D02*
X344800Y588583D01*
X344300Y588917D01*
X343967Y589500D01*
X343800Y590167D01*
X343967Y590833D01*
X344300Y591417D01*
X344800Y591750D01*
X345300Y591833D01*
X345800Y591750D01*
X346300Y591417D01*
X346633Y590833D01*
X346717Y590167D01*
X346633Y589500D01*
X346300Y588917D01*
X345800Y588583D01*
X345300Y588500D01*
G01X350900D02*
Y593500D01*
G01X355250Y590750D02*
X357917D01*
X357667Y591333D01*
X357250Y591667D01*
X356667Y591833D01*
X356083Y591750D01*
X355583Y591500D01*
X355250Y590917D01*
X355083Y590417D01*
Y589917D01*
X355250Y589417D01*
X355667Y588917D01*
X356167Y588583D01*
X356750Y588500D01*
X357333Y588667D01*
X357917Y589167D01*
G01X270667Y550000D02*
Y546417D01*
X271000Y545667D01*
X271667Y545167D01*
X272500Y545000D01*
X273333Y545167D01*
X274000Y545667D01*
X274333Y546417D01*
Y550000D01*
G01X276683Y545000D02*
Y548333D01*
G01Y547500D02*
X277017Y547917D01*
X277517Y548250D01*
X278183Y548333D01*
X278767Y548250D01*
X279267Y547917D01*
X279517Y547333D01*
Y545000D01*
G01X282617Y546667D02*
X284783D01*
G01X287800Y543333D02*
Y548333D01*
G01Y547583D02*
X288217Y548000D01*
X288633Y548250D01*
X289300Y548333D01*
X289883Y548250D01*
X290467Y547833D01*
X290717Y547250D01*
X290800Y546667D01*
X290717Y546083D01*
X290467Y545500D01*
X289967Y545167D01*
X289300Y545000D01*
X288717Y545083D01*
X288133Y545333D01*
X287800Y545667D01*
G01X294900Y545000D02*
Y550000D01*
G01X299083Y548333D02*
Y546000D01*
X299417Y545417D01*
X299917Y545083D01*
X300500Y545000D01*
X301083Y545083D01*
X301583Y545417D01*
X301917Y546000D01*
G01Y545000D02*
Y548333D01*
G01X304933Y543750D02*
X305517Y543417D01*
X306183Y543333D01*
X306767Y543417D01*
X307267Y543833D01*
X307600Y544417D01*
Y548333D01*
G01Y547667D02*
X307267Y548000D01*
X306767Y548250D01*
X306183Y548333D01*
X305517Y548167D01*
X305100Y547833D01*
X304767Y547250D01*
X304600Y546667D01*
X304683Y546167D01*
X305017Y545583D01*
X305517Y545167D01*
X306183Y545000D01*
X306683Y545083D01*
X307267Y545417D01*
X307600Y545750D01*
G01X310533Y543750D02*
X311117Y543417D01*
X311783Y543333D01*
X312367Y543417D01*
X312867Y543833D01*
X313200Y544417D01*
Y548333D01*
G01Y547667D02*
X312867Y548000D01*
X312367Y548250D01*
X311783Y548333D01*
X311117Y548167D01*
X310700Y547833D01*
X310367Y547250D01*
X310200Y546667D01*
X310283Y546167D01*
X310617Y545583D01*
X311117Y545167D01*
X311783Y545000D01*
X312283Y545083D01*
X312867Y545417D01*
X313200Y545750D01*
G01X316050Y547250D02*
X318717D01*
X318467Y547833D01*
X318050Y548167D01*
X317467Y548333D01*
X316883Y548250D01*
X316383Y548000D01*
X316050Y547417D01*
X315883Y546917D01*
Y546417D01*
X316050Y545917D01*
X316467Y545417D01*
X316967Y545083D01*
X317550Y545000D01*
X318133Y545167D01*
X318717Y545667D01*
G01X324400Y550000D02*
Y545000D01*
G01Y545750D02*
X324067Y545333D01*
X323567Y545083D01*
X322983Y545000D01*
X322317Y545167D01*
X321817Y545583D01*
X321483Y546083D01*
X321400Y546667D01*
X321483Y547250D01*
X321817Y547750D01*
X322317Y548167D01*
X322983Y548333D01*
X323567Y548250D01*
X323983Y548083D01*
X324400Y547750D01*
G01X332433Y545000D02*
Y550000D01*
X334433D01*
X335100Y549750D01*
X335600Y549167D01*
X335767Y548500D01*
X335600Y547833D01*
X335183Y547333D01*
X334433Y547083D01*
X332433D01*
G01X339700Y550000D02*
Y545000D01*
G01X337783Y550000D02*
X341617D01*
G01X343550Y545000D02*
Y550000D01*
G01X347050D02*
Y545000D01*
G01Y547500D02*
X343550D01*
G01X356083Y543333D02*
X355250Y544167D01*
X354833Y545000D01*
Y548333D01*
X355250Y549167D01*
X356083Y550000D01*
G01X360350Y545000D02*
Y550000D01*
G01X363850D02*
Y545000D01*
G01Y547500D02*
X360350D01*
G01X367700Y545000D02*
X367200Y545083D01*
X366700Y545417D01*
X366367Y546000D01*
X366200Y546667D01*
X366367Y547333D01*
X366700Y547917D01*
X367200Y548250D01*
X367700Y548333D01*
X368200Y548250D01*
X368700Y547917D01*
X369033Y547333D01*
X369117Y546667D01*
X369033Y546000D01*
X368700Y545417D01*
X368200Y545083D01*
X367700Y545000D01*
G01X373300D02*
Y550000D01*
G01X377650Y547250D02*
X380317D01*
X380067Y547833D01*
X379650Y548167D01*
X379067Y548333D01*
X378483Y548250D01*
X377983Y548000D01*
X377650Y547417D01*
X377483Y546917D01*
Y546417D01*
X377650Y545917D01*
X378067Y545417D01*
X378567Y545083D01*
X379150Y545000D01*
X379733Y545167D01*
X380317Y545667D01*
G01X388350D02*
X389017Y545250D01*
X389767Y545000D01*
X390433D01*
X391100Y545250D01*
X391600Y545667D01*
X391850Y546250D01*
X391683Y546833D01*
X391267Y547333D01*
X390517Y547667D01*
X389517Y547833D01*
X388933Y548167D01*
X388683Y548750D01*
X388850Y549333D01*
X389267Y549750D01*
X389850Y550000D01*
X390433D01*
X391017Y549833D01*
X391517Y549417D01*
G01X395700Y548333D02*
Y545000D01*
G01Y549667D02*
X395533Y549750D01*
Y549917D01*
X395700Y550000D01*
X395867Y549917D01*
Y549750D01*
X395700Y549667D01*
G01X400050Y548333D02*
X402550D01*
X400050Y545000D01*
X402550D01*
G01X405650Y547250D02*
X408317D01*
X408067Y547833D01*
X407650Y548167D01*
X407067Y548333D01*
X406483Y548250D01*
X405983Y548000D01*
X405650Y547417D01*
X405483Y546917D01*
Y546417D01*
X405650Y545917D01*
X406067Y545417D01*
X406567Y545083D01*
X407150Y545000D01*
X407733Y545167D01*
X408317Y545667D01*
G01X414167Y545000D02*
X410833Y546667D01*
X414167Y548333D01*
G01X418100Y545000D02*
Y550000D01*
X417100Y549000D01*
G01Y545000D02*
X419100D01*
G01X422283Y545583D02*
X422867Y545167D01*
X423533Y545000D01*
X424200Y545167D01*
X424783Y545667D01*
X425200Y546417D01*
X425367Y547167D01*
Y548083D01*
X425200Y548833D01*
X424783Y549500D01*
X424283Y549833D01*
X423700Y550000D01*
X423033Y549833D01*
X422533Y549500D01*
X422200Y549000D01*
X422033Y548333D01*
X422200Y547750D01*
X422617Y547167D01*
X423117Y546833D01*
X423700Y546750D01*
X424367Y546917D01*
X424867Y547333D01*
X425367Y548083D01*
G01X429133Y545000D02*
X429300Y546083D01*
X429550Y547000D01*
X429883Y547833D01*
X430300Y548750D01*
X430967Y550000D01*
X427633D01*
G01X432400Y545000D02*
Y548333D01*
G01Y547417D02*
X432650Y547833D01*
X433067Y548167D01*
X433650Y548333D01*
X434233Y548167D01*
X434650Y547833D01*
X434900Y547417D01*
Y545000D01*
G01Y547417D02*
X435150Y547833D01*
X435567Y548167D01*
X436150Y548333D01*
X436733Y548167D01*
X437150Y547833D01*
X437400Y547333D01*
Y545000D01*
G01X440500Y548333D02*
Y545000D01*
G01Y549667D02*
X440333Y549750D01*
Y549917D01*
X440500Y550000D01*
X440667Y549917D01*
Y549750D01*
X440500Y549667D01*
G01X446100Y545000D02*
Y550000D01*
G01X455217Y548333D02*
X456217Y545000D01*
X457300Y548333D01*
X458383Y545000D01*
X459383Y548333D01*
G01X462900D02*
Y545000D01*
G01Y549667D02*
X462733Y549750D01*
Y549917D01*
X462900Y550000D01*
X463067Y549917D01*
Y549750D01*
X462900Y549667D01*
G01X468500Y550000D02*
Y545000D01*
G01X467333Y548333D02*
X469667D01*
G01X472683Y545000D02*
Y550000D01*
G01Y547583D02*
X473100Y548000D01*
X473517Y548250D01*
X474183Y548333D01*
X474683Y548250D01*
X475267Y547917D01*
X475517Y547417D01*
Y545000D01*
G01X483883D02*
Y548333D01*
G01Y547500D02*
X484217Y547917D01*
X484717Y548250D01*
X485383Y548333D01*
X485967Y548250D01*
X486467Y547917D01*
X486717Y547333D01*
Y545000D01*
G01X490900D02*
X490400Y545083D01*
X489900Y545417D01*
X489567Y546000D01*
X489400Y546667D01*
X489567Y547333D01*
X489900Y547917D01*
X490400Y548250D01*
X490900Y548333D01*
X491400Y548250D01*
X491900Y547917D01*
X492233Y547333D01*
X492317Y546667D01*
X492233Y546000D01*
X491900Y545417D01*
X491400Y545083D01*
X490900Y545000D01*
G01X495083D02*
Y548333D01*
G01Y547500D02*
X495417Y547917D01*
X495917Y548250D01*
X496583Y548333D01*
X497167Y548250D01*
X497667Y547917D01*
X497917Y547333D01*
Y545000D01*
G01X501017Y546667D02*
X503183D01*
G01X505950Y545000D02*
Y550000D01*
G01X509450D02*
Y545000D01*
G01Y547500D02*
X505950D01*
G01X511217Y545000D02*
X513300Y550000D01*
X515383Y545000D01*
G01X514633Y546750D02*
X511967D01*
G01X517150Y545667D02*
X517817Y545250D01*
X518567Y545000D01*
X519233D01*
X519900Y545250D01*
X520400Y545667D01*
X520650Y546250D01*
X520483Y546833D01*
X520067Y547333D01*
X519317Y547667D01*
X518317Y547833D01*
X517733Y548167D01*
X517483Y548750D01*
X517650Y549333D01*
X518067Y549750D01*
X518650Y550000D01*
X519233D01*
X519817Y549833D01*
X520317Y549417D01*
G01X522833Y550000D02*
Y545000D01*
X526167D01*
G01X534200Y543333D02*
Y548333D01*
G01Y547583D02*
X534617Y548000D01*
X535033Y548250D01*
X535700Y548333D01*
X536283Y548250D01*
X536867Y547833D01*
X537117Y547250D01*
X537200Y546667D01*
X537117Y546083D01*
X536867Y545500D01*
X536367Y545167D01*
X535700Y545000D01*
X535117Y545083D01*
X534533Y545333D01*
X534200Y545667D01*
G01X540133Y545000D02*
Y548333D01*
G01Y547667D02*
X540550Y548000D01*
X540967Y548250D01*
X541550Y548333D01*
X541967Y548250D01*
X542467Y548000D01*
G01X546900Y545000D02*
X546400Y545083D01*
X545900Y545417D01*
X545567Y546000D01*
X545400Y546667D01*
X545567Y547333D01*
X545900Y547917D01*
X546400Y548250D01*
X546900Y548333D01*
X547400Y548250D01*
X547900Y547917D01*
X548233Y547333D01*
X548317Y546667D01*
X548233Y546000D01*
X547900Y545417D01*
X547400Y545083D01*
X546900Y545000D01*
G01X554000Y550000D02*
Y545000D01*
G01Y545750D02*
X553667Y545333D01*
X553167Y545083D01*
X552583Y545000D01*
X551917Y545167D01*
X551417Y545583D01*
X551083Y546083D01*
X551000Y546667D01*
X551083Y547250D01*
X551417Y547750D01*
X551917Y548167D01*
X552583Y548333D01*
X553167Y548250D01*
X553583Y548083D01*
X554000Y547750D01*
G01X556683Y548333D02*
Y546000D01*
X557017Y545417D01*
X557517Y545083D01*
X558100Y545000D01*
X558683Y545083D01*
X559183Y545417D01*
X559517Y546000D01*
G01Y545000D02*
Y548333D01*
G01X565033Y547917D02*
X564450Y548250D01*
X563950Y548333D01*
X563283Y548167D01*
X562783Y547833D01*
X562450Y547250D01*
X562367Y546667D01*
X562450Y546083D01*
X562783Y545583D01*
X563283Y545167D01*
X563950Y545000D01*
X564533Y545167D01*
X565033Y545500D01*
G01X569300Y550000D02*
Y545000D01*
G01X568133Y548333D02*
X570467D01*
G01X573650Y545583D02*
X574067Y545250D01*
X574650Y545000D01*
X575150D01*
X575650Y545167D01*
X575983Y545417D01*
X576150Y545750D01*
X576067Y546250D01*
X575733Y546500D01*
X574233Y547000D01*
X573900Y547583D01*
X574067Y548000D01*
X574400Y548250D01*
X574900Y548333D01*
X575400Y548250D01*
X575900Y548000D01*
G01X580917Y543333D02*
X581750Y544167D01*
X582167Y545000D01*
Y548333D01*
X581750Y549167D01*
X580917Y550000D01*
G01X270833Y575000D02*
Y580000D01*
X272833D01*
X273500Y579750D01*
X274000Y579167D01*
X274167Y578500D01*
X274000Y577833D01*
X273583Y577333D01*
X272833Y577083D01*
X270833D01*
G01X278100Y575000D02*
Y580000D01*
G01X282283Y578333D02*
Y576000D01*
X282617Y575417D01*
X283117Y575083D01*
X283700Y575000D01*
X284283Y575083D01*
X284783Y575417D01*
X285117Y576000D01*
G01Y575000D02*
Y578333D01*
G01X288133Y573750D02*
X288717Y573417D01*
X289383Y573333D01*
X289967Y573417D01*
X290467Y573833D01*
X290800Y574417D01*
Y578333D01*
G01Y577667D02*
X290467Y578000D01*
X289967Y578250D01*
X289383Y578333D01*
X288717Y578167D01*
X288300Y577833D01*
X287967Y577250D01*
X287800Y576667D01*
X287883Y576167D01*
X288217Y575583D01*
X288717Y575167D01*
X289383Y575000D01*
X289883Y575083D01*
X290467Y575417D01*
X290800Y575750D01*
G01X293733Y573750D02*
X294317Y573417D01*
X294983Y573333D01*
X295567Y573417D01*
X296067Y573833D01*
X296400Y574417D01*
Y578333D01*
G01Y577667D02*
X296067Y578000D01*
X295567Y578250D01*
X294983Y578333D01*
X294317Y578167D01*
X293900Y577833D01*
X293567Y577250D01*
X293400Y576667D01*
X293483Y576167D01*
X293817Y575583D01*
X294317Y575167D01*
X294983Y575000D01*
X295483Y575083D01*
X296067Y575417D01*
X296400Y575750D01*
G01X299250Y577250D02*
X301917D01*
X301667Y577833D01*
X301250Y578167D01*
X300667Y578333D01*
X300083Y578250D01*
X299583Y578000D01*
X299250Y577417D01*
X299083Y576917D01*
Y576417D01*
X299250Y575917D01*
X299667Y575417D01*
X300167Y575083D01*
X300750Y575000D01*
X301333Y575167D01*
X301917Y575667D01*
G01X307600Y580000D02*
Y575000D01*
G01Y575750D02*
X307267Y575333D01*
X306767Y575083D01*
X306183Y575000D01*
X305517Y575167D01*
X305017Y575583D01*
X304683Y576083D01*
X304600Y576667D01*
X304683Y577250D01*
X305017Y577750D01*
X305517Y578167D01*
X306183Y578333D01*
X306767Y578250D01*
X307183Y578083D01*
X307600Y577750D01*
G01X315217Y580000D02*
X317300Y575000D01*
X319383Y580000D01*
G01X322900Y578333D02*
Y575000D01*
G01Y579667D02*
X322733Y579750D01*
Y579917D01*
X322900Y580000D01*
X323067Y579917D01*
Y579750D01*
X322900Y579667D01*
G01X330000Y575000D02*
Y578333D01*
G01Y577750D02*
X329667Y578083D01*
X329167Y578250D01*
X328583Y578333D01*
X328000Y578167D01*
X327500Y577833D01*
X327167Y577333D01*
X327000Y576667D01*
X327167Y576000D01*
X327500Y575500D01*
X328000Y575167D01*
X328583Y575000D01*
X329167Y575083D01*
X329667Y575333D01*
X330000Y575667D01*
G01X333683Y573333D02*
X332850Y574167D01*
X332433Y575000D01*
Y578333D01*
X332850Y579167D01*
X333683Y580000D01*
G01X338283Y575000D02*
Y580000D01*
G01Y577583D02*
X338700Y578000D01*
X339117Y578250D01*
X339783Y578333D01*
X340283Y578250D01*
X340867Y577917D01*
X341117Y577417D01*
Y575000D01*
G01X345300D02*
X344800Y575083D01*
X344300Y575417D01*
X343967Y576000D01*
X343800Y576667D01*
X343967Y577333D01*
X344300Y577917D01*
X344800Y578250D01*
X345300Y578333D01*
X345800Y578250D01*
X346300Y577917D01*
X346633Y577333D01*
X346717Y576667D01*
X346633Y576000D01*
X346300Y575417D01*
X345800Y575083D01*
X345300Y575000D01*
G01X350900D02*
Y580000D01*
G01X355250Y577250D02*
X357917D01*
X357667Y577833D01*
X357250Y578167D01*
X356667Y578333D01*
X356083Y578250D01*
X355583Y578000D01*
X355250Y577417D01*
X355083Y576917D01*
Y576417D01*
X355250Y575917D01*
X355667Y575417D01*
X356167Y575083D01*
X356750Y575000D01*
X357333Y575167D01*
X357917Y575667D01*
G01X366450Y575583D02*
X366867Y575250D01*
X367450Y575000D01*
X367950D01*
X368450Y575167D01*
X368783Y575417D01*
X368950Y575750D01*
X368867Y576250D01*
X368533Y576500D01*
X367033Y577000D01*
X366700Y577583D01*
X366867Y578000D01*
X367200Y578250D01*
X367700Y578333D01*
X368200Y578250D01*
X368700Y578000D01*
G01X373300Y578333D02*
Y575000D01*
G01Y579667D02*
X373133Y579750D01*
Y579917D01*
X373300Y580000D01*
X373467Y579917D01*
Y579750D01*
X373300Y579667D01*
G01X377650Y578333D02*
X380150D01*
X377650Y575000D01*
X380150D01*
G01X383250Y577250D02*
X385917D01*
X385667Y577833D01*
X385250Y578167D01*
X384667Y578333D01*
X384083Y578250D01*
X383583Y578000D01*
X383250Y577417D01*
X383083Y576917D01*
Y576417D01*
X383250Y575917D01*
X383667Y575417D01*
X384167Y575083D01*
X384750Y575000D01*
X385333Y575167D01*
X385917Y575667D01*
G01X391767Y575000D02*
X388433Y576667D01*
X391767Y578333D01*
G01X395700Y575000D02*
Y580000D01*
X394700Y579000D01*
G01Y575000D02*
X396700D01*
G01X399717Y577083D02*
X400300Y577667D01*
X400800Y578000D01*
X401467Y578167D01*
X402050Y578000D01*
X402467Y577667D01*
X402800Y577167D01*
X402883Y576583D01*
X402800Y576083D01*
X402467Y575583D01*
X401967Y575167D01*
X401383Y575000D01*
X400717Y575167D01*
X400133Y575667D01*
X399800Y576417D01*
X399717Y577250D01*
X399883Y578333D01*
X400133Y578917D01*
X400550Y579500D01*
X401133Y579917D01*
X401717Y580000D01*
X402300Y579833D01*
X402717Y579417D01*
G01X410000Y575000D02*
Y578333D01*
G01Y577417D02*
X410250Y577833D01*
X410667Y578167D01*
X411250Y578333D01*
X411833Y578167D01*
X412250Y577833D01*
X412500Y577417D01*
Y575000D01*
G01Y577417D02*
X412750Y577833D01*
X413167Y578167D01*
X413750Y578333D01*
X414333Y578167D01*
X414750Y577833D01*
X415000Y577333D01*
Y575000D01*
G01X418100Y578333D02*
Y575000D01*
G01Y579667D02*
X417933Y579750D01*
Y579917D01*
X418100Y580000D01*
X418267Y579917D01*
Y579750D01*
X418100Y579667D01*
G01X423700Y575000D02*
Y580000D01*
G01X429717Y573333D02*
X430550Y574167D01*
X430967Y575000D01*
Y578333D01*
X430550Y579167D01*
X429717Y580000D01*
G01X270833Y560000D02*
Y565000D01*
X272833D01*
X273500Y564750D01*
X274000Y564167D01*
X274167Y563500D01*
X274000Y562833D01*
X273583Y562333D01*
X272833Y562083D01*
X270833D01*
G01X278100Y560000D02*
Y565000D01*
G01X282283Y563333D02*
Y561000D01*
X282617Y560417D01*
X283117Y560083D01*
X283700Y560000D01*
X284283Y560083D01*
X284783Y560417D01*
X285117Y561000D01*
G01Y560000D02*
Y563333D01*
G01X288133Y558750D02*
X288717Y558417D01*
X289383Y558333D01*
X289967Y558417D01*
X290467Y558833D01*
X290800Y559417D01*
Y563333D01*
G01Y562667D02*
X290467Y563000D01*
X289967Y563250D01*
X289383Y563333D01*
X288717Y563167D01*
X288300Y562833D01*
X287967Y562250D01*
X287800Y561667D01*
X287883Y561167D01*
X288217Y560583D01*
X288717Y560167D01*
X289383Y560000D01*
X289883Y560083D01*
X290467Y560417D01*
X290800Y560750D01*
G01X293733Y558750D02*
X294317Y558417D01*
X294983Y558333D01*
X295567Y558417D01*
X296067Y558833D01*
X296400Y559417D01*
Y563333D01*
G01Y562667D02*
X296067Y563000D01*
X295567Y563250D01*
X294983Y563333D01*
X294317Y563167D01*
X293900Y562833D01*
X293567Y562250D01*
X293400Y561667D01*
X293483Y561167D01*
X293817Y560583D01*
X294317Y560167D01*
X294983Y560000D01*
X295483Y560083D01*
X296067Y560417D01*
X296400Y560750D01*
G01X299250Y562250D02*
X301917D01*
X301667Y562833D01*
X301250Y563167D01*
X300667Y563333D01*
X300083Y563250D01*
X299583Y563000D01*
X299250Y562417D01*
X299083Y561917D01*
Y561417D01*
X299250Y560917D01*
X299667Y560417D01*
X300167Y560083D01*
X300750Y560000D01*
X301333Y560167D01*
X301917Y560667D01*
G01X307600Y565000D02*
Y560000D01*
G01Y560750D02*
X307267Y560333D01*
X306767Y560083D01*
X306183Y560000D01*
X305517Y560167D01*
X305017Y560583D01*
X304683Y561083D01*
X304600Y561667D01*
X304683Y562250D01*
X305017Y562750D01*
X305517Y563167D01*
X306183Y563333D01*
X306767Y563250D01*
X307183Y563083D01*
X307600Y562750D01*
G01X315633Y560000D02*
Y565000D01*
X317633D01*
X318300Y564750D01*
X318800Y564167D01*
X318967Y563500D01*
X318800Y562833D01*
X318383Y562333D01*
X317633Y562083D01*
X315633D01*
G01X322900Y565000D02*
Y560000D01*
G01X320983Y565000D02*
X324817D01*
G01X326750Y560000D02*
Y565000D01*
G01X330250D02*
Y560000D01*
G01Y562500D02*
X326750D01*
G01X333683Y558333D02*
X332850Y559167D01*
X332433Y560000D01*
Y563333D01*
X332850Y564167D01*
X333683Y565000D01*
G01X338283Y560000D02*
Y565000D01*
G01Y562583D02*
X338700Y563000D01*
X339117Y563250D01*
X339783Y563333D01*
X340283Y563250D01*
X340867Y562917D01*
X341117Y562417D01*
Y560000D01*
G01X345300D02*
X344800Y560083D01*
X344300Y560417D01*
X343967Y561000D01*
X343800Y561667D01*
X343967Y562333D01*
X344300Y562917D01*
X344800Y563250D01*
X345300Y563333D01*
X345800Y563250D01*
X346300Y562917D01*
X346633Y562333D01*
X346717Y561667D01*
X346633Y561000D01*
X346300Y560417D01*
X345800Y560083D01*
X345300Y560000D01*
G01X350900D02*
Y565000D01*
G01X355250Y562250D02*
X357917D01*
X357667Y562833D01*
X357250Y563167D01*
X356667Y563333D01*
X356083Y563250D01*
X355583Y563000D01*
X355250Y562417D01*
X355083Y561917D01*
Y561417D01*
X355250Y560917D01*
X355667Y560417D01*
X356167Y560083D01*
X356750Y560000D01*
X357333Y560167D01*
X357917Y560667D01*
G01X366450Y560583D02*
X366867Y560250D01*
X367450Y560000D01*
X367950D01*
X368450Y560167D01*
X368783Y560417D01*
X368950Y560750D01*
X368867Y561250D01*
X368533Y561500D01*
X367033Y562000D01*
X366700Y562583D01*
X366867Y563000D01*
X367200Y563250D01*
X367700Y563333D01*
X368200Y563250D01*
X368700Y563000D01*
G01X373300Y563333D02*
Y560000D01*
G01Y564667D02*
X373133Y564750D01*
Y564917D01*
X373300Y565000D01*
X373467Y564917D01*
Y564750D01*
X373300Y564667D01*
G01X377650Y563333D02*
X380150D01*
X377650Y560000D01*
X380150D01*
G01X383250Y562250D02*
X385917D01*
X385667Y562833D01*
X385250Y563167D01*
X384667Y563333D01*
X384083Y563250D01*
X383583Y563000D01*
X383250Y562417D01*
X383083Y561917D01*
Y561417D01*
X383250Y560917D01*
X383667Y560417D01*
X384167Y560083D01*
X384750Y560000D01*
X385333Y560167D01*
X385917Y560667D01*
G01X388433Y560000D02*
X391767Y561667D01*
X388433Y563333D01*
G01X394617Y560917D02*
X396783D01*
G01Y562417D02*
X394617D01*
G01X401300Y560000D02*
Y565000D01*
X400300Y564000D01*
G01Y560000D02*
X402300D01*
G01X405317Y562083D02*
X405900Y562667D01*
X406400Y563000D01*
X407067Y563167D01*
X407650Y563000D01*
X408067Y562667D01*
X408400Y562167D01*
X408483Y561583D01*
X408400Y561083D01*
X408067Y560583D01*
X407567Y560167D01*
X406983Y560000D01*
X406317Y560167D01*
X405733Y560667D01*
X405400Y561417D01*
X405317Y562250D01*
X405483Y563333D01*
X405733Y563917D01*
X406150Y564500D01*
X406733Y564917D01*
X407317Y565000D01*
X407900Y564833D01*
X408317Y564417D01*
G01X415600Y560000D02*
Y563333D01*
G01Y562417D02*
X415850Y562833D01*
X416267Y563167D01*
X416850Y563333D01*
X417433Y563167D01*
X417850Y562833D01*
X418100Y562417D01*
Y560000D01*
G01Y562417D02*
X418350Y562833D01*
X418767Y563167D01*
X419350Y563333D01*
X419933Y563167D01*
X420350Y562833D01*
X420600Y562333D01*
Y560000D01*
G01X423700Y563333D02*
Y560000D01*
G01Y564667D02*
X423533Y564750D01*
Y564917D01*
X423700Y565000D01*
X423867Y564917D01*
Y564750D01*
X423700Y564667D01*
G01X429300Y560000D02*
Y565000D01*
G01X435317Y558333D02*
X436150Y559167D01*
X436567Y560000D01*
Y563333D01*
X436150Y564167D01*
X435317Y565000D01*
G01X262500Y539000D02*
X694500D01*
G01X262500Y554000D02*
X694500D01*
G01X262500Y569000D02*
X694500D01*
G01X270917Y619000D02*
X273000Y624000D01*
X275083Y619000D01*
G01X274333Y620750D02*
X271667D01*
G01X277183Y619000D02*
Y622333D01*
G01Y621500D02*
X277517Y621917D01*
X278017Y622250D01*
X278683Y622333D01*
X279267Y622250D01*
X279767Y621917D01*
X280017Y621333D01*
Y619000D01*
G01X284200Y624000D02*
Y619000D01*
G01X283033Y622333D02*
X285367D01*
G01X289800D02*
Y619000D01*
G01Y623667D02*
X289633Y623750D01*
Y623917D01*
X289800Y624000D01*
X289967Y623917D01*
Y623750D01*
X289800Y623667D01*
G01X294317Y620667D02*
X296483D01*
G01X299500Y617333D02*
Y622333D01*
G01Y621583D02*
X299917Y622000D01*
X300333Y622250D01*
X301000Y622333D01*
X301583Y622250D01*
X302167Y621833D01*
X302417Y621250D01*
X302500Y620667D01*
X302417Y620083D01*
X302167Y619500D01*
X301667Y619167D01*
X301000Y619000D01*
X300417Y619083D01*
X299833Y619333D01*
X299500Y619667D01*
G01X308100Y619000D02*
Y622333D01*
G01Y621750D02*
X307767Y622083D01*
X307267Y622250D01*
X306683Y622333D01*
X306100Y622167D01*
X305600Y621833D01*
X305267Y621333D01*
X305100Y620667D01*
X305267Y620000D01*
X305600Y619500D01*
X306100Y619167D01*
X306683Y619000D01*
X307267Y619083D01*
X307767Y619333D01*
X308100Y619667D01*
G01X313700Y624000D02*
Y619000D01*
G01Y619750D02*
X313367Y619333D01*
X312867Y619083D01*
X312283Y619000D01*
X311617Y619167D01*
X311117Y619583D01*
X310783Y620083D01*
X310700Y620667D01*
X310783Y621250D01*
X311117Y621750D01*
X311617Y622167D01*
X312283Y622333D01*
X312867Y622250D01*
X313283Y622083D01*
X313700Y621750D01*
G01X322150Y619583D02*
X322567Y619250D01*
X323150Y619000D01*
X323650D01*
X324150Y619167D01*
X324483Y619417D01*
X324650Y619750D01*
X324567Y620250D01*
X324233Y620500D01*
X322733Y621000D01*
X322400Y621583D01*
X322567Y622000D01*
X322900Y622250D01*
X323400Y622333D01*
X323900Y622250D01*
X324400Y622000D01*
G01X329000Y622333D02*
Y619000D01*
G01Y623667D02*
X328833Y623750D01*
Y623917D01*
X329000Y624000D01*
X329167Y623917D01*
Y623750D01*
X329000Y623667D01*
G01X333350Y622333D02*
X335850D01*
X333350Y619000D01*
X335850D01*
G01X338950Y621250D02*
X341617D01*
X341367Y621833D01*
X340950Y622167D01*
X340367Y622333D01*
X339783Y622250D01*
X339283Y622000D01*
X338950Y621417D01*
X338783Y620917D01*
Y620417D01*
X338950Y619917D01*
X339367Y619417D01*
X339867Y619083D01*
X340450Y619000D01*
X341033Y619167D01*
X341617Y619667D01*
G01X269717Y637573D02*
X270717Y634240D01*
X271800Y637573D01*
X272883Y634240D01*
X273883Y637573D01*
G01X277400D02*
Y634240D01*
G01Y638907D02*
X277233Y638990D01*
Y639157D01*
X277400Y639240D01*
X277567Y639157D01*
Y638990D01*
X277400Y638907D01*
G01X283000Y639240D02*
Y634240D01*
G01X281833Y637573D02*
X284167D01*
G01X287183Y634240D02*
Y639240D01*
G01Y636823D02*
X287600Y637240D01*
X288017Y637490D01*
X288683Y637573D01*
X289183Y637490D01*
X289767Y637157D01*
X290017Y636657D01*
Y634240D01*
G01X294200D02*
X293700Y634323D01*
X293200Y634657D01*
X292867Y635240D01*
X292700Y635907D01*
X292867Y636573D01*
X293200Y637157D01*
X293700Y637490D01*
X294200Y637573D01*
X294700Y637490D01*
X295200Y637157D01*
X295533Y636573D01*
X295617Y635907D01*
X295533Y635240D01*
X295200Y634657D01*
X294700Y634323D01*
X294200Y634240D01*
G01X298383Y637573D02*
Y635240D01*
X298717Y634657D01*
X299217Y634323D01*
X299800Y634240D01*
X300383Y634323D01*
X300883Y634657D01*
X301217Y635240D01*
G01Y634240D02*
Y637573D01*
G01X305400Y639240D02*
Y634240D01*
G01X304233Y637573D02*
X306567D01*
G01X317933Y637157D02*
X317350Y637490D01*
X316850Y637573D01*
X316183Y637407D01*
X315683Y637073D01*
X315350Y636490D01*
X315267Y635907D01*
X315350Y635323D01*
X315683Y634823D01*
X316183Y634407D01*
X316850Y634240D01*
X317433Y634407D01*
X317933Y634740D01*
G01X322200Y634240D02*
X321700Y634323D01*
X321200Y634657D01*
X320867Y635240D01*
X320700Y635907D01*
X320867Y636573D01*
X321200Y637157D01*
X321700Y637490D01*
X322200Y637573D01*
X322700Y637490D01*
X323200Y637157D01*
X323533Y636573D01*
X323617Y635907D01*
X323533Y635240D01*
X323200Y634657D01*
X322700Y634323D01*
X322200Y634240D01*
G01X326383D02*
Y637573D01*
G01Y636740D02*
X326717Y637157D01*
X327217Y637490D01*
X327883Y637573D01*
X328467Y637490D01*
X328967Y637157D01*
X329217Y636573D01*
Y634240D01*
G01X331983D02*
Y637573D01*
G01Y636740D02*
X332317Y637157D01*
X332817Y637490D01*
X333483Y637573D01*
X334067Y637490D01*
X334567Y637157D01*
X334817Y636573D01*
Y634240D01*
G01X337750Y636490D02*
X340417D01*
X340167Y637073D01*
X339750Y637407D01*
X339167Y637573D01*
X338583Y637490D01*
X338083Y637240D01*
X337750Y636657D01*
X337583Y636157D01*
Y635657D01*
X337750Y635157D01*
X338167Y634657D01*
X338667Y634323D01*
X339250Y634240D01*
X339833Y634407D01*
X340417Y634907D01*
G01X345933Y637157D02*
X345350Y637490D01*
X344850Y637573D01*
X344183Y637407D01*
X343683Y637073D01*
X343350Y636490D01*
X343267Y635907D01*
X343350Y635323D01*
X343683Y634823D01*
X344183Y634407D01*
X344850Y634240D01*
X345433Y634407D01*
X345933Y634740D01*
G01X350200Y639240D02*
Y634240D01*
G01X349033Y637573D02*
X351367D01*
G01X355800D02*
Y634240D01*
G01Y638907D02*
X355633Y638990D01*
Y639157D01*
X355800Y639240D01*
X355967Y639157D01*
Y638990D01*
X355800Y638907D01*
G01X359983Y634240D02*
Y637573D01*
G01Y636740D02*
X360317Y637157D01*
X360817Y637490D01*
X361483Y637573D01*
X362067Y637490D01*
X362567Y637157D01*
X362817Y636573D01*
Y634240D01*
G01X365833Y632990D02*
X366417Y632657D01*
X367083Y632573D01*
X367667Y632657D01*
X368167Y633073D01*
X368500Y633657D01*
Y637573D01*
G01Y636907D02*
X368167Y637240D01*
X367667Y637490D01*
X367083Y637573D01*
X366417Y637407D01*
X366000Y637073D01*
X365667Y636490D01*
X365500Y635907D01*
X365583Y635407D01*
X365917Y634823D01*
X366417Y634407D01*
X367083Y634240D01*
X367583Y634323D01*
X368167Y634657D01*
X368500Y634990D01*
G01X378200Y639240D02*
Y634240D01*
G01X377033Y637573D02*
X379367D01*
G01X383800Y634240D02*
X383300Y634323D01*
X382800Y634657D01*
X382467Y635240D01*
X382300Y635907D01*
X382467Y636573D01*
X382800Y637157D01*
X383300Y637490D01*
X383800Y637573D01*
X384300Y637490D01*
X384800Y637157D01*
X385133Y636573D01*
X385217Y635907D01*
X385133Y635240D01*
X384800Y634657D01*
X384300Y634323D01*
X383800Y634240D01*
G01X395000D02*
X394500Y634323D01*
X394000Y634657D01*
X393667Y635240D01*
X393500Y635907D01*
X393667Y636573D01*
X394000Y637157D01*
X394500Y637490D01*
X395000Y637573D01*
X395500Y637490D01*
X396000Y637157D01*
X396333Y636573D01*
X396417Y635907D01*
X396333Y635240D01*
X396000Y634657D01*
X395500Y634323D01*
X395000Y634240D01*
G01X400600Y639240D02*
Y634240D01*
G01X399433Y637573D02*
X401767D01*
G01X404783Y634240D02*
Y639240D01*
G01Y636823D02*
X405200Y637240D01*
X405617Y637490D01*
X406283Y637573D01*
X406783Y637490D01*
X407367Y637157D01*
X407617Y636657D01*
Y634240D01*
G01X410550Y636490D02*
X413217D01*
X412967Y637073D01*
X412550Y637407D01*
X411967Y637573D01*
X411383Y637490D01*
X410883Y637240D01*
X410550Y636657D01*
X410383Y636157D01*
Y635657D01*
X410550Y635157D01*
X410967Y634657D01*
X411467Y634323D01*
X412050Y634240D01*
X412633Y634407D01*
X413217Y634907D01*
G01X416233Y634240D02*
Y637573D01*
G01Y636907D02*
X416650Y637240D01*
X417067Y637490D01*
X417650Y637573D01*
X418067Y637490D01*
X418567Y637240D01*
G01X428600Y634240D02*
Y639240D01*
G01X435700Y634240D02*
Y637573D01*
G01Y636990D02*
X435367Y637323D01*
X434867Y637490D01*
X434283Y637573D01*
X433700Y637407D01*
X433200Y637073D01*
X432867Y636573D01*
X432700Y635907D01*
X432867Y635240D01*
X433200Y634740D01*
X433700Y634407D01*
X434283Y634240D01*
X434867Y634323D01*
X435367Y634573D01*
X435700Y634907D01*
G01X438050Y632740D02*
X438550Y632573D01*
X439217Y632740D01*
X439633Y633073D01*
X439967Y633490D01*
X440467Y634823D01*
X441550Y637573D01*
G01X438883D02*
X440467Y634823D01*
G01X444150Y636490D02*
X446817D01*
X446567Y637073D01*
X446150Y637407D01*
X445567Y637573D01*
X444983Y637490D01*
X444483Y637240D01*
X444150Y636657D01*
X443983Y636157D01*
Y635657D01*
X444150Y635157D01*
X444567Y634657D01*
X445067Y634323D01*
X445650Y634240D01*
X446233Y634407D01*
X446817Y634907D01*
G01X449833Y634240D02*
Y637573D01*
G01Y636907D02*
X450250Y637240D01*
X450667Y637490D01*
X451250Y637573D01*
X451667Y637490D01*
X452167Y637240D01*
G01X455350Y634823D02*
X455767Y634490D01*
X456350Y634240D01*
X456850D01*
X457350Y634407D01*
X457683Y634657D01*
X457850Y634990D01*
X457767Y635490D01*
X457433Y635740D01*
X455933Y636240D01*
X455600Y636823D01*
X455767Y637240D01*
X456100Y637490D01*
X456600Y637573D01*
X457100Y637490D01*
X457600Y637240D01*
G01X462617Y632573D02*
X463450Y633407D01*
X463867Y634240D01*
Y637573D01*
X463450Y638407D01*
X462617Y639240D01*
G01X270257Y644950D02*
Y649950D01*
X271923D01*
X272590Y649700D01*
X273090Y649367D01*
X273507Y648867D01*
X273840Y648283D01*
X273923Y647450D01*
X273840Y646617D01*
X273507Y646033D01*
X273090Y645533D01*
X272590Y645200D01*
X271923Y644950D01*
X270257D01*
G01X276440Y647200D02*
X279107D01*
X278857Y647783D01*
X278440Y648117D01*
X277857Y648283D01*
X277273Y648200D01*
X276773Y647950D01*
X276440Y647367D01*
X276273Y646867D01*
Y646367D01*
X276440Y645867D01*
X276857Y645367D01*
X277357Y645033D01*
X277940Y644950D01*
X278523Y645117D01*
X279107Y645617D01*
G01X283290Y644950D02*
Y649950D01*
G01X287640Y647200D02*
X290307D01*
X290057Y647783D01*
X289640Y648117D01*
X289057Y648283D01*
X288473Y648200D01*
X287973Y647950D01*
X287640Y647367D01*
X287473Y646867D01*
Y646367D01*
X287640Y645867D01*
X288057Y645367D01*
X288557Y645033D01*
X289140Y644950D01*
X289723Y645117D01*
X290307Y645617D01*
G01X294490Y649950D02*
Y644950D01*
G01X293323Y648283D02*
X295657D01*
G01X298840Y647200D02*
X301507D01*
X301257Y647783D01*
X300840Y648117D01*
X300257Y648283D01*
X299673Y648200D01*
X299173Y647950D01*
X298840Y647367D01*
X298673Y646867D01*
Y646367D01*
X298840Y645867D01*
X299257Y645367D01*
X299757Y645033D01*
X300340Y644950D01*
X300923Y645117D01*
X301507Y645617D01*
G01X309873Y644950D02*
Y648283D01*
G01Y647450D02*
X310207Y647867D01*
X310707Y648200D01*
X311373Y648283D01*
X311957Y648200D01*
X312457Y647867D01*
X312707Y647283D01*
Y644950D01*
G01X316890D02*
X316390Y645033D01*
X315890Y645367D01*
X315557Y645950D01*
X315390Y646617D01*
X315557Y647283D01*
X315890Y647867D01*
X316390Y648200D01*
X316890Y648283D01*
X317390Y648200D01*
X317890Y647867D01*
X318223Y647283D01*
X318307Y646617D01*
X318223Y645950D01*
X317890Y645367D01*
X317390Y645033D01*
X316890Y644950D01*
G01X321073D02*
Y648283D01*
G01Y647450D02*
X321407Y647867D01*
X321907Y648200D01*
X322573Y648283D01*
X323157Y648200D01*
X323657Y647867D01*
X323907Y647283D01*
Y644950D01*
G01X327007Y646617D02*
X329173D01*
G01X333190Y644950D02*
Y649200D01*
X333357Y649617D01*
X333690Y649867D01*
X334190Y649950D01*
X334690Y649783D01*
X334940Y649367D01*
G01X333940Y647950D02*
X332273D01*
G01X337873Y648283D02*
Y645950D01*
X338207Y645367D01*
X338707Y645033D01*
X339290Y644950D01*
X339873Y645033D01*
X340373Y645367D01*
X340707Y645950D01*
G01Y644950D02*
Y648283D01*
G01X343473Y644950D02*
Y648283D01*
G01Y647450D02*
X343807Y647867D01*
X344307Y648200D01*
X344973Y648283D01*
X345557Y648200D01*
X346057Y647867D01*
X346307Y647283D01*
Y644950D01*
G01X351823Y647867D02*
X351240Y648200D01*
X350740Y648283D01*
X350073Y648117D01*
X349573Y647783D01*
X349240Y647200D01*
X349157Y646617D01*
X349240Y646033D01*
X349573Y645533D01*
X350073Y645117D01*
X350740Y644950D01*
X351323Y645117D01*
X351823Y645450D01*
G01X356090Y649950D02*
Y644950D01*
G01X354923Y648283D02*
X357257D01*
G01X361690D02*
Y644950D01*
G01Y649617D02*
X361523Y649700D01*
Y649867D01*
X361690Y649950D01*
X361857Y649867D01*
Y649700D01*
X361690Y649617D01*
G01X367290Y644950D02*
X366790Y645033D01*
X366290Y645367D01*
X365957Y645950D01*
X365790Y646617D01*
X365957Y647283D01*
X366290Y647867D01*
X366790Y648200D01*
X367290Y648283D01*
X367790Y648200D01*
X368290Y647867D01*
X368623Y647283D01*
X368707Y646617D01*
X368623Y645950D01*
X368290Y645367D01*
X367790Y645033D01*
X367290Y644950D01*
G01X371473D02*
Y648283D01*
G01Y647450D02*
X371807Y647867D01*
X372307Y648200D01*
X372973Y648283D01*
X373557Y648200D01*
X374057Y647867D01*
X374307Y647283D01*
Y644950D01*
G01X379990D02*
Y648283D01*
G01Y647700D02*
X379657Y648033D01*
X379157Y648200D01*
X378573Y648283D01*
X377990Y648117D01*
X377490Y647783D01*
X377157Y647283D01*
X376990Y646617D01*
X377157Y645950D01*
X377490Y645450D01*
X377990Y645117D01*
X378573Y644950D01*
X379157Y645033D01*
X379657Y645283D01*
X379990Y645617D01*
G01X384090Y644950D02*
Y649950D01*
G01X393790Y643283D02*
Y648283D01*
G01Y647533D02*
X394207Y647950D01*
X394623Y648200D01*
X395290Y648283D01*
X395873Y648200D01*
X396457Y647783D01*
X396707Y647200D01*
X396790Y646617D01*
X396707Y646033D01*
X396457Y645450D01*
X395957Y645117D01*
X395290Y644950D01*
X394707Y645033D01*
X394123Y645283D01*
X393790Y645617D01*
G01X402390Y644950D02*
Y648283D01*
G01Y647700D02*
X402057Y648033D01*
X401557Y648200D01*
X400973Y648283D01*
X400390Y648117D01*
X399890Y647783D01*
X399557Y647283D01*
X399390Y646617D01*
X399557Y645950D01*
X399890Y645450D01*
X400390Y645117D01*
X400973Y644950D01*
X401557Y645033D01*
X402057Y645283D01*
X402390Y645617D01*
G01X407990Y649950D02*
Y644950D01*
G01Y645700D02*
X407657Y645283D01*
X407157Y645033D01*
X406573Y644950D01*
X405907Y645117D01*
X405407Y645533D01*
X405073Y646033D01*
X404990Y646617D01*
X405073Y647200D01*
X405407Y647700D01*
X405907Y648117D01*
X406573Y648283D01*
X407157Y648200D01*
X407573Y648033D01*
X407990Y647700D01*
G01X417690Y648283D02*
Y644950D01*
G01Y649617D02*
X417523Y649700D01*
Y649867D01*
X417690Y649950D01*
X417857Y649867D01*
Y649700D01*
X417690Y649617D01*
G01X421873Y644950D02*
Y648283D01*
G01Y647450D02*
X422207Y647867D01*
X422707Y648200D01*
X423373Y648283D01*
X423957Y648200D01*
X424457Y647867D01*
X424707Y647283D01*
Y644950D01*
G01X435990D02*
Y648283D01*
G01Y647700D02*
X435657Y648033D01*
X435157Y648200D01*
X434573Y648283D01*
X433990Y648117D01*
X433490Y647783D01*
X433157Y647283D01*
X432990Y646617D01*
X433157Y645950D01*
X433490Y645450D01*
X433990Y645117D01*
X434573Y644950D01*
X435157Y645033D01*
X435657Y645283D01*
X435990Y645617D01*
G01X440090Y644950D02*
Y649950D01*
G01X445690Y644950D02*
Y649950D01*
G01X455390Y643283D02*
Y648283D01*
G01Y647533D02*
X455807Y647950D01*
X456223Y648200D01*
X456890Y648283D01*
X457473Y648200D01*
X458057Y647783D01*
X458307Y647200D01*
X458390Y646617D01*
X458307Y646033D01*
X458057Y645450D01*
X457557Y645117D01*
X456890Y644950D01*
X456307Y645033D01*
X455723Y645283D01*
X455390Y645617D01*
G01X461323Y644950D02*
Y648283D01*
G01Y647617D02*
X461740Y647950D01*
X462157Y648200D01*
X462740Y648283D01*
X463157Y648200D01*
X463657Y647950D01*
G01X468090Y644950D02*
X467590Y645033D01*
X467090Y645367D01*
X466757Y645950D01*
X466590Y646617D01*
X466757Y647283D01*
X467090Y647867D01*
X467590Y648200D01*
X468090Y648283D01*
X468590Y648200D01*
X469090Y647867D01*
X469423Y647283D01*
X469507Y646617D01*
X469423Y645950D01*
X469090Y645367D01*
X468590Y645033D01*
X468090Y644950D01*
G01X475190Y649950D02*
Y644950D01*
G01Y645700D02*
X474857Y645283D01*
X474357Y645033D01*
X473773Y644950D01*
X473107Y645117D01*
X472607Y645533D01*
X472273Y646033D01*
X472190Y646617D01*
X472273Y647200D01*
X472607Y647700D01*
X473107Y648117D01*
X473773Y648283D01*
X474357Y648200D01*
X474773Y648033D01*
X475190Y647700D01*
G01X477873Y648283D02*
Y645950D01*
X478207Y645367D01*
X478707Y645033D01*
X479290Y644950D01*
X479873Y645033D01*
X480373Y645367D01*
X480707Y645950D01*
G01Y644950D02*
Y648283D01*
G01X486223Y647867D02*
X485640Y648200D01*
X485140Y648283D01*
X484473Y648117D01*
X483973Y647783D01*
X483640Y647200D01*
X483557Y646617D01*
X483640Y646033D01*
X483973Y645533D01*
X484473Y645117D01*
X485140Y644950D01*
X485723Y645117D01*
X486223Y645450D01*
G01X490490Y649950D02*
Y644950D01*
G01X489323Y648283D02*
X491657D01*
G01X494840Y645533D02*
X495257Y645200D01*
X495840Y644950D01*
X496340D01*
X496840Y645117D01*
X497173Y645367D01*
X497340Y645700D01*
X497257Y646200D01*
X496923Y646450D01*
X495423Y646950D01*
X495090Y647533D01*
X495257Y647950D01*
X495590Y648200D01*
X496090Y648283D01*
X496590Y648200D01*
X497090Y647950D01*
G01X501690Y644783D02*
X501523Y644867D01*
Y645033D01*
X501690Y645117D01*
X501857Y645033D01*
Y644867D01*
X501690Y644783D01*
G01X506873Y643283D02*
X506040Y644117D01*
X505623Y644950D01*
Y648283D01*
X506040Y649117D01*
X506873Y649950D01*
G01X511890D02*
X513890D01*
G01X512890D02*
Y644950D01*
G01X511890D02*
X513890D01*
G01X517240Y645533D02*
X517657Y645200D01*
X518240Y644950D01*
X518740D01*
X519240Y645117D01*
X519573Y645367D01*
X519740Y645700D01*
X519657Y646200D01*
X519323Y646450D01*
X517823Y646950D01*
X517490Y647533D01*
X517657Y647950D01*
X517990Y648200D01*
X518490Y648283D01*
X518990Y648200D01*
X519490Y647950D01*
G01X524090Y644950D02*
X523590Y645033D01*
X523090Y645367D01*
X522757Y645950D01*
X522590Y646617D01*
X522757Y647283D01*
X523090Y647867D01*
X523590Y648200D01*
X524090Y648283D01*
X524590Y648200D01*
X525090Y647867D01*
X525423Y647283D01*
X525507Y646617D01*
X525423Y645950D01*
X525090Y645367D01*
X524590Y645033D01*
X524090Y644950D01*
G01X529690D02*
Y649950D01*
G01X536790Y644950D02*
Y648283D01*
G01Y647700D02*
X536457Y648033D01*
X535957Y648200D01*
X535373Y648283D01*
X534790Y648117D01*
X534290Y647783D01*
X533957Y647283D01*
X533790Y646617D01*
X533957Y645950D01*
X534290Y645450D01*
X534790Y645117D01*
X535373Y644950D01*
X535957Y645033D01*
X536457Y645283D01*
X536790Y645617D01*
G01X540890Y649950D02*
Y644950D01*
G01X539723Y648283D02*
X542057D01*
G01X545240Y647200D02*
X547907D01*
X547657Y647783D01*
X547240Y648117D01*
X546657Y648283D01*
X546073Y648200D01*
X545573Y647950D01*
X545240Y647367D01*
X545073Y646867D01*
Y646367D01*
X545240Y645867D01*
X545657Y645367D01*
X546157Y645033D01*
X546740Y644950D01*
X547323Y645117D01*
X547907Y645617D01*
G01X556190Y643283D02*
Y648283D01*
G01Y647533D02*
X556607Y647950D01*
X557023Y648200D01*
X557690Y648283D01*
X558273Y648200D01*
X558857Y647783D01*
X559107Y647200D01*
X559190Y646617D01*
X559107Y646033D01*
X558857Y645450D01*
X558357Y645117D01*
X557690Y644950D01*
X557107Y645033D01*
X556523Y645283D01*
X556190Y645617D01*
G01X564790Y644950D02*
Y648283D01*
G01Y647700D02*
X564457Y648033D01*
X563957Y648200D01*
X563373Y648283D01*
X562790Y648117D01*
X562290Y647783D01*
X561957Y647283D01*
X561790Y646617D01*
X561957Y645950D01*
X562290Y645450D01*
X562790Y645117D01*
X563373Y644950D01*
X563957Y645033D01*
X564457Y645283D01*
X564790Y645617D01*
G01X570390Y649950D02*
Y644950D01*
G01Y645700D02*
X570057Y645283D01*
X569557Y645033D01*
X568973Y644950D01*
X568307Y645117D01*
X567807Y645533D01*
X567473Y646033D01*
X567390Y646617D01*
X567473Y647200D01*
X567807Y647700D01*
X568307Y648117D01*
X568973Y648283D01*
X569557Y648200D01*
X569973Y648033D01*
X570390Y647700D01*
G01X322623Y303963D02*
X322890Y304163D01*
X323090Y304497D01*
X323223Y304963D01*
X323090Y305363D01*
X322823Y305630D01*
X322357Y305830D01*
X320557D01*
Y301830D01*
X322757D01*
X323223Y302097D01*
X323490Y302497D01*
X323623Y302963D01*
X323490Y303430D01*
X323090Y303830D01*
X322623Y303963D01*
X320557D01*
G01X320423Y351330D02*
X322090Y355330D01*
X323757Y351330D01*
G01X323157Y352730D02*
X321023D01*
G01X361117Y328537D02*
X360717Y328737D01*
X360250Y328870D01*
X359717D01*
X359117Y328670D01*
X358650Y328337D01*
X358317Y327937D01*
X358050Y327270D01*
X357983Y326670D01*
X358117Y326070D01*
X358317Y325670D01*
X358717Y325270D01*
X359183Y325003D01*
X359650Y324870D01*
X360117D01*
X360583Y325003D01*
X360983Y325203D01*
X361317Y325470D01*
G01X395000Y364500D02*
Y175500D01*
G01X402977Y229887D02*
X403310Y230137D01*
X403560Y230553D01*
X403727Y231137D01*
X403560Y231637D01*
X403227Y231970D01*
X402643Y232220D01*
X400393D01*
Y227220D01*
X403143D01*
X403727Y227553D01*
X404060Y228053D01*
X404227Y228637D01*
X404060Y229220D01*
X403560Y229720D01*
X402977Y229887D01*
X400393D01*
G01X406493Y230553D02*
Y228220D01*
X406827Y227637D01*
X407327Y227303D01*
X407910Y227220D01*
X408493Y227303D01*
X408993Y227637D01*
X409327Y228220D01*
G01Y227220D02*
Y230553D01*
G01X411010Y227220D02*
Y230553D01*
G01Y229637D02*
X411260Y230053D01*
X411677Y230387D01*
X412260Y230553D01*
X412843Y230387D01*
X413260Y230053D01*
X413510Y229637D01*
Y227220D01*
G01Y229637D02*
X413760Y230053D01*
X414177Y230387D01*
X414760Y230553D01*
X415343Y230387D01*
X415760Y230053D01*
X416010Y229553D01*
Y227220D01*
G01X417610Y225553D02*
Y230553D01*
G01Y229803D02*
X418027Y230220D01*
X418443Y230470D01*
X419110Y230553D01*
X419693Y230470D01*
X420277Y230053D01*
X420527Y229470D01*
X420610Y228887D01*
X420527Y228303D01*
X420277Y227720D01*
X419777Y227387D01*
X419110Y227220D01*
X418527Y227303D01*
X417943Y227553D01*
X417610Y227887D01*
G01X401520Y268213D02*
X403020Y264880D01*
X404520Y268213D01*
G01X408620D02*
Y264880D01*
G01Y269547D02*
X408453Y269630D01*
Y269797D01*
X408620Y269880D01*
X408787Y269797D01*
Y269630D01*
X408620Y269547D01*
G01X415720Y264880D02*
Y268213D01*
G01Y267630D02*
X415387Y267963D01*
X414887Y268130D01*
X414303Y268213D01*
X413720Y268047D01*
X413220Y267713D01*
X412887Y267213D01*
X412720Y266547D01*
X412887Y265880D01*
X413220Y265380D01*
X413720Y265047D01*
X414303Y264880D01*
X414887Y264963D01*
X415387Y265213D01*
X415720Y265547D01*
G01X401067Y277360D02*
Y282360D01*
X402733D01*
X403400Y282110D01*
X403900Y281777D01*
X404317Y281277D01*
X404650Y280693D01*
X404733Y279860D01*
X404650Y279027D01*
X404317Y278443D01*
X403900Y277943D01*
X403400Y277610D01*
X402733Y277360D01*
X401067D01*
G01X408500Y280693D02*
Y277360D01*
G01Y282027D02*
X408333Y282110D01*
Y282277D01*
X408500Y282360D01*
X408667Y282277D01*
Y282110D01*
X408500Y282027D01*
G01X411600Y277360D02*
Y280693D01*
G01Y279777D02*
X411850Y280193D01*
X412267Y280527D01*
X412850Y280693D01*
X413433Y280527D01*
X413850Y280193D01*
X414100Y279777D01*
Y277360D01*
G01Y279777D02*
X414350Y280193D01*
X414767Y280527D01*
X415350Y280693D01*
X415933Y280527D01*
X416350Y280193D01*
X416600Y279693D01*
Y277360D01*
G01X418200Y275693D02*
Y280693D01*
G01Y279943D02*
X418617Y280360D01*
X419033Y280610D01*
X419700Y280693D01*
X420283Y280610D01*
X420867Y280193D01*
X421117Y279610D01*
X421200Y279027D01*
X421117Y278443D01*
X420867Y277860D01*
X420367Y277527D01*
X419700Y277360D01*
X419117Y277443D01*
X418533Y277693D01*
X418200Y278027D01*
G01X425300Y277360D02*
Y282360D01*
G01X429650Y279610D02*
X432317D01*
X432067Y280193D01*
X431650Y280527D01*
X431067Y280693D01*
X430483Y280610D01*
X429983Y280360D01*
X429650Y279777D01*
X429483Y279277D01*
Y278777D01*
X429650Y278277D01*
X430067Y277777D01*
X430567Y277443D01*
X431150Y277360D01*
X431733Y277527D01*
X432317Y278027D01*
G01X441600Y277360D02*
Y281610D01*
X441767Y282027D01*
X442100Y282277D01*
X442600Y282360D01*
X443100Y282193D01*
X443350Y281777D01*
G01X442350Y280360D02*
X440683D01*
G01X447700Y277360D02*
X447200Y277443D01*
X446700Y277777D01*
X446367Y278360D01*
X446200Y279027D01*
X446367Y279693D01*
X446700Y280277D01*
X447200Y280610D01*
X447700Y280693D01*
X448200Y280610D01*
X448700Y280277D01*
X449033Y279693D01*
X449117Y279027D01*
X449033Y278360D01*
X448700Y277777D01*
X448200Y277443D01*
X447700Y277360D01*
G01X452133D02*
Y280693D01*
G01Y280027D02*
X452550Y280360D01*
X452967Y280610D01*
X453550Y280693D01*
X453967Y280610D01*
X454467Y280360D01*
G01X464500Y277360D02*
X464000Y277443D01*
X463500Y277777D01*
X463167Y278360D01*
X463000Y279027D01*
X463167Y279693D01*
X463500Y280277D01*
X464000Y280610D01*
X464500Y280693D01*
X465000Y280610D01*
X465500Y280277D01*
X465833Y279693D01*
X465917Y279027D01*
X465833Y278360D01*
X465500Y277777D01*
X465000Y277443D01*
X464500Y277360D01*
G01X468683Y280693D02*
Y278360D01*
X469017Y277777D01*
X469517Y277443D01*
X470100Y277360D01*
X470683Y277443D01*
X471183Y277777D01*
X471517Y278360D01*
G01Y277360D02*
Y280693D01*
G01X475700Y282360D02*
Y277360D01*
G01X474533Y280693D02*
X476867D01*
G01X480050Y279610D02*
X482717D01*
X482467Y280193D01*
X482050Y280527D01*
X481467Y280693D01*
X480883Y280610D01*
X480383Y280360D01*
X480050Y279777D01*
X479883Y279277D01*
Y278777D01*
X480050Y278277D01*
X480467Y277777D01*
X480967Y277443D01*
X481550Y277360D01*
X482133Y277527D01*
X482717Y278027D01*
G01X485733Y277360D02*
Y280693D01*
G01Y280027D02*
X486150Y280360D01*
X486567Y280610D01*
X487150Y280693D01*
X487567Y280610D01*
X488067Y280360D01*
G01X499600Y277360D02*
Y280693D01*
G01Y280110D02*
X499267Y280443D01*
X498767Y280610D01*
X498183Y280693D01*
X497600Y280527D01*
X497100Y280193D01*
X496767Y279693D01*
X496600Y279027D01*
X496767Y278360D01*
X497100Y277860D01*
X497600Y277527D01*
X498183Y277360D01*
X498767Y277443D01*
X499267Y277693D01*
X499600Y278027D01*
G01X502283Y277360D02*
Y280693D01*
G01Y279860D02*
X502617Y280277D01*
X503117Y280610D01*
X503783Y280693D01*
X504367Y280610D01*
X504867Y280277D01*
X505117Y279693D01*
Y277360D01*
G01X510800Y282360D02*
Y277360D01*
G01Y278110D02*
X510467Y277693D01*
X509967Y277443D01*
X509383Y277360D01*
X508717Y277527D01*
X508217Y277943D01*
X507883Y278443D01*
X507800Y279027D01*
X507883Y279610D01*
X508217Y280110D01*
X508717Y280527D01*
X509383Y280693D01*
X509967Y280610D01*
X510383Y280443D01*
X510800Y280110D01*
G01X520500Y280693D02*
Y277360D01*
G01Y282027D02*
X520333Y282110D01*
Y282277D01*
X520500Y282360D01*
X520667Y282277D01*
Y282110D01*
X520500Y282027D01*
G01X524683Y277360D02*
Y280693D01*
G01Y279860D02*
X525017Y280277D01*
X525517Y280610D01*
X526183Y280693D01*
X526767Y280610D01*
X527267Y280277D01*
X527517Y279693D01*
Y277360D01*
G01X530283D02*
Y280693D01*
G01Y279860D02*
X530617Y280277D01*
X531117Y280610D01*
X531783Y280693D01*
X532367Y280610D01*
X532867Y280277D01*
X533117Y279693D01*
Y277360D01*
G01X536050Y279610D02*
X538717D01*
X538467Y280193D01*
X538050Y280527D01*
X537467Y280693D01*
X536883Y280610D01*
X536383Y280360D01*
X536050Y279777D01*
X535883Y279277D01*
Y278777D01*
X536050Y278277D01*
X536467Y277777D01*
X536967Y277443D01*
X537550Y277360D01*
X538133Y277527D01*
X538717Y278027D01*
G01X541733Y277360D02*
Y280693D01*
G01Y280027D02*
X542150Y280360D01*
X542567Y280610D01*
X543150Y280693D01*
X543567Y280610D01*
X544067Y280360D01*
G01X554100Y277360D02*
Y282360D01*
G01X561200Y277360D02*
Y280693D01*
G01Y280110D02*
X560867Y280443D01*
X560367Y280610D01*
X559783Y280693D01*
X559200Y280527D01*
X558700Y280193D01*
X558367Y279693D01*
X558200Y279027D01*
X558367Y278360D01*
X558700Y277860D01*
X559200Y277527D01*
X559783Y277360D01*
X560367Y277443D01*
X560867Y277693D01*
X561200Y278027D01*
G01X564050Y277943D02*
X564467Y277610D01*
X565050Y277360D01*
X565550D01*
X566050Y277527D01*
X566383Y277777D01*
X566550Y278110D01*
X566467Y278610D01*
X566133Y278860D01*
X564633Y279360D01*
X564300Y279943D01*
X564467Y280360D01*
X564800Y280610D01*
X565300Y280693D01*
X565800Y280610D01*
X566300Y280360D01*
G01X569650Y279610D02*
X572317D01*
X572067Y280193D01*
X571650Y280527D01*
X571067Y280693D01*
X570483Y280610D01*
X569983Y280360D01*
X569650Y279777D01*
X569483Y279277D01*
Y278777D01*
X569650Y278277D01*
X570067Y277777D01*
X570567Y277443D01*
X571150Y277360D01*
X571733Y277527D01*
X572317Y278027D01*
G01X575333Y277360D02*
Y280693D01*
G01Y280027D02*
X575750Y280360D01*
X576167Y280610D01*
X576750Y280693D01*
X577167Y280610D01*
X577667Y280360D01*
G01X444197Y299927D02*
X443797Y300127D01*
X443330Y300260D01*
X442797D01*
X442197Y300060D01*
X441730Y299727D01*
X441397Y299327D01*
X441130Y298660D01*
X441063Y298060D01*
X441197Y297460D01*
X441397Y297060D01*
X441797Y296660D01*
X442263Y296393D01*
X442730Y296260D01*
X443197D01*
X443663Y296393D01*
X444063Y296593D01*
X444397Y296860D01*
G01X401827Y295540D02*
X403910Y300540D01*
X405993Y295540D01*
G01X405243Y297290D02*
X402577D01*
G01X408093Y295540D02*
Y298873D01*
G01Y298040D02*
X408427Y298457D01*
X408927Y298790D01*
X409593Y298873D01*
X410177Y298790D01*
X410677Y298457D01*
X410927Y297873D01*
Y295540D01*
G01X413943Y294290D02*
X414527Y293957D01*
X415193Y293873D01*
X415777Y293957D01*
X416277Y294373D01*
X416610Y294957D01*
Y298873D01*
G01Y298207D02*
X416277Y298540D01*
X415777Y298790D01*
X415193Y298873D01*
X414527Y298707D01*
X414110Y298373D01*
X413777Y297790D01*
X413610Y297207D01*
X413693Y296707D01*
X414027Y296123D01*
X414527Y295707D01*
X415193Y295540D01*
X415693Y295623D01*
X416277Y295957D01*
X416610Y296290D01*
G01X420710Y295540D02*
Y300540D01*
G01X425060Y297790D02*
X427727D01*
X427477Y298373D01*
X427060Y298707D01*
X426477Y298873D01*
X425893Y298790D01*
X425393Y298540D01*
X425060Y297957D01*
X424893Y297457D01*
Y296957D01*
X425060Y296457D01*
X425477Y295957D01*
X425977Y295623D01*
X426560Y295540D01*
X427143Y295707D01*
X427727Y296207D01*
G01X431493Y293873D02*
X430660Y294707D01*
X430243Y295540D01*
Y298873D01*
X430660Y299707D01*
X431493Y300540D01*
G01X449127Y293873D02*
X449960Y294707D01*
X450377Y295540D01*
Y298873D01*
X449960Y299707D01*
X449127Y300540D01*
G01X401777Y331927D02*
X402110Y332177D01*
X402360Y332593D01*
X402527Y333177D01*
X402360Y333677D01*
X402027Y334010D01*
X401443Y334260D01*
X399193D01*
Y329260D01*
X401943D01*
X402527Y329593D01*
X402860Y330093D01*
X403027Y330677D01*
X402860Y331260D01*
X402360Y331760D01*
X401777Y331927D01*
X399193D01*
G01X405210Y329093D02*
X408210Y334260D01*
G01X410227Y329260D02*
X412310Y334260D01*
X414393Y329260D01*
G01X413643Y331010D02*
X410977D01*
G01X400633Y358960D02*
Y353960D01*
X403967D01*
G01X409400D02*
Y357293D01*
G01Y356710D02*
X409067Y357043D01*
X408567Y357210D01*
X407983Y357293D01*
X407400Y357127D01*
X406900Y356793D01*
X406567Y356293D01*
X406400Y355627D01*
X406567Y354960D01*
X406900Y354460D01*
X407400Y354127D01*
X407983Y353960D01*
X408567Y354043D01*
X409067Y354293D01*
X409400Y354627D01*
G01X412250Y354543D02*
X412667Y354210D01*
X413250Y353960D01*
X413750D01*
X414250Y354127D01*
X414583Y354377D01*
X414750Y354710D01*
X414667Y355210D01*
X414333Y355460D01*
X412833Y355960D01*
X412500Y356543D01*
X412667Y356960D01*
X413000Y357210D01*
X413500Y357293D01*
X414000Y357210D01*
X414500Y356960D01*
G01X417850Y356210D02*
X420517D01*
X420267Y356793D01*
X419850Y357127D01*
X419267Y357293D01*
X418683Y357210D01*
X418183Y356960D01*
X417850Y356377D01*
X417683Y355877D01*
Y355377D01*
X417850Y354877D01*
X418267Y354377D01*
X418767Y354043D01*
X419350Y353960D01*
X419933Y354127D01*
X420517Y354627D01*
G01X423533Y353960D02*
Y357293D01*
G01Y356627D02*
X423950Y356960D01*
X424367Y357210D01*
X424950Y357293D01*
X425367Y357210D01*
X425867Y356960D01*
G01X434400Y357293D02*
X435900Y353960D01*
X437400Y357293D01*
G01X441500D02*
Y353960D01*
G01Y358627D02*
X441333Y358710D01*
Y358877D01*
X441500Y358960D01*
X441667Y358877D01*
Y358710D01*
X441500Y358627D01*
G01X448600Y353960D02*
Y357293D01*
G01Y356710D02*
X448267Y357043D01*
X447767Y357210D01*
X447183Y357293D01*
X446600Y357127D01*
X446100Y356793D01*
X445767Y356293D01*
X445600Y355627D01*
X445767Y354960D01*
X446100Y354460D01*
X446600Y354127D01*
X447183Y353960D01*
X447767Y354043D01*
X448267Y354293D01*
X448600Y354627D01*
G01X457050Y354543D02*
X457467Y354210D01*
X458050Y353960D01*
X458550D01*
X459050Y354127D01*
X459383Y354377D01*
X459550Y354710D01*
X459467Y355210D01*
X459133Y355460D01*
X457633Y355960D01*
X457300Y356543D01*
X457467Y356960D01*
X457800Y357210D01*
X458300Y357293D01*
X458800Y357210D01*
X459300Y356960D01*
G01X463900Y357293D02*
Y353960D01*
G01Y358627D02*
X463733Y358710D01*
Y358877D01*
X463900Y358960D01*
X464067Y358877D01*
Y358710D01*
X463900Y358627D01*
G01X468250Y357293D02*
X470750D01*
X468250Y353960D01*
X470750D01*
G01X473850Y356210D02*
X476517D01*
X476267Y356793D01*
X475850Y357127D01*
X475267Y357293D01*
X474683Y357210D01*
X474183Y356960D01*
X473850Y356377D01*
X473683Y355877D01*
Y355377D01*
X473850Y354877D01*
X474267Y354377D01*
X474767Y354043D01*
X475350Y353960D01*
X475933Y354127D01*
X476517Y354627D01*
G01X484217Y357293D02*
X485217Y353960D01*
X486300Y357293D01*
X487383Y353960D01*
X488383Y357293D01*
G01X491900D02*
Y353960D01*
G01Y358627D02*
X491733Y358710D01*
Y358877D01*
X491900Y358960D01*
X492067Y358877D01*
Y358710D01*
X491900Y358627D01*
G01X497500Y358960D02*
Y353960D01*
G01X496333Y357293D02*
X498667D01*
G01X501683Y353960D02*
Y358960D01*
G01Y356543D02*
X502100Y356960D01*
X502517Y357210D01*
X503183Y357293D01*
X503683Y357210D01*
X504267Y356877D01*
X504517Y356377D01*
Y353960D01*
G01X508700D02*
X508200Y354043D01*
X507700Y354377D01*
X507367Y354960D01*
X507200Y355627D01*
X507367Y356293D01*
X507700Y356877D01*
X508200Y357210D01*
X508700Y357293D01*
X509200Y357210D01*
X509700Y356877D01*
X510033Y356293D01*
X510117Y355627D01*
X510033Y354960D01*
X509700Y354377D01*
X509200Y354043D01*
X508700Y353960D01*
G01X512883Y357293D02*
Y354960D01*
X513217Y354377D01*
X513717Y354043D01*
X514300Y353960D01*
X514883Y354043D01*
X515383Y354377D01*
X515717Y354960D01*
G01Y353960D02*
Y357293D01*
G01X519900Y358960D02*
Y353960D01*
G01X518733Y357293D02*
X521067D01*
G01X529600Y352293D02*
Y357293D01*
G01Y356543D02*
X530017Y356960D01*
X530433Y357210D01*
X531100Y357293D01*
X531683Y357210D01*
X532267Y356793D01*
X532517Y356210D01*
X532600Y355627D01*
X532517Y355043D01*
X532267Y354460D01*
X531767Y354127D01*
X531100Y353960D01*
X530517Y354043D01*
X529933Y354293D01*
X529600Y354627D01*
G01X536700Y353960D02*
Y358960D01*
G01X543800Y353960D02*
Y357293D01*
G01Y356710D02*
X543467Y357043D01*
X542967Y357210D01*
X542383Y357293D01*
X541800Y357127D01*
X541300Y356793D01*
X540967Y356293D01*
X540800Y355627D01*
X540967Y354960D01*
X541300Y354460D01*
X541800Y354127D01*
X542383Y353960D01*
X542967Y354043D01*
X543467Y354293D01*
X543800Y354627D01*
G01X547900Y358960D02*
Y353960D01*
G01X546733Y357293D02*
X549067D01*
G01X553500D02*
Y353960D01*
G01Y358627D02*
X553333Y358710D01*
Y358877D01*
X553500Y358960D01*
X553667Y358877D01*
Y358710D01*
X553500Y358627D01*
G01X557683Y353960D02*
Y357293D01*
G01Y356460D02*
X558017Y356877D01*
X558517Y357210D01*
X559183Y357293D01*
X559767Y357210D01*
X560267Y356877D01*
X560517Y356293D01*
Y353960D01*
G01X563533Y352710D02*
X564117Y352377D01*
X564783Y352293D01*
X565367Y352377D01*
X565867Y352793D01*
X566200Y353377D01*
Y357293D01*
G01Y356627D02*
X565867Y356960D01*
X565367Y357210D01*
X564783Y357293D01*
X564117Y357127D01*
X563700Y356793D01*
X563367Y356210D01*
X563200Y355627D01*
X563283Y355127D01*
X563617Y354543D01*
X564117Y354127D01*
X564783Y353960D01*
X565283Y354043D01*
X565867Y354377D01*
X566200Y354710D01*
G01X575483Y352293D02*
X574650Y353127D01*
X574233Y353960D01*
Y357293D01*
X574650Y358127D01*
X575483Y358960D01*
G01X582167Y356627D02*
X582500Y356877D01*
X582750Y357293D01*
X582917Y357877D01*
X582750Y358377D01*
X582417Y358710D01*
X581833Y358960D01*
X579583D01*
Y353960D01*
X582333D01*
X582917Y354293D01*
X583250Y354793D01*
X583417Y355377D01*
X583250Y355960D01*
X582750Y356460D01*
X582167Y356627D01*
X579583D01*
G01X587517Y352293D02*
X588350Y353127D01*
X588767Y353960D01*
Y357293D01*
X588350Y358127D01*
X587517Y358960D01*
G01X395000Y305500D02*
X694500D01*
G01X395000Y337500D02*
X694500D01*
G01X404500Y666833D02*
Y663500D01*
G01Y668167D02*
X404333Y668250D01*
Y668417D01*
X404500Y668500D01*
X404667Y668417D01*
Y668250D01*
X404500Y668167D01*
G01X410100Y668500D02*
Y663500D01*
G01X408933Y666833D02*
X411267D01*
G01X414450Y665750D02*
X417117D01*
X416867Y666333D01*
X416450Y666667D01*
X415867Y666833D01*
X415283Y666750D01*
X414783Y666500D01*
X414450Y665917D01*
X414283Y665417D01*
Y664917D01*
X414450Y664417D01*
X414867Y663917D01*
X415367Y663583D01*
X415950Y663500D01*
X416533Y663667D01*
X417117Y664167D01*
G01X418800Y663500D02*
Y666833D01*
G01Y665917D02*
X419050Y666333D01*
X419467Y666667D01*
X420050Y666833D01*
X420633Y666667D01*
X421050Y666333D01*
X421300Y665917D01*
Y663500D01*
G01Y665917D02*
X421550Y666333D01*
X421967Y666667D01*
X422550Y666833D01*
X423133Y666667D01*
X423550Y666333D01*
X423800Y665833D01*
Y663500D01*
G01X605333Y-65000D02*
Y-60000D01*
X607500Y-64167D01*
X609667Y-60000D01*
Y-65000D01*
G01X611683Y-61667D02*
Y-64000D01*
X612017Y-64583D01*
X612517Y-64917D01*
X613100Y-65000D01*
X613683Y-64917D01*
X614183Y-64583D01*
X614517Y-64000D01*
G01Y-65000D02*
Y-61667D01*
G01X617450Y-64417D02*
X617867Y-64750D01*
X618450Y-65000D01*
X618950D01*
X619450Y-64833D01*
X619783Y-64583D01*
X619950Y-64250D01*
X619867Y-63750D01*
X619533Y-63500D01*
X618033Y-63000D01*
X617700Y-62417D01*
X617867Y-62000D01*
X618200Y-61750D01*
X618700Y-61667D01*
X619200Y-61750D01*
X619700Y-62000D01*
G01X624300Y-60000D02*
Y-65000D01*
G01X623133Y-61667D02*
X625467D01*
G01X635000Y-65000D02*
Y-60750D01*
X635167Y-60333D01*
X635500Y-60083D01*
X636000Y-60000D01*
X636500Y-60167D01*
X636750Y-60583D01*
G01X635750Y-62000D02*
X634083D01*
G01X641100Y-65000D02*
X640600Y-64917D01*
X640100Y-64583D01*
X639767Y-64000D01*
X639600Y-63333D01*
X639767Y-62667D01*
X640100Y-62083D01*
X640600Y-61750D01*
X641100Y-61667D01*
X641600Y-61750D01*
X642100Y-62083D01*
X642433Y-62667D01*
X642517Y-63333D01*
X642433Y-64000D01*
X642100Y-64583D01*
X641600Y-64917D01*
X641100Y-65000D01*
G01X646700D02*
Y-60000D01*
G01X652300Y-65000D02*
Y-60000D01*
G01X657900Y-65000D02*
X657400Y-64917D01*
X656900Y-64583D01*
X656567Y-64000D01*
X656400Y-63333D01*
X656567Y-62667D01*
X656900Y-62083D01*
X657400Y-61750D01*
X657900Y-61667D01*
X658400Y-61750D01*
X658900Y-62083D01*
X659233Y-62667D01*
X659317Y-63333D01*
X659233Y-64000D01*
X658900Y-64583D01*
X658400Y-64917D01*
X657900Y-65000D01*
G01X661417Y-61667D02*
X662417Y-65000D01*
X663500Y-61667D01*
X664583Y-65000D01*
X665583Y-61667D01*
G01X595500Y-69500D02*
Y438000D01*
G01X606583Y-1833D02*
X608583D01*
G01X607500Y-750D02*
Y-2917D01*
G01X611600Y-3667D02*
X614600Y1500D01*
G01X617617Y-1833D02*
X619783D01*
G01X624300Y-3500D02*
Y1500D01*
X623300Y500D01*
G01Y-3500D02*
X625300D01*
G01X627400D02*
Y-167D01*
G01Y-1083D02*
X627650Y-667D01*
X628067Y-333D01*
X628650Y-167D01*
X629233Y-333D01*
X629650Y-667D01*
X629900Y-1083D01*
Y-3500D01*
G01Y-1083D02*
X630150Y-667D01*
X630567Y-333D01*
X631150Y-167D01*
X631733Y-333D01*
X632150Y-667D01*
X632400Y-1167D01*
Y-3500D01*
G01X635500Y-167D02*
Y-3500D01*
G01Y1167D02*
X635333Y1250D01*
Y1417D01*
X635500Y1500D01*
X635667Y1417D01*
Y1250D01*
X635500Y1167D01*
G01X641100Y-3500D02*
Y1500D01*
G01X607500Y-15000D02*
X606833Y-15167D01*
X606333Y-15583D01*
X606000Y-16083D01*
X605750Y-16750D01*
X605667Y-17500D01*
X605750Y-18250D01*
X606000Y-18917D01*
X606333Y-19417D01*
X606833Y-19833D01*
X607500Y-20000D01*
X608167Y-19833D01*
X608667Y-19417D01*
X609000Y-18917D01*
X609250Y-18250D01*
X609333Y-17500D01*
X609250Y-16750D01*
X609000Y-16083D01*
X608667Y-15583D01*
X608167Y-15167D01*
X607500Y-15000D01*
G01X613100Y-20167D02*
X612933Y-20083D01*
Y-19917D01*
X613100Y-19833D01*
X613267Y-19917D01*
Y-20083D01*
X613100Y-20167D01*
G01X616867Y-19000D02*
X617367Y-19583D01*
X618033Y-19917D01*
X618783Y-20000D01*
X619450Y-19917D01*
X620117Y-19500D01*
X620533Y-19000D01*
X620617Y-18500D01*
X620450Y-17917D01*
X619867Y-17500D01*
X619283Y-17333D01*
X618533D01*
G01X619283D02*
X619783Y-17083D01*
X620200Y-16667D01*
X620367Y-16167D01*
X620200Y-15667D01*
X619783Y-15250D01*
X619033Y-15000D01*
X618283Y-15083D01*
X617533Y-15417D01*
G01X621800Y-18333D02*
X622633Y-16667D01*
X623467D01*
X625133Y-20000D01*
X625967D01*
X626800Y-18333D01*
G01X629900Y-15000D02*
X629233Y-15167D01*
X628733Y-15583D01*
X628400Y-16083D01*
X628150Y-16750D01*
X628067Y-17500D01*
X628150Y-18250D01*
X628400Y-18917D01*
X628733Y-19417D01*
X629233Y-19833D01*
X629900Y-20000D01*
X630567Y-19833D01*
X631067Y-19417D01*
X631400Y-18917D01*
X631650Y-18250D01*
X631733Y-17500D01*
X631650Y-16750D01*
X631400Y-16083D01*
X631067Y-15583D01*
X630567Y-15167D01*
X629900Y-15000D01*
G01X635500Y-20167D02*
X635333Y-20083D01*
Y-19917D01*
X635500Y-19833D01*
X635667Y-19917D01*
Y-20083D01*
X635500Y-20167D01*
G01X640933Y-20000D02*
X641100Y-18917D01*
X641350Y-18000D01*
X641683Y-17167D01*
X642100Y-16250D01*
X642767Y-15000D01*
X639433D01*
G01X644200Y-20000D02*
Y-16667D01*
G01Y-17583D02*
X644450Y-17167D01*
X644867Y-16833D01*
X645450Y-16667D01*
X646033Y-16833D01*
X646450Y-17167D01*
X646700Y-17583D01*
Y-20000D01*
G01Y-17583D02*
X646950Y-17167D01*
X647367Y-16833D01*
X647950Y-16667D01*
X648533Y-16833D01*
X648950Y-17167D01*
X649200Y-17667D01*
Y-20000D01*
G01X652300Y-16667D02*
Y-20000D01*
G01Y-15333D02*
X652133Y-15250D01*
Y-15083D01*
X652300Y-15000D01*
X652467Y-15083D01*
Y-15250D01*
X652300Y-15333D01*
G01X657900Y-20000D02*
Y-15000D01*
G01X607500Y-28500D02*
X606833Y-28667D01*
X606333Y-29083D01*
X606000Y-29583D01*
X605750Y-30250D01*
X605667Y-31000D01*
X605750Y-31750D01*
X606000Y-32417D01*
X606333Y-32917D01*
X606833Y-33333D01*
X607500Y-33500D01*
X608167Y-33333D01*
X608667Y-32917D01*
X609000Y-32417D01*
X609250Y-31750D01*
X609333Y-31000D01*
X609250Y-30250D01*
X609000Y-29583D01*
X608667Y-29083D01*
X608167Y-28667D01*
X607500Y-28500D01*
G01X613100Y-33667D02*
X612933Y-33583D01*
Y-33417D01*
X613100Y-33333D01*
X613267Y-33417D01*
Y-33583D01*
X613100Y-33667D01*
G01X616867Y-32500D02*
X617367Y-33083D01*
X618033Y-33417D01*
X618783Y-33500D01*
X619450Y-33417D01*
X620117Y-33000D01*
X620533Y-32500D01*
X620617Y-32000D01*
X620450Y-31417D01*
X619867Y-31000D01*
X619283Y-30833D01*
X618533D01*
G01X619283D02*
X619783Y-30583D01*
X620200Y-30167D01*
X620367Y-29667D01*
X620200Y-29167D01*
X619783Y-28750D01*
X619033Y-28500D01*
X618283Y-28583D01*
X617533Y-28917D01*
G01X621800Y-31833D02*
X622633Y-30167D01*
X623467D01*
X625133Y-33500D01*
X625967D01*
X626800Y-31833D01*
G01X629900Y-28500D02*
X629233Y-28667D01*
X628733Y-29083D01*
X628400Y-29583D01*
X628150Y-30250D01*
X628067Y-31000D01*
X628150Y-31750D01*
X628400Y-32417D01*
X628733Y-32917D01*
X629233Y-33333D01*
X629900Y-33500D01*
X630567Y-33333D01*
X631067Y-32917D01*
X631400Y-32417D01*
X631650Y-31750D01*
X631733Y-31000D01*
X631650Y-30250D01*
X631400Y-29583D01*
X631067Y-29083D01*
X630567Y-28667D01*
X629900Y-28500D01*
G01X635500Y-33667D02*
X635333Y-33583D01*
Y-33417D01*
X635500Y-33333D01*
X635667Y-33417D01*
Y-33583D01*
X635500Y-33667D01*
G01X640933Y-33500D02*
X641100Y-32417D01*
X641350Y-31500D01*
X641683Y-30667D01*
X642100Y-29750D01*
X642767Y-28500D01*
X639433D01*
G01X644200Y-33500D02*
Y-30167D01*
G01Y-31083D02*
X644450Y-30667D01*
X644867Y-30333D01*
X645450Y-30167D01*
X646033Y-30333D01*
X646450Y-30667D01*
X646700Y-31083D01*
Y-33500D01*
G01Y-31083D02*
X646950Y-30667D01*
X647367Y-30333D01*
X647950Y-30167D01*
X648533Y-30333D01*
X648950Y-30667D01*
X649200Y-31167D01*
Y-33500D01*
G01X652300Y-30167D02*
Y-33500D01*
G01Y-28833D02*
X652133Y-28750D01*
Y-28583D01*
X652300Y-28500D01*
X652467Y-28583D01*
Y-28750D01*
X652300Y-28833D01*
G01X657900Y-33500D02*
Y-28500D01*
G01X609167Y-48500D02*
X605833Y-46833D01*
X609167Y-45167D01*
G01X612017Y-47583D02*
X614183D01*
G01Y-46083D02*
X612017D01*
G01X618700Y-48500D02*
Y-43500D01*
X617700Y-44500D01*
G01Y-48500D02*
X619700D01*
G01X624300Y-48667D02*
X624133Y-48583D01*
Y-48417D01*
X624300Y-48333D01*
X624467Y-48417D01*
Y-48583D01*
X624300Y-48667D01*
G01X630900Y-48500D02*
Y-43500D01*
X627817Y-47083D01*
X631983D01*
G01X633000Y-48500D02*
Y-45167D01*
G01Y-46083D02*
X633250Y-45667D01*
X633667Y-45333D01*
X634250Y-45167D01*
X634833Y-45333D01*
X635250Y-45667D01*
X635500Y-46083D01*
Y-48500D01*
G01Y-46083D02*
X635750Y-45667D01*
X636167Y-45333D01*
X636750Y-45167D01*
X637333Y-45333D01*
X637750Y-45667D01*
X638000Y-46167D01*
Y-48500D01*
G01X641100Y-45167D02*
Y-48500D01*
G01Y-43833D02*
X640933Y-43750D01*
Y-43583D01*
X641100Y-43500D01*
X641267Y-43583D01*
Y-43750D01*
X641100Y-43833D01*
G01X646700Y-48500D02*
Y-43500D01*
G01X606583Y24667D02*
X608583D01*
G01X607500Y25750D02*
Y23583D01*
G01X611600Y22833D02*
X614600Y28000D01*
G01X617617Y24667D02*
X619783D01*
G01X624300Y23000D02*
Y28000D01*
X623300Y27000D01*
G01Y23000D02*
X625300D01*
G01X627400D02*
Y26333D01*
G01Y25417D02*
X627650Y25833D01*
X628067Y26167D01*
X628650Y26333D01*
X629233Y26167D01*
X629650Y25833D01*
X629900Y25417D01*
Y23000D01*
G01Y25417D02*
X630150Y25833D01*
X630567Y26167D01*
X631150Y26333D01*
X631733Y26167D01*
X632150Y25833D01*
X632400Y25333D01*
Y23000D01*
G01X635500Y26333D02*
Y23000D01*
G01Y27667D02*
X635333Y27750D01*
Y27917D01*
X635500Y28000D01*
X635667Y27917D01*
Y27750D01*
X635500Y27667D01*
G01X641100Y23000D02*
Y28000D01*
G01X606583Y13167D02*
X608583D01*
G01X607500Y14250D02*
Y12083D01*
G01X611600Y11333D02*
X614600Y16500D01*
G01X617617Y13167D02*
X619783D01*
G01X622717Y15667D02*
X623217Y16167D01*
X623800Y16417D01*
X624467Y16500D01*
X625300Y16333D01*
X625883Y15917D01*
X626050Y15417D01*
X625967Y14917D01*
X625633Y14500D01*
X623967Y13667D01*
X623217Y13083D01*
X622717Y12250D01*
X622550Y11500D01*
X626050D01*
G01X627400D02*
Y14833D01*
G01Y13917D02*
X627650Y14333D01*
X628067Y14667D01*
X628650Y14833D01*
X629233Y14667D01*
X629650Y14333D01*
X629900Y13917D01*
Y11500D01*
G01Y13917D02*
X630150Y14333D01*
X630567Y14667D01*
X631150Y14833D01*
X631733Y14667D01*
X632150Y14333D01*
X632400Y13833D01*
Y11500D01*
G01X635500Y14833D02*
Y11500D01*
G01Y16167D02*
X635333Y16250D01*
Y16417D01*
X635500Y16500D01*
X635667Y16417D01*
Y16250D01*
X635500Y16167D01*
G01X641100Y11500D02*
Y16500D01*
G01X606583Y98167D02*
X608583D01*
G01X607500Y99250D02*
Y97083D01*
G01X611600Y96333D02*
X614600Y101500D01*
G01X617617Y98167D02*
X619783D01*
G01X622717Y100667D02*
X623217Y101167D01*
X623800Y101417D01*
X624467Y101500D01*
X625300Y101333D01*
X625883Y100917D01*
X626050Y100417D01*
X625967Y99917D01*
X625633Y99500D01*
X623967Y98667D01*
X623217Y98083D01*
X622717Y97250D01*
X622550Y96500D01*
X626050D01*
G01X629900Y101500D02*
X629233Y101333D01*
X628733Y100917D01*
X628400Y100417D01*
X628150Y99750D01*
X628067Y99000D01*
X628150Y98250D01*
X628400Y97583D01*
X628733Y97083D01*
X629233Y96667D01*
X629900Y96500D01*
X630567Y96667D01*
X631067Y97083D01*
X631400Y97583D01*
X631650Y98250D01*
X631733Y99000D01*
X631650Y99750D01*
X631400Y100417D01*
X631067Y100917D01*
X630567Y101333D01*
X629900Y101500D01*
G01X634000Y96333D02*
X637000Y101500D01*
G01X634000D02*
X633500Y101333D01*
X633250Y101083D01*
X633083Y100583D01*
X633250Y100083D01*
X633500Y99833D01*
X634000Y99667D01*
X634500Y99833D01*
X634750Y100083D01*
X634917Y100583D01*
X634750Y101083D01*
X634500Y101333D01*
X634000Y101500D01*
G01X637000Y98167D02*
X636500Y98000D01*
X636250Y97750D01*
X636083Y97250D01*
X636250Y96750D01*
X636500Y96500D01*
X637000Y96333D01*
X637500Y96500D01*
X637750Y96750D01*
X637917Y97250D01*
X637750Y97750D01*
X637500Y98000D01*
X637000Y98167D01*
G01X606583Y68167D02*
X608583D01*
G01X607500Y69250D02*
Y67083D01*
G01X611600Y66333D02*
X614600Y71500D01*
G01X617617Y68167D02*
X619783D01*
G01X624300Y66500D02*
Y71500D01*
X623300Y70500D01*
G01Y66500D02*
X625300D01*
G01X628067Y67250D02*
X628567Y66833D01*
X629150Y66583D01*
X629900Y66500D01*
X630650Y66667D01*
X631233Y67000D01*
X631650Y67583D01*
X631733Y68250D01*
X631567Y68917D01*
X631150Y69333D01*
X630567Y69667D01*
X629983Y69750D01*
X629400Y69667D01*
X628650Y69333D01*
X628900Y71500D01*
X631150D01*
G01X634000Y66333D02*
X637000Y71500D01*
G01X634000D02*
X633500Y71333D01*
X633250Y71083D01*
X633083Y70583D01*
X633250Y70083D01*
X633500Y69833D01*
X634000Y69667D01*
X634500Y69833D01*
X634750Y70083D01*
X634917Y70583D01*
X634750Y71083D01*
X634500Y71333D01*
X634000Y71500D01*
G01X637000Y68167D02*
X636500Y68000D01*
X636250Y67750D01*
X636083Y67250D01*
X636250Y66750D01*
X636500Y66500D01*
X637000Y66333D01*
X637500Y66500D01*
X637750Y66750D01*
X637917Y67250D01*
X637750Y67750D01*
X637500Y68000D01*
X637000Y68167D01*
G01X606583Y113167D02*
X608583D01*
G01X607500Y114250D02*
Y112083D01*
G01X611600Y111333D02*
X614600Y116500D01*
G01X617617Y113167D02*
X619783D01*
G01X622467Y112500D02*
X622967Y111917D01*
X623633Y111583D01*
X624383Y111500D01*
X625050Y111583D01*
X625717Y112000D01*
X626133Y112500D01*
X626217Y113000D01*
X626050Y113583D01*
X625467Y114000D01*
X624883Y114167D01*
X624133D01*
G01X624883D02*
X625383Y114417D01*
X625800Y114833D01*
X625967Y115333D01*
X625800Y115833D01*
X625383Y116250D01*
X624633Y116500D01*
X623883Y116417D01*
X623133Y116083D01*
G01X627400Y111500D02*
Y114833D01*
G01Y113917D02*
X627650Y114333D01*
X628067Y114667D01*
X628650Y114833D01*
X629233Y114667D01*
X629650Y114333D01*
X629900Y113917D01*
Y111500D01*
G01Y113917D02*
X630150Y114333D01*
X630567Y114667D01*
X631150Y114833D01*
X631733Y114667D01*
X632150Y114333D01*
X632400Y113833D01*
Y111500D01*
G01X635500Y114833D02*
Y111500D01*
G01Y116167D02*
X635333Y116250D01*
Y116417D01*
X635500Y116500D01*
X635667Y116417D01*
Y116250D01*
X635500Y116167D01*
G01X641100Y111500D02*
Y116500D01*
G01X606583Y83167D02*
X608583D01*
G01X607500Y84250D02*
Y82083D01*
G01X611600Y81333D02*
X614600Y86500D01*
G01X617617Y83167D02*
X619783D01*
G01X624300Y81500D02*
Y86500D01*
X623300Y85500D01*
G01Y81500D02*
X625300D01*
G01X627400D02*
Y84833D01*
G01Y83917D02*
X627650Y84333D01*
X628067Y84667D01*
X628650Y84833D01*
X629233Y84667D01*
X629650Y84333D01*
X629900Y83917D01*
Y81500D01*
G01Y83917D02*
X630150Y84333D01*
X630567Y84667D01*
X631150Y84833D01*
X631733Y84667D01*
X632150Y84333D01*
X632400Y83833D01*
Y81500D01*
G01X635500Y84833D02*
Y81500D01*
G01Y86167D02*
X635333Y86250D01*
Y86417D01*
X635500Y86500D01*
X635667Y86417D01*
Y86250D01*
X635500Y86167D01*
G01X641100Y81500D02*
Y86500D01*
G01X606583Y48667D02*
X608583D01*
G01X607500Y49750D02*
Y47583D01*
G01X611600Y46833D02*
X614600Y52000D01*
G01X617617Y48667D02*
X619783D01*
G01X622717Y51167D02*
X623217Y51667D01*
X623800Y51917D01*
X624467Y52000D01*
X625300Y51833D01*
X625883Y51417D01*
X626050Y50917D01*
X625967Y50417D01*
X625633Y50000D01*
X623967Y49167D01*
X623217Y48583D01*
X622717Y47750D01*
X622550Y47000D01*
X626050D01*
G01X627400D02*
Y50333D01*
G01Y49417D02*
X627650Y49833D01*
X628067Y50167D01*
X628650Y50333D01*
X629233Y50167D01*
X629650Y49833D01*
X629900Y49417D01*
Y47000D01*
G01Y49417D02*
X630150Y49833D01*
X630567Y50167D01*
X631150Y50333D01*
X631733Y50167D01*
X632150Y49833D01*
X632400Y49333D01*
Y47000D01*
G01X635500Y50333D02*
Y47000D01*
G01Y51667D02*
X635333Y51750D01*
Y51917D01*
X635500Y52000D01*
X635667Y51917D01*
Y51750D01*
X635500Y51667D01*
G01X641100Y47000D02*
Y52000D01*
G01X605833Y166500D02*
X609167Y168167D01*
X605833Y169833D01*
G01X612017Y167417D02*
X614183D01*
G01Y168917D02*
X612017D01*
G01X618700Y166500D02*
Y171500D01*
X617700Y170500D01*
G01Y166500D02*
X619700D01*
G01X624300Y166333D02*
X624133Y166417D01*
Y166583D01*
X624300Y166667D01*
X624467Y166583D01*
Y166417D01*
X624300Y166333D01*
G01X628067Y167500D02*
X628567Y166917D01*
X629233Y166583D01*
X629983Y166500D01*
X630650Y166583D01*
X631317Y167000D01*
X631733Y167500D01*
X631817Y168000D01*
X631650Y168583D01*
X631067Y169000D01*
X630483Y169167D01*
X629733D01*
G01X630483D02*
X630983Y169417D01*
X631400Y169833D01*
X631567Y170333D01*
X631400Y170833D01*
X630983Y171250D01*
X630233Y171500D01*
X629483Y171417D01*
X628733Y171083D01*
G01X633000Y166500D02*
Y169833D01*
G01Y168917D02*
X633250Y169333D01*
X633667Y169667D01*
X634250Y169833D01*
X634833Y169667D01*
X635250Y169333D01*
X635500Y168917D01*
Y166500D01*
G01Y168917D02*
X635750Y169333D01*
X636167Y169667D01*
X636750Y169833D01*
X637333Y169667D01*
X637750Y169333D01*
X638000Y168833D01*
Y166500D01*
G01X641100Y169833D02*
Y166500D01*
G01Y171167D02*
X640933Y171250D01*
Y171417D01*
X641100Y171500D01*
X641267Y171417D01*
Y171250D01*
X641100Y171167D01*
G01X646700Y166500D02*
Y171500D01*
G01X605833Y144000D02*
X609167Y145667D01*
X605833Y147333D01*
G01X612017Y144917D02*
X614183D01*
G01Y146417D02*
X612017D01*
G01X618700Y144000D02*
Y149000D01*
X617700Y148000D01*
G01Y144000D02*
X619700D01*
G01X624300Y143833D02*
X624133Y143917D01*
Y144083D01*
X624300Y144167D01*
X624467Y144083D01*
Y143917D01*
X624300Y143833D01*
G01X628067Y144750D02*
X628567Y144333D01*
X629150Y144083D01*
X629900Y144000D01*
X630650Y144167D01*
X631233Y144500D01*
X631650Y145083D01*
X631733Y145750D01*
X631567Y146417D01*
X631150Y146833D01*
X630567Y147167D01*
X629983Y147250D01*
X629400Y147167D01*
X628650Y146833D01*
X628900Y149000D01*
X631150D01*
G01X633000Y144000D02*
Y147333D01*
G01Y146417D02*
X633250Y146833D01*
X633667Y147167D01*
X634250Y147333D01*
X634833Y147167D01*
X635250Y146833D01*
X635500Y146417D01*
Y144000D01*
G01Y146417D02*
X635750Y146833D01*
X636167Y147167D01*
X636750Y147333D01*
X637333Y147167D01*
X637750Y146833D01*
X638000Y146333D01*
Y144000D01*
G01X641100Y147333D02*
Y144000D01*
G01Y148667D02*
X640933Y148750D01*
Y148917D01*
X641100Y149000D01*
X641267Y148917D01*
Y148750D01*
X641100Y148667D01*
G01X646700Y144000D02*
Y149000D01*
G01X605833Y126500D02*
X609167Y128167D01*
X605833Y129833D01*
G01X612017Y127417D02*
X614183D01*
G01Y128917D02*
X612017D01*
G01X618700Y126500D02*
Y131500D01*
X617700Y130500D01*
G01Y126500D02*
X619700D01*
G01X624300Y126333D02*
X624133Y126417D01*
Y126583D01*
X624300Y126667D01*
X624467Y126583D01*
Y126417D01*
X624300Y126333D01*
G01X629900Y131500D02*
X629233Y131333D01*
X628733Y130917D01*
X628400Y130417D01*
X628150Y129750D01*
X628067Y129000D01*
X628150Y128250D01*
X628400Y127583D01*
X628733Y127083D01*
X629233Y126667D01*
X629900Y126500D01*
X630567Y126667D01*
X631067Y127083D01*
X631400Y127583D01*
X631650Y128250D01*
X631733Y129000D01*
X631650Y129750D01*
X631400Y130417D01*
X631067Y130917D01*
X630567Y131333D01*
X629900Y131500D01*
G01X633000Y126500D02*
Y129833D01*
G01Y128917D02*
X633250Y129333D01*
X633667Y129667D01*
X634250Y129833D01*
X634833Y129667D01*
X635250Y129333D01*
X635500Y128917D01*
Y126500D01*
G01Y128917D02*
X635750Y129333D01*
X636167Y129667D01*
X636750Y129833D01*
X637333Y129667D01*
X637750Y129333D01*
X638000Y128833D01*
Y126500D01*
G01X641100Y129833D02*
Y126500D01*
G01Y131167D02*
X640933Y131250D01*
Y131417D01*
X641100Y131500D01*
X641267Y131417D01*
Y131250D01*
X641100Y131167D01*
G01X646700Y126500D02*
Y131500D01*
G01X612977Y200490D02*
X609643Y202157D01*
X612977Y203823D01*
G01X616910Y205490D02*
X616243Y205323D01*
X615743Y204907D01*
X615410Y204407D01*
X615160Y203740D01*
X615077Y202990D01*
X615160Y202240D01*
X615410Y201573D01*
X615743Y201073D01*
X616243Y200657D01*
X616910Y200490D01*
X617577Y200657D01*
X618077Y201073D01*
X618410Y201573D01*
X618660Y202240D01*
X618743Y202990D01*
X618660Y203740D01*
X618410Y204407D01*
X618077Y204907D01*
X617577Y205323D01*
X616910Y205490D01*
G01X622510Y200323D02*
X622343Y200407D01*
Y200573D01*
X622510Y200657D01*
X622677Y200573D01*
Y200407D01*
X622510Y200323D01*
G01X626277Y201490D02*
X626777Y200907D01*
X627443Y200573D01*
X628193Y200490D01*
X628860Y200573D01*
X629527Y200990D01*
X629943Y201490D01*
X630027Y201990D01*
X629860Y202573D01*
X629277Y202990D01*
X628693Y203157D01*
X627943D01*
G01X628693D02*
X629193Y203407D01*
X629610Y203823D01*
X629777Y204323D01*
X629610Y204823D01*
X629193Y205240D01*
X628443Y205490D01*
X627693Y205407D01*
X626943Y205073D01*
G01X631210Y200490D02*
Y203823D01*
G01Y202907D02*
X631460Y203323D01*
X631877Y203657D01*
X632460Y203823D01*
X633043Y203657D01*
X633460Y203323D01*
X633710Y202907D01*
Y200490D01*
G01Y202907D02*
X633960Y203323D01*
X634377Y203657D01*
X634960Y203823D01*
X635543Y203657D01*
X635960Y203323D01*
X636210Y202823D01*
Y200490D01*
G01X639310Y203823D02*
Y200490D01*
G01Y205157D02*
X639143Y205240D01*
Y205407D01*
X639310Y205490D01*
X639477Y205407D01*
Y205240D01*
X639310Y205157D01*
G01X644910Y200490D02*
Y205490D01*
G01X612377Y255680D02*
X609043Y257347D01*
X612377Y259013D01*
G01X616310Y255680D02*
Y260680D01*
X615310Y259680D01*
G01Y255680D02*
X617310D01*
G01X619410D02*
Y259013D01*
G01Y258097D02*
X619660Y258513D01*
X620077Y258847D01*
X620660Y259013D01*
X621243Y258847D01*
X621660Y258513D01*
X621910Y258097D01*
Y255680D01*
G01Y258097D02*
X622160Y258513D01*
X622577Y258847D01*
X623160Y259013D01*
X623743Y258847D01*
X624160Y258513D01*
X624410Y258013D01*
Y255680D01*
G01X627510Y259013D02*
Y255680D01*
G01Y260347D02*
X627343Y260430D01*
Y260597D01*
X627510Y260680D01*
X627677Y260597D01*
Y260430D01*
X627510Y260347D01*
G01X633110Y255680D02*
Y260680D01*
G01X602120Y310470D02*
Y313803D01*
G01Y312887D02*
X602370Y313303D01*
X602787Y313637D01*
X603370Y313803D01*
X603953Y313637D01*
X604370Y313303D01*
X604620Y312887D01*
Y310470D01*
G01Y312887D02*
X604870Y313303D01*
X605287Y313637D01*
X605870Y313803D01*
X606453Y313637D01*
X606870Y313303D01*
X607120Y312803D01*
Y310470D01*
G01X608803Y313803D02*
Y311470D01*
X609137Y310887D01*
X609637Y310553D01*
X610220Y310470D01*
X610803Y310553D01*
X611303Y310887D01*
X611637Y311470D01*
G01Y310470D02*
Y313803D01*
G01X614570Y311053D02*
X614987Y310720D01*
X615570Y310470D01*
X616070D01*
X616570Y310637D01*
X616903Y310887D01*
X617070Y311220D01*
X616987Y311720D01*
X616653Y311970D01*
X615153Y312470D01*
X614820Y313053D01*
X614987Y313470D01*
X615320Y313720D01*
X615820Y313803D01*
X616320Y313720D01*
X616820Y313470D01*
G01X621420Y315470D02*
Y310470D01*
G01X620253Y313803D02*
X622587D01*
G01X628687Y310470D02*
X625353Y312137D01*
X628687Y313803D01*
G01X630537Y310470D02*
X632620Y315470D01*
X634703Y310470D01*
G01X633953Y312220D02*
X631287D01*
G01X645320Y315470D02*
Y310470D01*
G01Y311220D02*
X644987Y310803D01*
X644487Y310553D01*
X643903Y310470D01*
X643237Y310637D01*
X642737Y311053D01*
X642403Y311553D01*
X642320Y312137D01*
X642403Y312720D01*
X642737Y313220D01*
X643237Y313637D01*
X643903Y313803D01*
X644487Y313720D01*
X644903Y313553D01*
X645320Y313220D01*
G01X649420Y313803D02*
Y310470D01*
G01Y315137D02*
X649253Y315220D01*
Y315387D01*
X649420Y315470D01*
X649587Y315387D01*
Y315220D01*
X649420Y315137D01*
G01X656520Y310470D02*
Y313803D01*
G01Y313220D02*
X656187Y313553D01*
X655687Y313720D01*
X655103Y313803D01*
X654520Y313637D01*
X654020Y313303D01*
X653687Y312803D01*
X653520Y312137D01*
X653687Y311470D01*
X654020Y310970D01*
X654520Y310637D01*
X655103Y310470D01*
X655687Y310553D01*
X656187Y310803D01*
X656520Y311137D01*
G01X658120Y310470D02*
Y313803D01*
G01Y312887D02*
X658370Y313303D01*
X658787Y313637D01*
X659370Y313803D01*
X659953Y313637D01*
X660370Y313303D01*
X660620Y312887D01*
Y310470D01*
G01Y312887D02*
X660870Y313303D01*
X661287Y313637D01*
X661870Y313803D01*
X662453Y313637D01*
X662870Y313303D01*
X663120Y312803D01*
Y310470D01*
G01X664970Y312720D02*
X667637D01*
X667387Y313303D01*
X666970Y313637D01*
X666387Y313803D01*
X665803Y313720D01*
X665303Y313470D01*
X664970Y312887D01*
X664803Y312387D01*
Y311887D01*
X664970Y311387D01*
X665387Y310887D01*
X665887Y310553D01*
X666470Y310470D01*
X667053Y310637D01*
X667637Y311137D01*
G01X671820Y315470D02*
Y310470D01*
G01X670653Y313803D02*
X672987D01*
G01X676170Y312720D02*
X678837D01*
X678587Y313303D01*
X678170Y313637D01*
X677587Y313803D01*
X677003Y313720D01*
X676503Y313470D01*
X676170Y312887D01*
X676003Y312387D01*
Y311887D01*
X676170Y311387D01*
X676587Y310887D01*
X677087Y310553D01*
X677670Y310470D01*
X678253Y310637D01*
X678837Y311137D01*
G01X681853Y310470D02*
Y313803D01*
G01Y313137D02*
X682270Y313470D01*
X682687Y313720D01*
X683270Y313803D01*
X683687Y313720D01*
X684187Y313470D01*
G01X602700Y319240D02*
Y324240D01*
G01Y321740D02*
X603117Y322240D01*
X603617Y322490D01*
X604117Y322573D01*
X604867Y322407D01*
X605367Y322073D01*
X605700Y321490D01*
Y320823D01*
X605533Y320157D01*
X605200Y319657D01*
X604617Y319323D01*
X604117Y319240D01*
X603617Y319323D01*
X603117Y319573D01*
X602700Y319990D01*
G01X608383Y322573D02*
Y320240D01*
X608717Y319657D01*
X609217Y319323D01*
X609800Y319240D01*
X610383Y319323D01*
X610883Y319657D01*
X611217Y320240D01*
G01Y319240D02*
Y322573D01*
G01X615400Y324240D02*
Y319240D01*
G01X614233Y322573D02*
X616567D01*
G01X627267Y321907D02*
X627600Y322157D01*
X627850Y322573D01*
X628017Y323157D01*
X627850Y323657D01*
X627517Y323990D01*
X626933Y324240D01*
X624683D01*
Y319240D01*
X627433D01*
X628017Y319573D01*
X628350Y320073D01*
X628517Y320657D01*
X628350Y321240D01*
X627850Y321740D01*
X627267Y321907D01*
X624683D01*
G01X639300Y324240D02*
Y319240D01*
G01Y319990D02*
X638967Y319573D01*
X638467Y319323D01*
X637883Y319240D01*
X637217Y319407D01*
X636717Y319823D01*
X636383Y320323D01*
X636300Y320907D01*
X636383Y321490D01*
X636717Y321990D01*
X637217Y322407D01*
X637883Y322573D01*
X638467Y322490D01*
X638883Y322323D01*
X639300Y321990D01*
G01X643400Y322573D02*
Y319240D01*
G01Y323907D02*
X643233Y323990D01*
Y324157D01*
X643400Y324240D01*
X643567Y324157D01*
Y323990D01*
X643400Y323907D01*
G01X650500Y319240D02*
Y322573D01*
G01Y321990D02*
X650167Y322323D01*
X649667Y322490D01*
X649083Y322573D01*
X648500Y322407D01*
X648000Y322073D01*
X647667Y321573D01*
X647500Y320907D01*
X647667Y320240D01*
X648000Y319740D01*
X648500Y319407D01*
X649083Y319240D01*
X649667Y319323D01*
X650167Y319573D01*
X650500Y319907D01*
G01X652100Y319240D02*
Y322573D01*
G01Y321657D02*
X652350Y322073D01*
X652767Y322407D01*
X653350Y322573D01*
X653933Y322407D01*
X654350Y322073D01*
X654600Y321657D01*
Y319240D01*
G01Y321657D02*
X654850Y322073D01*
X655267Y322407D01*
X655850Y322573D01*
X656433Y322407D01*
X656850Y322073D01*
X657100Y321573D01*
Y319240D01*
G01X658950Y321490D02*
X661617D01*
X661367Y322073D01*
X660950Y322407D01*
X660367Y322573D01*
X659783Y322490D01*
X659283Y322240D01*
X658950Y321657D01*
X658783Y321157D01*
Y320657D01*
X658950Y320157D01*
X659367Y319657D01*
X659867Y319323D01*
X660450Y319240D01*
X661033Y319407D01*
X661617Y319907D01*
G01X665800Y324240D02*
Y319240D01*
G01X664633Y322573D02*
X666967D01*
G01X670150Y321490D02*
X672817D01*
X672567Y322073D01*
X672150Y322407D01*
X671567Y322573D01*
X670983Y322490D01*
X670483Y322240D01*
X670150Y321657D01*
X669983Y321157D01*
Y320657D01*
X670150Y320157D01*
X670567Y319657D01*
X671067Y319323D01*
X671650Y319240D01*
X672233Y319407D01*
X672817Y319907D01*
G01X675833Y319240D02*
Y322573D01*
G01Y321907D02*
X676250Y322240D01*
X676667Y322490D01*
X677250Y322573D01*
X677667Y322490D01*
X678167Y322240D01*
G01X608397Y295230D02*
X605063Y296897D01*
X608397Y298563D01*
G01X610913Y295813D02*
X611497Y295397D01*
X612163Y295230D01*
X612830Y295397D01*
X613413Y295897D01*
X613830Y296647D01*
X613997Y297397D01*
Y298313D01*
X613830Y299063D01*
X613413Y299730D01*
X612913Y300063D01*
X612330Y300230D01*
X611663Y300063D01*
X611163Y299730D01*
X610830Y299230D01*
X610663Y298563D01*
X610830Y297980D01*
X611247Y297397D01*
X611747Y297063D01*
X612330Y296980D01*
X612997Y297147D01*
X613497Y297563D01*
X613997Y298313D01*
G01X617930Y300230D02*
X617263Y300063D01*
X616763Y299647D01*
X616430Y299147D01*
X616180Y298480D01*
X616097Y297730D01*
X616180Y296980D01*
X616430Y296313D01*
X616763Y295813D01*
X617263Y295397D01*
X617930Y295230D01*
X618597Y295397D01*
X619097Y295813D01*
X619430Y296313D01*
X619680Y296980D01*
X619763Y297730D01*
X619680Y298480D01*
X619430Y299147D01*
X619097Y299647D01*
X618597Y300063D01*
X617930Y300230D01*
G01X630630D02*
Y295230D01*
G01Y295980D02*
X630297Y295563D01*
X629797Y295313D01*
X629213Y295230D01*
X628547Y295397D01*
X628047Y295813D01*
X627713Y296313D01*
X627630Y296897D01*
X627713Y297480D01*
X628047Y297980D01*
X628547Y298397D01*
X629213Y298563D01*
X629797Y298480D01*
X630213Y298313D01*
X630630Y297980D01*
G01X633480Y297480D02*
X636147D01*
X635897Y298063D01*
X635480Y298397D01*
X634897Y298563D01*
X634313Y298480D01*
X633813Y298230D01*
X633480Y297647D01*
X633313Y297147D01*
Y296647D01*
X633480Y296147D01*
X633897Y295647D01*
X634397Y295313D01*
X634980Y295230D01*
X635563Y295397D01*
X636147Y295897D01*
G01X639163Y293980D02*
X639747Y293647D01*
X640413Y293563D01*
X640997Y293647D01*
X641497Y294063D01*
X641830Y294647D01*
Y298563D01*
G01Y297897D02*
X641497Y298230D01*
X640997Y298480D01*
X640413Y298563D01*
X639747Y298397D01*
X639330Y298063D01*
X638997Y297480D01*
X638830Y296897D01*
X638913Y296397D01*
X639247Y295813D01*
X639747Y295397D01*
X640413Y295230D01*
X640913Y295313D01*
X641497Y295647D01*
X641830Y295980D01*
G01X644763Y295230D02*
Y298563D01*
G01Y297897D02*
X645180Y298230D01*
X645597Y298480D01*
X646180Y298563D01*
X646597Y298480D01*
X647097Y298230D01*
G01X650280Y297480D02*
X652947D01*
X652697Y298063D01*
X652280Y298397D01*
X651697Y298563D01*
X651113Y298480D01*
X650613Y298230D01*
X650280Y297647D01*
X650113Y297147D01*
Y296647D01*
X650280Y296147D01*
X650697Y295647D01*
X651197Y295313D01*
X651780Y295230D01*
X652363Y295397D01*
X652947Y295897D01*
G01X655880Y297480D02*
X658547D01*
X658297Y298063D01*
X657880Y298397D01*
X657297Y298563D01*
X656713Y298480D01*
X656213Y298230D01*
X655880Y297647D01*
X655713Y297147D01*
Y296647D01*
X655880Y296147D01*
X656297Y295647D01*
X656797Y295313D01*
X657380Y295230D01*
X657963Y295397D01*
X658547Y295897D01*
G01X603783Y329260D02*
X607117Y330927D01*
X603783Y332593D01*
G01X609967Y330177D02*
X612133D01*
G01Y331677D02*
X609967D01*
G01X616483Y329260D02*
X616650Y330343D01*
X616900Y331260D01*
X617233Y332093D01*
X617650Y333010D01*
X618317Y334260D01*
X614983D01*
G01X622250D02*
X621583Y334093D01*
X621083Y333677D01*
X620750Y333177D01*
X620500Y332510D01*
X620417Y331760D01*
X620500Y331010D01*
X620750Y330343D01*
X621083Y329843D01*
X621583Y329427D01*
X622250Y329260D01*
X622917Y329427D01*
X623417Y329843D01*
X623750Y330343D01*
X624000Y331010D01*
X624083Y331760D01*
X624000Y332510D01*
X623750Y333177D01*
X623417Y333677D01*
X622917Y334093D01*
X622250Y334260D01*
G01X626350Y329093D02*
X629350Y334260D01*
G01X626350D02*
X625850Y334093D01*
X625600Y333843D01*
X625433Y333343D01*
X625600Y332843D01*
X625850Y332593D01*
X626350Y332427D01*
X626850Y332593D01*
X627100Y332843D01*
X627267Y333343D01*
X627100Y333843D01*
X626850Y334093D01*
X626350Y334260D01*
G01X629350Y330927D02*
X628850Y330760D01*
X628600Y330510D01*
X628433Y330010D01*
X628600Y329510D01*
X628850Y329260D01*
X629350Y329093D01*
X629850Y329260D01*
X630100Y329510D01*
X630267Y330010D01*
X630100Y330510D01*
X629850Y330760D01*
X629350Y330927D01*
G01X633283Y328343D02*
X633617Y329427D01*
G01X605763Y349687D02*
X607763D01*
G01X606680Y350770D02*
Y348603D01*
G01X610780Y347853D02*
X613780Y353020D01*
G01X616797Y349687D02*
X618963D01*
G01X623480Y348020D02*
Y353020D01*
X622480Y352020D01*
G01Y348020D02*
X624480D01*
G01X626580D02*
Y351353D01*
G01Y350437D02*
X626830Y350853D01*
X627247Y351187D01*
X627830Y351353D01*
X628413Y351187D01*
X628830Y350853D01*
X629080Y350437D01*
Y348020D01*
G01Y350437D02*
X629330Y350853D01*
X629747Y351187D01*
X630330Y351353D01*
X630913Y351187D01*
X631330Y350853D01*
X631580Y350353D01*
Y348020D01*
G01X634680Y351353D02*
Y348020D01*
G01Y352687D02*
X634513Y352770D01*
Y352937D01*
X634680Y353020D01*
X634847Y352937D01*
Y352770D01*
X634680Y352687D01*
G01X640280Y348020D02*
Y353020D01*
G01X608333Y393000D02*
Y398000D01*
X610500Y393833D01*
X612667Y398000D01*
Y393000D01*
G01X614683Y396333D02*
Y394000D01*
X615017Y393417D01*
X615517Y393083D01*
X616100Y393000D01*
X616683Y393083D01*
X617183Y393417D01*
X617517Y394000D01*
G01Y393000D02*
Y396333D01*
G01X620450Y393583D02*
X620867Y393250D01*
X621450Y393000D01*
X621950D01*
X622450Y393167D01*
X622783Y393417D01*
X622950Y393750D01*
X622867Y394250D01*
X622533Y394500D01*
X621033Y395000D01*
X620700Y395583D01*
X620867Y396000D01*
X621200Y396250D01*
X621700Y396333D01*
X622200Y396250D01*
X622700Y396000D01*
G01X627300Y398000D02*
Y393000D01*
G01X626133Y396333D02*
X628467D01*
G01X638000Y393000D02*
Y397250D01*
X638167Y397667D01*
X638500Y397917D01*
X639000Y398000D01*
X639500Y397833D01*
X639750Y397417D01*
G01X638750Y396000D02*
X637083D01*
G01X644100Y393000D02*
X643600Y393083D01*
X643100Y393417D01*
X642767Y394000D01*
X642600Y394667D01*
X642767Y395333D01*
X643100Y395917D01*
X643600Y396250D01*
X644100Y396333D01*
X644600Y396250D01*
X645100Y395917D01*
X645433Y395333D01*
X645517Y394667D01*
X645433Y394000D01*
X645100Y393417D01*
X644600Y393083D01*
X644100Y393000D01*
G01X649700D02*
Y398000D01*
G01X655300Y393000D02*
Y398000D01*
G01X660900Y393000D02*
X660400Y393083D01*
X659900Y393417D01*
X659567Y394000D01*
X659400Y394667D01*
X659567Y395333D01*
X659900Y395917D01*
X660400Y396250D01*
X660900Y396333D01*
X661400Y396250D01*
X661900Y395917D01*
X662233Y395333D01*
X662317Y394667D01*
X662233Y394000D01*
X661900Y393417D01*
X661400Y393083D01*
X660900Y393000D01*
G01X664417Y396333D02*
X665417Y393000D01*
X666500Y396333D01*
X667583Y393000D01*
X668583Y396333D01*
G01X605810Y429990D02*
Y434240D01*
X605977Y434657D01*
X606310Y434907D01*
X606810Y434990D01*
X607310Y434823D01*
X607560Y434407D01*
G01X606560Y432990D02*
X604893D01*
G01X611910Y429990D02*
X611410Y430073D01*
X610910Y430407D01*
X610577Y430990D01*
X610410Y431657D01*
X610577Y432323D01*
X610910Y432907D01*
X611410Y433240D01*
X611910Y433323D01*
X612410Y433240D01*
X612910Y432907D01*
X613243Y432323D01*
X613327Y431657D01*
X613243Y430990D01*
X612910Y430407D01*
X612410Y430073D01*
X611910Y429990D01*
G01X617510D02*
Y434990D01*
G01X623110Y429990D02*
Y434990D01*
G01X628710Y429990D02*
X628210Y430073D01*
X627710Y430407D01*
X627377Y430990D01*
X627210Y431657D01*
X627377Y432323D01*
X627710Y432907D01*
X628210Y433240D01*
X628710Y433323D01*
X629210Y433240D01*
X629710Y432907D01*
X630043Y432323D01*
X630127Y431657D01*
X630043Y430990D01*
X629710Y430407D01*
X629210Y430073D01*
X628710Y429990D01*
G01X632227Y433323D02*
X633227Y429990D01*
X634310Y433323D01*
X635393Y429990D01*
X636393Y433323D01*
G01X647010Y434990D02*
Y429990D01*
G01Y430740D02*
X646677Y430323D01*
X646177Y430073D01*
X645593Y429990D01*
X644927Y430157D01*
X644427Y430573D01*
X644093Y431073D01*
X644010Y431657D01*
X644093Y432240D01*
X644427Y432740D01*
X644927Y433157D01*
X645593Y433323D01*
X646177Y433240D01*
X646593Y433073D01*
X647010Y432740D01*
G01X649943Y429990D02*
Y433323D01*
G01Y432657D02*
X650360Y432990D01*
X650777Y433240D01*
X651360Y433323D01*
X651777Y433240D01*
X652277Y432990D01*
G01X658210Y429990D02*
Y433323D01*
G01Y432740D02*
X657877Y433073D01*
X657377Y433240D01*
X656793Y433323D01*
X656210Y433157D01*
X655710Y432823D01*
X655377Y432323D01*
X655210Y431657D01*
X655377Y430990D01*
X655710Y430490D01*
X656210Y430157D01*
X656793Y429990D01*
X657377Y430073D01*
X657877Y430323D01*
X658210Y430657D01*
G01X660227Y433323D02*
X661227Y429990D01*
X662310Y433323D01*
X663393Y429990D01*
X664393Y433323D01*
G01X667910D02*
Y429990D01*
G01Y434657D02*
X667743Y434740D01*
Y434907D01*
X667910Y434990D01*
X668077Y434907D01*
Y434740D01*
X667910Y434657D01*
G01X672093Y429990D02*
Y433323D01*
G01Y432490D02*
X672427Y432907D01*
X672927Y433240D01*
X673593Y433323D01*
X674177Y433240D01*
X674677Y432907D01*
X674927Y432323D01*
Y429990D01*
G01X677943Y428740D02*
X678527Y428407D01*
X679193Y428323D01*
X679777Y428407D01*
X680277Y428823D01*
X680610Y429407D01*
Y433323D01*
G01Y432657D02*
X680277Y432990D01*
X679777Y433240D01*
X679193Y433323D01*
X678527Y433157D01*
X678110Y432823D01*
X677777Y432240D01*
X677610Y431657D01*
X677693Y431157D01*
X678027Y430573D01*
X678527Y430157D01*
X679193Y429990D01*
X679693Y430073D01*
X680277Y430407D01*
X680610Y430740D01*
G01X685127Y428323D02*
X685960Y429157D01*
X686377Y429990D01*
Y433323D01*
X685960Y434157D01*
X685127Y434990D01*
G01X606903Y440587D02*
X608903D01*
G01X607820Y441670D02*
Y439503D01*
G01X611920Y438753D02*
X614920Y443920D01*
G01X617937Y440587D02*
X620103D01*
G01X622787Y439670D02*
X623287Y439253D01*
X623870Y439003D01*
X624620Y438920D01*
X625370Y439087D01*
X625953Y439420D01*
X626370Y440003D01*
X626453Y440670D01*
X626287Y441337D01*
X625870Y441753D01*
X625287Y442087D01*
X624703Y442170D01*
X624120Y442087D01*
X623370Y441753D01*
X623620Y443920D01*
X625870D01*
G01X627720Y438920D02*
Y442253D01*
G01Y441337D02*
X627970Y441753D01*
X628387Y442087D01*
X628970Y442253D01*
X629553Y442087D01*
X629970Y441753D01*
X630220Y441337D01*
Y438920D01*
G01Y441337D02*
X630470Y441753D01*
X630887Y442087D01*
X631470Y442253D01*
X632053Y442087D01*
X632470Y441753D01*
X632720Y441253D01*
Y438920D01*
G01X635820Y442253D02*
Y438920D01*
G01Y443587D02*
X635653Y443670D01*
Y443837D01*
X635820Y443920D01*
X635987Y443837D01*
Y443670D01*
X635820Y443587D01*
G01X641420Y438920D02*
Y443920D01*
G01X595500Y679000D02*
Y396000D01*
G01X607500Y452000D02*
Y457000D01*
X606500Y456000D01*
G01Y452000D02*
X608500D01*
G01X613100Y451833D02*
X612933Y451917D01*
Y452083D01*
X613100Y452167D01*
X613267Y452083D01*
Y451917D01*
X613100Y451833D01*
G01X618700Y457000D02*
X618033Y456833D01*
X617533Y456417D01*
X617200Y455917D01*
X616950Y455250D01*
X616867Y454500D01*
X616950Y453750D01*
X617200Y453083D01*
X617533Y452583D01*
X618033Y452167D01*
X618700Y452000D01*
X619367Y452167D01*
X619867Y452583D01*
X620200Y453083D01*
X620450Y453750D01*
X620533Y454500D01*
X620450Y455250D01*
X620200Y455917D01*
X619867Y456417D01*
X619367Y456833D01*
X618700Y457000D01*
G01X621800Y452000D02*
Y455333D01*
G01Y454417D02*
X622050Y454833D01*
X622467Y455167D01*
X623050Y455333D01*
X623633Y455167D01*
X624050Y454833D01*
X624300Y454417D01*
Y452000D01*
G01Y454417D02*
X624550Y454833D01*
X624967Y455167D01*
X625550Y455333D01*
X626133Y455167D01*
X626550Y454833D01*
X626800Y454333D01*
Y452000D01*
G01X629900Y455333D02*
Y452000D01*
G01Y456667D02*
X629733Y456750D01*
Y456917D01*
X629900Y457000D01*
X630067Y456917D01*
Y456750D01*
X629900Y456667D01*
G01X635500Y452000D02*
Y457000D01*
G01X644200Y452000D02*
Y455333D01*
G01Y454417D02*
X644450Y454833D01*
X644867Y455167D01*
X645450Y455333D01*
X646033Y455167D01*
X646450Y454833D01*
X646700Y454417D01*
Y452000D01*
G01Y454417D02*
X646950Y454833D01*
X647367Y455167D01*
X647950Y455333D01*
X648533Y455167D01*
X648950Y454833D01*
X649200Y454333D01*
Y452000D01*
G01X653800D02*
Y455333D01*
G01Y454750D02*
X653467Y455083D01*
X652967Y455250D01*
X652383Y455333D01*
X651800Y455167D01*
X651300Y454833D01*
X650967Y454333D01*
X650800Y453667D01*
X650967Y453000D01*
X651300Y452500D01*
X651800Y452167D01*
X652383Y452000D01*
X652967Y452083D01*
X653467Y452333D01*
X653800Y452667D01*
G01X656650Y455333D02*
X659150Y452000D01*
G01Y455333D02*
X656650Y452000D01*
G01X606583Y471667D02*
X608583D01*
G01X607500Y472750D02*
Y470583D01*
G01X611600Y469833D02*
X614600Y475000D01*
G01X617617Y471667D02*
X619783D01*
G01X622467Y470750D02*
X622967Y470333D01*
X623550Y470083D01*
X624300Y470000D01*
X625050Y470167D01*
X625633Y470500D01*
X626050Y471083D01*
X626133Y471750D01*
X625967Y472417D01*
X625550Y472833D01*
X624967Y473167D01*
X624383Y473250D01*
X623800Y473167D01*
X623050Y472833D01*
X623300Y475000D01*
X625550D01*
G01X627400Y470000D02*
Y473333D01*
G01Y472417D02*
X627650Y472833D01*
X628067Y473167D01*
X628650Y473333D01*
X629233Y473167D01*
X629650Y472833D01*
X629900Y472417D01*
Y470000D01*
G01Y472417D02*
X630150Y472833D01*
X630567Y473167D01*
X631150Y473333D01*
X631733Y473167D01*
X632150Y472833D01*
X632400Y472333D01*
Y470000D01*
G01X635500Y473333D02*
Y470000D01*
G01Y474667D02*
X635333Y474750D01*
Y474917D01*
X635500Y475000D01*
X635667Y474917D01*
Y474750D01*
X635500Y474667D01*
G01X641100Y470000D02*
Y475000D01*
G01X606583Y486667D02*
X608583D01*
G01X607500Y487750D02*
Y485583D01*
G01X611600Y484833D02*
X614600Y490000D01*
G01X617617Y486667D02*
X619783D01*
G01X622467Y485750D02*
X622967Y485333D01*
X623550Y485083D01*
X624300Y485000D01*
X625050Y485167D01*
X625633Y485500D01*
X626050Y486083D01*
X626133Y486750D01*
X625967Y487417D01*
X625550Y487833D01*
X624967Y488167D01*
X624383Y488250D01*
X623800Y488167D01*
X623050Y487833D01*
X623300Y490000D01*
X625550D01*
G01X627400Y485000D02*
Y488333D01*
G01Y487417D02*
X627650Y487833D01*
X628067Y488167D01*
X628650Y488333D01*
X629233Y488167D01*
X629650Y487833D01*
X629900Y487417D01*
Y485000D01*
G01Y487417D02*
X630150Y487833D01*
X630567Y488167D01*
X631150Y488333D01*
X631733Y488167D01*
X632150Y487833D01*
X632400Y487333D01*
Y485000D01*
G01X635500Y488333D02*
Y485000D01*
G01Y489667D02*
X635333Y489750D01*
Y489917D01*
X635500Y490000D01*
X635667Y489917D01*
Y489750D01*
X635500Y489667D01*
G01X641100Y485000D02*
Y490000D01*
G01X606583Y501667D02*
X608583D01*
G01X607500Y502750D02*
Y500583D01*
G01X611267Y501000D02*
X611767Y500417D01*
X612433Y500083D01*
X613183Y500000D01*
X613850Y500083D01*
X614517Y500500D01*
X614933Y501000D01*
X615017Y501500D01*
X614850Y502083D01*
X614267Y502500D01*
X613683Y502667D01*
X612933D01*
G01X613683D02*
X614183Y502917D01*
X614600Y503333D01*
X614767Y503833D01*
X614600Y504333D01*
X614183Y504750D01*
X613433Y505000D01*
X612683Y504917D01*
X611933Y504583D01*
G01X617200Y499833D02*
X620200Y505000D01*
G01X623217Y501667D02*
X625383D01*
G01X629900Y505000D02*
X629233Y504833D01*
X628733Y504417D01*
X628400Y503917D01*
X628150Y503250D01*
X628067Y502500D01*
X628150Y501750D01*
X628400Y501083D01*
X628733Y500583D01*
X629233Y500167D01*
X629900Y500000D01*
X630567Y500167D01*
X631067Y500583D01*
X631400Y501083D01*
X631650Y501750D01*
X631733Y502500D01*
X631650Y503250D01*
X631400Y503917D01*
X631067Y504417D01*
X630567Y504833D01*
X629900Y505000D01*
G01X633000Y500000D02*
Y503333D01*
G01Y502417D02*
X633250Y502833D01*
X633667Y503167D01*
X634250Y503333D01*
X634833Y503167D01*
X635250Y502833D01*
X635500Y502417D01*
Y500000D01*
G01Y502417D02*
X635750Y502833D01*
X636167Y503167D01*
X636750Y503333D01*
X637333Y503167D01*
X637750Y502833D01*
X638000Y502333D01*
Y500000D01*
G01X641100Y503333D02*
Y500000D01*
G01Y504667D02*
X640933Y504750D01*
Y504917D01*
X641100Y505000D01*
X641267Y504917D01*
Y504750D01*
X641100Y504667D01*
G01X646700Y500000D02*
Y505000D01*
G01X606583Y516667D02*
X608583D01*
G01X607500Y517750D02*
Y515583D01*
G01X611600Y514833D02*
X614600Y520000D01*
G01X617617Y516667D02*
X619783D01*
G01X622717Y519167D02*
X623217Y519667D01*
X623800Y519917D01*
X624467Y520000D01*
X625300Y519833D01*
X625883Y519417D01*
X626050Y518917D01*
X625967Y518417D01*
X625633Y518000D01*
X623967Y517167D01*
X623217Y516583D01*
X622717Y515750D01*
X622550Y515000D01*
X626050D01*
G01X627400D02*
Y518333D01*
G01Y517417D02*
X627650Y517833D01*
X628067Y518167D01*
X628650Y518333D01*
X629233Y518167D01*
X629650Y517833D01*
X629900Y517417D01*
Y515000D01*
G01Y517417D02*
X630150Y517833D01*
X630567Y518167D01*
X631150Y518333D01*
X631733Y518167D01*
X632150Y517833D01*
X632400Y517333D01*
Y515000D01*
G01X635500Y518333D02*
Y515000D01*
G01Y519667D02*
X635333Y519750D01*
Y519917D01*
X635500Y520000D01*
X635667Y519917D01*
Y519750D01*
X635500Y519667D01*
G01X641100Y515000D02*
Y520000D01*
G01X606583Y530167D02*
X608583D01*
G01X607500Y531250D02*
Y529083D01*
G01X611600Y528333D02*
X614600Y533500D01*
G01X617617Y530167D02*
X619783D01*
G01X622467Y529500D02*
X622967Y528917D01*
X623633Y528583D01*
X624383Y528500D01*
X625050Y528583D01*
X625717Y529000D01*
X626133Y529500D01*
X626217Y530000D01*
X626050Y530583D01*
X625467Y531000D01*
X624883Y531167D01*
X624133D01*
G01X624883D02*
X625383Y531417D01*
X625800Y531833D01*
X625967Y532333D01*
X625800Y532833D01*
X625383Y533250D01*
X624633Y533500D01*
X623883Y533417D01*
X623133Y533083D01*
G01X627400Y528500D02*
Y531833D01*
G01Y530917D02*
X627650Y531333D01*
X628067Y531667D01*
X628650Y531833D01*
X629233Y531667D01*
X629650Y531333D01*
X629900Y530917D01*
Y528500D01*
G01Y530917D02*
X630150Y531333D01*
X630567Y531667D01*
X631150Y531833D01*
X631733Y531667D01*
X632150Y531333D01*
X632400Y530833D01*
Y528500D01*
G01X635500Y531833D02*
Y528500D01*
G01Y533167D02*
X635333Y533250D01*
Y533417D01*
X635500Y533500D01*
X635667Y533417D01*
Y533250D01*
X635500Y533167D01*
G01X641100Y528500D02*
Y533500D01*
G01X606583Y591667D02*
X608583D01*
G01X607500Y592750D02*
Y590583D01*
G01X611600Y589833D02*
X614600Y595000D01*
G01X617617Y591667D02*
X619783D01*
G01X622467Y591000D02*
X622967Y590417D01*
X623633Y590083D01*
X624383Y590000D01*
X625050Y590083D01*
X625717Y590500D01*
X626133Y591000D01*
X626217Y591500D01*
X626050Y592083D01*
X625467Y592500D01*
X624883Y592667D01*
X624133D01*
G01X624883D02*
X625383Y592917D01*
X625800Y593333D01*
X625967Y593833D01*
X625800Y594333D01*
X625383Y594750D01*
X624633Y595000D01*
X623883Y594917D01*
X623133Y594583D01*
G01X627400Y590000D02*
Y593333D01*
G01Y592417D02*
X627650Y592833D01*
X628067Y593167D01*
X628650Y593333D01*
X629233Y593167D01*
X629650Y592833D01*
X629900Y592417D01*
Y590000D01*
G01Y592417D02*
X630150Y592833D01*
X630567Y593167D01*
X631150Y593333D01*
X631733Y593167D01*
X632150Y592833D01*
X632400Y592333D01*
Y590000D01*
G01X635500Y593333D02*
Y590000D01*
G01Y594667D02*
X635333Y594750D01*
Y594917D01*
X635500Y595000D01*
X635667Y594917D01*
Y594750D01*
X635500Y594667D01*
G01X641100Y590000D02*
Y595000D01*
G01X605417Y603500D02*
X607500Y608500D01*
X609583Y603500D01*
G01X608833Y605250D02*
X606167D01*
G01X613100Y603500D02*
Y608500D01*
G01X618700Y603500D02*
Y608500D01*
G01X624300Y603500D02*
X623800Y603583D01*
X623300Y603917D01*
X622967Y604500D01*
X622800Y605167D01*
X622967Y605833D01*
X623300Y606417D01*
X623800Y606750D01*
X624300Y606833D01*
X624800Y606750D01*
X625300Y606417D01*
X625633Y605833D01*
X625717Y605167D01*
X625633Y604500D01*
X625300Y603917D01*
X624800Y603583D01*
X624300Y603500D01*
G01X627817Y606833D02*
X628817Y603500D01*
X629900Y606833D01*
X630983Y603500D01*
X631983Y606833D01*
G01X606583Y546667D02*
X608583D01*
G01X607500Y547750D02*
Y545583D01*
G01X611600Y544833D02*
X614600Y550000D01*
G01X617617Y546667D02*
X619783D01*
G01X622717Y549167D02*
X623217Y549667D01*
X623800Y549917D01*
X624467Y550000D01*
X625300Y549833D01*
X625883Y549417D01*
X626050Y548917D01*
X625967Y548417D01*
X625633Y548000D01*
X623967Y547167D01*
X623217Y546583D01*
X622717Y545750D01*
X622550Y545000D01*
X626050D01*
G01X627400D02*
Y548333D01*
G01Y547417D02*
X627650Y547833D01*
X628067Y548167D01*
X628650Y548333D01*
X629233Y548167D01*
X629650Y547833D01*
X629900Y547417D01*
Y545000D01*
G01Y547417D02*
X630150Y547833D01*
X630567Y548167D01*
X631150Y548333D01*
X631733Y548167D01*
X632150Y547833D01*
X632400Y547333D01*
Y545000D01*
G01X635500Y548333D02*
Y545000D01*
G01Y549667D02*
X635333Y549750D01*
Y549917D01*
X635500Y550000D01*
X635667Y549917D01*
Y549750D01*
X635500Y549667D01*
G01X641100Y545000D02*
Y550000D01*
G01X606583Y575167D02*
X608583D01*
G01X607500Y576250D02*
Y574083D01*
G01X611517Y577667D02*
X612017Y578167D01*
X612600Y578417D01*
X613267Y578500D01*
X614100Y578333D01*
X614683Y577917D01*
X614850Y577417D01*
X614767Y576917D01*
X614433Y576500D01*
X612767Y575667D01*
X612017Y575083D01*
X611517Y574250D01*
X611350Y573500D01*
X614850D01*
G01X617200Y573333D02*
X620200Y578500D01*
G01X623217Y575167D02*
X625383D01*
G01X630900Y573500D02*
Y578500D01*
X627817Y574917D01*
X631983D01*
G01X633000Y573500D02*
Y576833D01*
G01Y575917D02*
X633250Y576333D01*
X633667Y576667D01*
X634250Y576833D01*
X634833Y576667D01*
X635250Y576333D01*
X635500Y575917D01*
Y573500D01*
G01Y575917D02*
X635750Y576333D01*
X636167Y576667D01*
X636750Y576833D01*
X637333Y576667D01*
X637750Y576333D01*
X638000Y575833D01*
Y573500D01*
G01X641100Y576833D02*
Y573500D01*
G01Y578167D02*
X640933Y578250D01*
Y578417D01*
X641100Y578500D01*
X641267Y578417D01*
Y578250D01*
X641100Y578167D01*
G01X646700Y573500D02*
Y578500D01*
G01X606583Y561667D02*
X608583D01*
G01X607500Y562750D02*
Y560583D01*
G01X611600Y559833D02*
X614600Y565000D01*
G01X617617Y561667D02*
X619783D01*
G01X622717Y564167D02*
X623217Y564667D01*
X623800Y564917D01*
X624467Y565000D01*
X625300Y564833D01*
X625883Y564417D01*
X626050Y563917D01*
X625967Y563417D01*
X625633Y563000D01*
X623967Y562167D01*
X623217Y561583D01*
X622717Y560750D01*
X622550Y560000D01*
X626050D01*
G01X627400D02*
Y563333D01*
G01Y562417D02*
X627650Y562833D01*
X628067Y563167D01*
X628650Y563333D01*
X629233Y563167D01*
X629650Y562833D01*
X629900Y562417D01*
Y560000D01*
G01Y562417D02*
X630150Y562833D01*
X630567Y563167D01*
X631150Y563333D01*
X631733Y563167D01*
X632150Y562833D01*
X632400Y562333D01*
Y560000D01*
G01X635500Y563333D02*
Y560000D01*
G01Y564667D02*
X635333Y564750D01*
Y564917D01*
X635500Y565000D01*
X635667Y564917D01*
Y564750D01*
X635500Y564667D01*
G01X641100Y560000D02*
Y565000D01*
G01X606583Y620167D02*
X608583D01*
G01X607500Y621250D02*
Y619083D01*
G01X611600Y618333D02*
X614600Y623500D01*
G01X617617Y620167D02*
X619783D01*
G01X622717Y622667D02*
X623217Y623167D01*
X623800Y623417D01*
X624467Y623500D01*
X625300Y623333D01*
X625883Y622917D01*
X626050Y622417D01*
X625967Y621917D01*
X625633Y621500D01*
X623967Y620667D01*
X623217Y620083D01*
X622717Y619250D01*
X622550Y618500D01*
X626050D01*
G01X627400D02*
Y621833D01*
G01Y620917D02*
X627650Y621333D01*
X628067Y621667D01*
X628650Y621833D01*
X629233Y621667D01*
X629650Y621333D01*
X629900Y620917D01*
Y618500D01*
G01Y620917D02*
X630150Y621333D01*
X630567Y621667D01*
X631150Y621833D01*
X631733Y621667D01*
X632150Y621333D01*
X632400Y620833D01*
Y618500D01*
G01X635500Y621833D02*
Y618500D01*
G01Y623167D02*
X635333Y623250D01*
Y623417D01*
X635500Y623500D01*
X635667Y623417D01*
Y623250D01*
X635500Y623167D01*
G01X641100Y618500D02*
Y623500D01*
G01X605353Y638700D02*
Y643700D01*
X607520Y639533D01*
X609687Y643700D01*
Y638700D01*
G01X611703Y642033D02*
Y639700D01*
X612037Y639117D01*
X612537Y638783D01*
X613120Y638700D01*
X613703Y638783D01*
X614203Y639117D01*
X614537Y639700D01*
G01Y638700D02*
Y642033D01*
G01X617470Y639283D02*
X617887Y638950D01*
X618470Y638700D01*
X618970D01*
X619470Y638867D01*
X619803Y639117D01*
X619970Y639450D01*
X619887Y639950D01*
X619553Y640200D01*
X618053Y640700D01*
X617720Y641283D01*
X617887Y641700D01*
X618220Y641950D01*
X618720Y642033D01*
X619220Y641950D01*
X619720Y641700D01*
G01X624320Y643700D02*
Y638700D01*
G01X623153Y642033D02*
X625487D01*
G01X635020Y638700D02*
Y642950D01*
X635187Y643367D01*
X635520Y643617D01*
X636020Y643700D01*
X636520Y643533D01*
X636770Y643117D01*
G01X635770Y641700D02*
X634103D01*
G01X641120Y638700D02*
X640620Y638783D01*
X640120Y639117D01*
X639787Y639700D01*
X639620Y640367D01*
X639787Y641033D01*
X640120Y641617D01*
X640620Y641950D01*
X641120Y642033D01*
X641620Y641950D01*
X642120Y641617D01*
X642453Y641033D01*
X642537Y640367D01*
X642453Y639700D01*
X642120Y639117D01*
X641620Y638783D01*
X641120Y638700D01*
G01X646720D02*
Y643700D01*
G01X652320Y638700D02*
Y643700D01*
G01X657920Y638700D02*
X657420Y638783D01*
X656920Y639117D01*
X656587Y639700D01*
X656420Y640367D01*
X656587Y641033D01*
X656920Y641617D01*
X657420Y641950D01*
X657920Y642033D01*
X658420Y641950D01*
X658920Y641617D01*
X659253Y641033D01*
X659337Y640367D01*
X659253Y639700D01*
X658920Y639117D01*
X658420Y638783D01*
X657920Y638700D01*
G01X661437Y642033D02*
X662437Y638700D01*
X663520Y642033D01*
X664603Y638700D01*
X665603Y642033D01*
G01X590417Y860000D02*
X592500Y855000D01*
X594583Y860000D01*
G01X596267Y856000D02*
X596767Y855417D01*
X597433Y855083D01*
X598183Y855000D01*
X598850Y855083D01*
X599517Y855500D01*
X599933Y856000D01*
X600017Y856500D01*
X599850Y857083D01*
X599267Y857500D01*
X598683Y857667D01*
X597933D01*
G01X598683D02*
X599183Y857917D01*
X599600Y858333D01*
X599767Y858833D01*
X599600Y859333D01*
X599183Y859750D01*
X598433Y860000D01*
X597683Y859917D01*
X596933Y859583D01*
G01X603700Y854833D02*
X603533Y854917D01*
Y855083D01*
X603700Y855167D01*
X603867Y855083D01*
Y854917D01*
X603700Y854833D01*
G01X610300Y855000D02*
Y860000D01*
X607217Y856417D01*
X611383D01*
G01X614900Y854833D02*
X614733Y854917D01*
Y855083D01*
X614900Y855167D01*
X615067Y855083D01*
Y854917D01*
X614900Y854833D01*
G01X620500Y855000D02*
Y860000D01*
X619500Y859000D01*
G01Y855000D02*
X621500D01*
G01X641317Y859167D02*
X641817Y859667D01*
X642400Y859917D01*
X643067Y860000D01*
X643900Y859833D01*
X644483Y859417D01*
X644650Y858917D01*
X644567Y858417D01*
X644233Y858000D01*
X642567Y857167D01*
X641817Y856583D01*
X641317Y855750D01*
X641150Y855000D01*
X644650D01*
G01X648500Y860000D02*
X647833Y859833D01*
X647333Y859417D01*
X647000Y858917D01*
X646750Y858250D01*
X646667Y857500D01*
X646750Y856750D01*
X647000Y856083D01*
X647333Y855583D01*
X647833Y855167D01*
X648500Y855000D01*
X649167Y855167D01*
X649667Y855583D01*
X650000Y856083D01*
X650250Y856750D01*
X650333Y857500D01*
X650250Y858250D01*
X650000Y858917D01*
X649667Y859417D01*
X649167Y859833D01*
X648500Y860000D01*
G01X654100Y855000D02*
Y860000D01*
X653100Y859000D01*
G01Y855000D02*
X655100D01*
G01X657867Y855750D02*
X658367Y855333D01*
X658950Y855083D01*
X659700Y855000D01*
X660450Y855167D01*
X661033Y855500D01*
X661450Y856083D01*
X661533Y856750D01*
X661367Y857417D01*
X660950Y857833D01*
X660367Y858167D01*
X659783Y858250D01*
X659200Y858167D01*
X658450Y857833D01*
X658700Y860000D01*
X660950D01*
G01X663800Y854833D02*
X666800Y860000D01*
G01X670900D02*
X670233Y859833D01*
X669733Y859417D01*
X669400Y858917D01*
X669150Y858250D01*
X669067Y857500D01*
X669150Y856750D01*
X669400Y856083D01*
X669733Y855583D01*
X670233Y855167D01*
X670900Y855000D01*
X671567Y855167D01*
X672067Y855583D01*
X672400Y856083D01*
X672650Y856750D01*
X672733Y857500D01*
X672650Y858250D01*
X672400Y858917D01*
X672067Y859417D01*
X671567Y859833D01*
X670900Y860000D01*
G01X674917Y857083D02*
X675500Y857667D01*
X676000Y858000D01*
X676667Y858167D01*
X677250Y858000D01*
X677667Y857667D01*
X678000Y857167D01*
X678083Y856583D01*
X678000Y856083D01*
X677667Y855583D01*
X677167Y855167D01*
X676583Y855000D01*
X675917Y855167D01*
X675333Y855667D01*
X675000Y856417D01*
X674917Y857250D01*
X675083Y858333D01*
X675333Y858917D01*
X675750Y859500D01*
X676333Y859917D01*
X676917Y860000D01*
X677500Y859833D01*
X677917Y859417D01*
G01X694500Y716000D02*
Y-69500D01*
G01X650853Y438153D02*
X650020Y438987D01*
X649603Y439820D01*
Y443153D01*
X650020Y443987D01*
X650853Y444820D01*
G01X656870Y439820D02*
X656370Y439903D01*
X655870Y440237D01*
X655537Y440820D01*
X655370Y441487D01*
X655537Y442153D01*
X655870Y442737D01*
X656370Y443070D01*
X656870Y443153D01*
X657370Y443070D01*
X657870Y442737D01*
X658203Y442153D01*
X658287Y441487D01*
X658203Y440820D01*
X657870Y440237D01*
X657370Y439903D01*
X656870Y439820D01*
G01X661303D02*
Y443153D01*
G01Y442487D02*
X661720Y442820D01*
X662137Y443070D01*
X662720Y443153D01*
X663137Y443070D01*
X663637Y442820D01*
G01X617500Y668500D02*
Y663500D01*
G01X615583Y668500D02*
X619417D01*
G01X623100Y663500D02*
X622600Y663583D01*
X622100Y663917D01*
X621767Y664500D01*
X621600Y665167D01*
X621767Y665833D01*
X622100Y666417D01*
X622600Y666750D01*
X623100Y666833D01*
X623600Y666750D01*
X624100Y666417D01*
X624433Y665833D01*
X624517Y665167D01*
X624433Y664500D01*
X624100Y663917D01*
X623600Y663583D01*
X623100Y663500D01*
G01X628700D02*
Y668500D01*
G01X633050Y665750D02*
X635717D01*
X635467Y666333D01*
X635050Y666667D01*
X634467Y666833D01*
X633883Y666750D01*
X633383Y666500D01*
X633050Y665917D01*
X632883Y665417D01*
Y664917D01*
X633050Y664417D01*
X633467Y663917D01*
X633967Y663583D01*
X634550Y663500D01*
X635133Y663667D01*
X635717Y664167D01*
G01X638733Y663500D02*
Y666833D01*
G01Y666167D02*
X639150Y666500D01*
X639567Y666750D01*
X640150Y666833D01*
X640567Y666750D01*
X641067Y666500D01*
G01X647000Y663500D02*
Y666833D01*
G01Y666250D02*
X646667Y666583D01*
X646167Y666750D01*
X645583Y666833D01*
X645000Y666667D01*
X644500Y666333D01*
X644167Y665833D01*
X644000Y665167D01*
X644167Y664500D01*
X644500Y664000D01*
X645000Y663667D01*
X645583Y663500D01*
X646167Y663583D01*
X646667Y663833D01*
X647000Y664167D01*
G01X649683Y663500D02*
Y666833D01*
G01Y666000D02*
X650017Y666417D01*
X650517Y666750D01*
X651183Y666833D01*
X651767Y666750D01*
X652267Y666417D01*
X652517Y665833D01*
Y663500D01*
G01X658033Y666417D02*
X657450Y666750D01*
X656950Y666833D01*
X656283Y666667D01*
X655783Y666333D01*
X655450Y665750D01*
X655367Y665167D01*
X655450Y664583D01*
X655783Y664083D01*
X656283Y663667D01*
X656950Y663500D01*
X657533Y663667D01*
X658033Y664000D01*
G01X661050Y665750D02*
X663717D01*
X663467Y666333D01*
X663050Y666667D01*
X662467Y666833D01*
X661883Y666750D01*
X661383Y666500D01*
X661050Y665917D01*
X660883Y665417D01*
Y664917D01*
X661050Y664417D01*
X661467Y663917D01*
X661967Y663583D01*
X662550Y663500D01*
X663133Y663667D01*
X663717Y664167D01*
G01X736937Y-65320D02*
X737437Y-65737D01*
X738020Y-65987D01*
X738770Y-66070D01*
X739520Y-65903D01*
X740103Y-65570D01*
X740520Y-64987D01*
X740603Y-64320D01*
X740437Y-63653D01*
X740020Y-63237D01*
X739437Y-62903D01*
X738853Y-62820D01*
X738270Y-62903D01*
X737520Y-63237D01*
X737770Y-61070D01*
X740020D01*
G01X744370Y-66237D02*
X744203Y-66153D01*
Y-65987D01*
X744370Y-65903D01*
X744537Y-65987D01*
Y-66153D01*
X744370Y-66237D01*
G01X749970Y-66070D02*
Y-61070D01*
X748970Y-62070D01*
G01Y-66070D02*
X750970D01*
G01X760170Y-61070D02*
X762170D01*
G01X761170D02*
Y-66070D01*
G01X760170D02*
X762170D01*
G01X766270D02*
Y-61820D01*
X766437Y-61403D01*
X766770Y-61153D01*
X767270Y-61070D01*
X767770Y-61237D01*
X768020Y-61653D01*
G01X767020Y-63070D02*
X765353D01*
G01X778470Y-63570D02*
X780137D01*
Y-65070D01*
X779637Y-65570D01*
X779053Y-65903D01*
X778220Y-66070D01*
X777387Y-65903D01*
X776803Y-65570D01*
X776303Y-65070D01*
X775970Y-64487D01*
X775803Y-63820D01*
Y-63237D01*
X775970Y-62737D01*
X776303Y-62153D01*
X776803Y-61653D01*
X777303Y-61320D01*
X777970Y-61070D01*
X778553D01*
X779220Y-61237D01*
X779720Y-61570D01*
G01X782320Y-63820D02*
X784987D01*
X784737Y-63237D01*
X784320Y-62903D01*
X783737Y-62737D01*
X783153Y-62820D01*
X782653Y-63070D01*
X782320Y-63653D01*
X782153Y-64153D01*
Y-64653D01*
X782320Y-65153D01*
X782737Y-65653D01*
X783237Y-65987D01*
X783820Y-66070D01*
X784403Y-65903D01*
X784987Y-65403D01*
G01X788003Y-66070D02*
Y-62737D01*
G01Y-63403D02*
X788420Y-63070D01*
X788837Y-62820D01*
X789420Y-62737D01*
X789837Y-62820D01*
X790337Y-63070D01*
G01X793270Y-66070D02*
Y-61070D01*
G01Y-63570D02*
X793687Y-63070D01*
X794187Y-62820D01*
X794687Y-62737D01*
X795437Y-62903D01*
X795937Y-63237D01*
X796270Y-63820D01*
Y-64487D01*
X796103Y-65153D01*
X795770Y-65653D01*
X795187Y-65987D01*
X794687Y-66070D01*
X794187Y-65987D01*
X793687Y-65737D01*
X793270Y-65320D01*
G01X799120Y-63820D02*
X801787D01*
X801537Y-63237D01*
X801120Y-62903D01*
X800537Y-62737D01*
X799953Y-62820D01*
X799453Y-63070D01*
X799120Y-63653D01*
X798953Y-64153D01*
Y-64653D01*
X799120Y-65153D01*
X799537Y-65653D01*
X800037Y-65987D01*
X800620Y-66070D01*
X801203Y-65903D01*
X801787Y-65403D01*
G01X804803Y-66070D02*
Y-62737D01*
G01Y-63403D02*
X805220Y-63070D01*
X805637Y-62820D01*
X806220Y-62737D01*
X806637Y-62820D01*
X807137Y-63070D01*
G01X815753Y-66070D02*
Y-61070D01*
G01Y-63487D02*
X816170Y-63070D01*
X816587Y-62820D01*
X817253Y-62737D01*
X817753Y-62820D01*
X818337Y-63153D01*
X818587Y-63653D01*
Y-66070D01*
G01X824270D02*
Y-62737D01*
G01Y-63320D02*
X823937Y-62987D01*
X823437Y-62820D01*
X822853Y-62737D01*
X822270Y-62903D01*
X821770Y-63237D01*
X821437Y-63737D01*
X821270Y-64403D01*
X821437Y-65070D01*
X821770Y-65570D01*
X822270Y-65903D01*
X822853Y-66070D01*
X823437Y-65987D01*
X823937Y-65737D01*
X824270Y-65403D01*
G01X827120Y-65487D02*
X827537Y-65820D01*
X828120Y-66070D01*
X828620D01*
X829120Y-65903D01*
X829453Y-65653D01*
X829620Y-65320D01*
X829537Y-64820D01*
X829203Y-64570D01*
X827703Y-64070D01*
X827370Y-63487D01*
X827537Y-63070D01*
X827870Y-62820D01*
X828370Y-62737D01*
X828870Y-62820D01*
X829370Y-63070D01*
G01X839570Y-61070D02*
Y-66070D01*
G01X838403Y-62737D02*
X840737D01*
G01X843753Y-66070D02*
Y-61070D01*
G01Y-63487D02*
X844170Y-63070D01*
X844587Y-62820D01*
X845253Y-62737D01*
X845753Y-62820D01*
X846337Y-63153D01*
X846587Y-63653D01*
Y-66070D01*
G01X850770Y-62737D02*
Y-66070D01*
G01Y-61403D02*
X850603Y-61320D01*
Y-61153D01*
X850770Y-61070D01*
X850937Y-61153D01*
Y-61320D01*
X850770Y-61403D01*
G01X855120Y-65487D02*
X855537Y-65820D01*
X856120Y-66070D01*
X856620D01*
X857120Y-65903D01*
X857453Y-65653D01*
X857620Y-65320D01*
X857537Y-64820D01*
X857203Y-64570D01*
X855703Y-64070D01*
X855370Y-63487D01*
X855537Y-63070D01*
X855870Y-62820D01*
X856370Y-62737D01*
X856870Y-62820D01*
X857370Y-63070D01*
G01X866153Y-66070D02*
Y-61070D01*
G01X868820Y-62737D02*
X866153Y-64653D01*
G01X867237Y-63903D02*
X868987Y-66070D01*
G01X873170Y-62737D02*
Y-66070D01*
G01Y-61403D02*
X873003Y-61320D01*
Y-61153D01*
X873170Y-61070D01*
X873337Y-61153D01*
Y-61320D01*
X873170Y-61403D01*
G01X877353Y-66070D02*
Y-62737D01*
G01Y-63570D02*
X877687Y-63153D01*
X878187Y-62820D01*
X878853Y-62737D01*
X879437Y-62820D01*
X879937Y-63153D01*
X880187Y-63737D01*
Y-66070D01*
G01X885870Y-61070D02*
Y-66070D01*
G01Y-65320D02*
X885537Y-65737D01*
X885037Y-65987D01*
X884453Y-66070D01*
X883787Y-65903D01*
X883287Y-65487D01*
X882953Y-64987D01*
X882870Y-64403D01*
X882953Y-63820D01*
X883287Y-63320D01*
X883787Y-62903D01*
X884453Y-62737D01*
X885037Y-62820D01*
X885453Y-62987D01*
X885870Y-63320D01*
G01X895570Y-66070D02*
X895070Y-65987D01*
X894570Y-65653D01*
X894237Y-65070D01*
X894070Y-64403D01*
X894237Y-63737D01*
X894570Y-63153D01*
X895070Y-62820D01*
X895570Y-62737D01*
X896070Y-62820D01*
X896570Y-63153D01*
X896903Y-63737D01*
X896987Y-64403D01*
X896903Y-65070D01*
X896570Y-65653D01*
X896070Y-65987D01*
X895570Y-66070D01*
G01X900670D02*
Y-61820D01*
X900837Y-61403D01*
X901170Y-61153D01*
X901670Y-61070D01*
X902170Y-61237D01*
X902420Y-61653D01*
G01X901420Y-63070D02*
X899753D01*
G01X913870Y-61070D02*
Y-66070D01*
G01Y-65320D02*
X913537Y-65737D01*
X913037Y-65987D01*
X912453Y-66070D01*
X911787Y-65903D01*
X911287Y-65487D01*
X910953Y-64987D01*
X910870Y-64403D01*
X910953Y-63820D01*
X911287Y-63320D01*
X911787Y-62903D01*
X912453Y-62737D01*
X913037Y-62820D01*
X913453Y-62987D01*
X913870Y-63320D01*
G01X916720Y-63820D02*
X919387D01*
X919137Y-63237D01*
X918720Y-62903D01*
X918137Y-62737D01*
X917553Y-62820D01*
X917053Y-63070D01*
X916720Y-63653D01*
X916553Y-64153D01*
Y-64653D01*
X916720Y-65153D01*
X917137Y-65653D01*
X917637Y-65987D01*
X918220Y-66070D01*
X918803Y-65903D01*
X919387Y-65403D01*
G01X922320Y-65487D02*
X922737Y-65820D01*
X923320Y-66070D01*
X923820D01*
X924320Y-65903D01*
X924653Y-65653D01*
X924820Y-65320D01*
X924737Y-64820D01*
X924403Y-64570D01*
X922903Y-64070D01*
X922570Y-63487D01*
X922737Y-63070D01*
X923070Y-62820D01*
X923570Y-62737D01*
X924070Y-62820D01*
X924570Y-63070D01*
G01X929170Y-62737D02*
Y-66070D01*
G01Y-61403D02*
X929003Y-61320D01*
Y-61153D01*
X929170Y-61070D01*
X929337Y-61153D01*
Y-61320D01*
X929170Y-61403D01*
G01X933603Y-67320D02*
X934187Y-67653D01*
X934853Y-67737D01*
X935437Y-67653D01*
X935937Y-67237D01*
X936270Y-66653D01*
Y-62737D01*
G01Y-63403D02*
X935937Y-63070D01*
X935437Y-62820D01*
X934853Y-62737D01*
X934187Y-62903D01*
X933770Y-63237D01*
X933437Y-63820D01*
X933270Y-64403D01*
X933353Y-64903D01*
X933687Y-65487D01*
X934187Y-65903D01*
X934853Y-66070D01*
X935353Y-65987D01*
X935937Y-65653D01*
X936270Y-65320D01*
G01X938953Y-66070D02*
Y-62737D01*
G01Y-63570D02*
X939287Y-63153D01*
X939787Y-62820D01*
X940453Y-62737D01*
X941037Y-62820D01*
X941537Y-63153D01*
X941787Y-63737D01*
Y-66070D01*
G01X945803Y-66987D02*
X946137Y-65903D01*
G01X955670Y-67737D02*
Y-62737D01*
G01Y-63487D02*
X956087Y-63070D01*
X956503Y-62820D01*
X957170Y-62737D01*
X957753Y-62820D01*
X958337Y-63237D01*
X958587Y-63820D01*
X958670Y-64403D01*
X958587Y-64987D01*
X958337Y-65570D01*
X957837Y-65903D01*
X957170Y-66070D01*
X956587Y-65987D01*
X956003Y-65737D01*
X955670Y-65403D01*
G01X962770Y-66070D02*
Y-61070D01*
G01X967120Y-63820D02*
X969787D01*
X969537Y-63237D01*
X969120Y-62903D01*
X968537Y-62737D01*
X967953Y-62820D01*
X967453Y-63070D01*
X967120Y-63653D01*
X966953Y-64153D01*
Y-64653D01*
X967120Y-65153D01*
X967537Y-65653D01*
X968037Y-65987D01*
X968620Y-66070D01*
X969203Y-65903D01*
X969787Y-65403D01*
G01X975470Y-66070D02*
Y-62737D01*
G01Y-63320D02*
X975137Y-62987D01*
X974637Y-62820D01*
X974053Y-62737D01*
X973470Y-62903D01*
X972970Y-63237D01*
X972637Y-63737D01*
X972470Y-64403D01*
X972637Y-65070D01*
X972970Y-65570D01*
X973470Y-65903D01*
X974053Y-66070D01*
X974637Y-65987D01*
X975137Y-65737D01*
X975470Y-65403D01*
G01X978320Y-65487D02*
X978737Y-65820D01*
X979320Y-66070D01*
X979820D01*
X980320Y-65903D01*
X980653Y-65653D01*
X980820Y-65320D01*
X980737Y-64820D01*
X980403Y-64570D01*
X978903Y-64070D01*
X978570Y-63487D01*
X978737Y-63070D01*
X979070Y-62820D01*
X979570Y-62737D01*
X980070Y-62820D01*
X980570Y-63070D01*
G01X983920Y-63820D02*
X986587D01*
X986337Y-63237D01*
X985920Y-62903D01*
X985337Y-62737D01*
X984753Y-62820D01*
X984253Y-63070D01*
X983920Y-63653D01*
X983753Y-64153D01*
Y-64653D01*
X983920Y-65153D01*
X984337Y-65653D01*
X984837Y-65987D01*
X985420Y-66070D01*
X986003Y-65903D01*
X986587Y-65403D01*
G01X995870Y-66070D02*
Y-61820D01*
X996037Y-61403D01*
X996370Y-61153D01*
X996870Y-61070D01*
X997370Y-61237D01*
X997620Y-61653D01*
G01X996620Y-63070D02*
X994953D01*
G01X1001970Y-66070D02*
X1001470Y-65987D01*
X1000970Y-65653D01*
X1000637Y-65070D01*
X1000470Y-64403D01*
X1000637Y-63737D01*
X1000970Y-63153D01*
X1001470Y-62820D01*
X1001970Y-62737D01*
X1002470Y-62820D01*
X1002970Y-63153D01*
X1003303Y-63737D01*
X1003387Y-64403D01*
X1003303Y-65070D01*
X1002970Y-65653D01*
X1002470Y-65987D01*
X1001970Y-66070D01*
G01X1007570D02*
Y-61070D01*
G01X1013170Y-66070D02*
Y-61070D01*
G01X1018770Y-66070D02*
X1018270Y-65987D01*
X1017770Y-65653D01*
X1017437Y-65070D01*
X1017270Y-64403D01*
X1017437Y-63737D01*
X1017770Y-63153D01*
X1018270Y-62820D01*
X1018770Y-62737D01*
X1019270Y-62820D01*
X1019770Y-63153D01*
X1020103Y-63737D01*
X1020187Y-64403D01*
X1020103Y-65070D01*
X1019770Y-65653D01*
X1019270Y-65987D01*
X1018770Y-66070D01*
G01X1022287Y-62737D02*
X1023287Y-66070D01*
X1024370Y-62737D01*
X1025453Y-66070D01*
X1026453Y-62737D01*
G01X1029970Y-66237D02*
X1029803Y-66153D01*
Y-65987D01*
X1029970Y-65903D01*
X1030137Y-65987D01*
Y-66153D01*
X1029970Y-66237D01*
G01X1040170Y-61070D02*
X1042170D01*
G01X1041170D02*
Y-66070D01*
G01X1040170D02*
X1042170D01*
G01X1046270D02*
Y-61820D01*
X1046437Y-61403D01*
X1046770Y-61153D01*
X1047270Y-61070D01*
X1047770Y-61237D01*
X1048020Y-61653D01*
G01X1047020Y-63070D02*
X1045353D01*
G01X1056553Y-66070D02*
Y-62737D01*
G01Y-63570D02*
X1056887Y-63153D01*
X1057387Y-62820D01*
X1058053Y-62737D01*
X1058637Y-62820D01*
X1059137Y-63153D01*
X1059387Y-63737D01*
Y-66070D01*
G01X1063570D02*
X1063070Y-65987D01*
X1062570Y-65653D01*
X1062237Y-65070D01*
X1062070Y-64403D01*
X1062237Y-63737D01*
X1062570Y-63153D01*
X1063070Y-62820D01*
X1063570Y-62737D01*
X1064070Y-62820D01*
X1064570Y-63153D01*
X1064903Y-63737D01*
X1064987Y-64403D01*
X1064903Y-65070D01*
X1064570Y-65653D01*
X1064070Y-65987D01*
X1063570Y-66070D01*
G01X1069170Y-61070D02*
Y-66070D01*
G01X1068003Y-62737D02*
X1070337D01*
G01X1074603Y-66987D02*
X1074937Y-65903D01*
G01X1084470Y-67737D02*
Y-62737D01*
G01Y-63487D02*
X1084887Y-63070D01*
X1085303Y-62820D01*
X1085970Y-62737D01*
X1086553Y-62820D01*
X1087137Y-63237D01*
X1087387Y-63820D01*
X1087470Y-64403D01*
X1087387Y-64987D01*
X1087137Y-65570D01*
X1086637Y-65903D01*
X1085970Y-66070D01*
X1085387Y-65987D01*
X1084803Y-65737D01*
X1084470Y-65403D01*
G01X1091570Y-66070D02*
Y-61070D01*
G01X1095920Y-63820D02*
X1098587D01*
X1098337Y-63237D01*
X1097920Y-62903D01*
X1097337Y-62737D01*
X1096753Y-62820D01*
X1096253Y-63070D01*
X1095920Y-63653D01*
X1095753Y-64153D01*
Y-64653D01*
X1095920Y-65153D01*
X1096337Y-65653D01*
X1096837Y-65987D01*
X1097420Y-66070D01*
X1098003Y-65903D01*
X1098587Y-65403D01*
G01X1104270Y-66070D02*
Y-62737D01*
G01Y-63320D02*
X1103937Y-62987D01*
X1103437Y-62820D01*
X1102853Y-62737D01*
X1102270Y-62903D01*
X1101770Y-63237D01*
X1101437Y-63737D01*
X1101270Y-64403D01*
X1101437Y-65070D01*
X1101770Y-65570D01*
X1102270Y-65903D01*
X1102853Y-66070D01*
X1103437Y-65987D01*
X1103937Y-65737D01*
X1104270Y-65403D01*
G01X1107120Y-65487D02*
X1107537Y-65820D01*
X1108120Y-66070D01*
X1108620D01*
X1109120Y-65903D01*
X1109453Y-65653D01*
X1109620Y-65320D01*
X1109537Y-64820D01*
X1109203Y-64570D01*
X1107703Y-64070D01*
X1107370Y-63487D01*
X1107537Y-63070D01*
X1107870Y-62820D01*
X1108370Y-62737D01*
X1108870Y-62820D01*
X1109370Y-63070D01*
G01X1112720Y-63820D02*
X1115387D01*
X1115137Y-63237D01*
X1114720Y-62903D01*
X1114137Y-62737D01*
X1113553Y-62820D01*
X1113053Y-63070D01*
X1112720Y-63653D01*
X1112553Y-64153D01*
Y-64653D01*
X1112720Y-65153D01*
X1113137Y-65653D01*
X1113637Y-65987D01*
X1114220Y-66070D01*
X1114803Y-65903D01*
X1115387Y-65403D01*
G01X1125170Y-62737D02*
Y-66070D01*
G01Y-61403D02*
X1125003Y-61320D01*
Y-61153D01*
X1125170Y-61070D01*
X1125337Y-61153D01*
Y-61320D01*
X1125170Y-61403D01*
G01X1132270Y-67737D02*
Y-62737D01*
G01Y-63487D02*
X1131853Y-63070D01*
X1131353Y-62820D01*
X1130770Y-62737D01*
X1130270Y-62820D01*
X1129687Y-63237D01*
X1129353Y-63820D01*
X1129270Y-64403D01*
X1129353Y-64987D01*
X1129687Y-65570D01*
X1130270Y-65987D01*
X1130770Y-66070D01*
X1131353Y-65987D01*
X1131853Y-65737D01*
X1132270Y-65320D01*
G01X1134953Y-66070D02*
Y-62737D01*
G01Y-63570D02*
X1135287Y-63153D01*
X1135787Y-62820D01*
X1136453Y-62737D01*
X1137037Y-62820D01*
X1137537Y-63153D01*
X1137787Y-63737D01*
Y-66070D01*
G01X1141970D02*
X1141470Y-65987D01*
X1140970Y-65653D01*
X1140637Y-65070D01*
X1140470Y-64403D01*
X1140637Y-63737D01*
X1140970Y-63153D01*
X1141470Y-62820D01*
X1141970Y-62737D01*
X1142470Y-62820D01*
X1142970Y-63153D01*
X1143303Y-63737D01*
X1143387Y-64403D01*
X1143303Y-65070D01*
X1142970Y-65653D01*
X1142470Y-65987D01*
X1141970Y-66070D01*
G01X1146403D02*
Y-62737D01*
G01Y-63403D02*
X1146820Y-63070D01*
X1147237Y-62820D01*
X1147820Y-62737D01*
X1148237Y-62820D01*
X1148737Y-63070D01*
G01X1151920Y-63820D02*
X1154587D01*
X1154337Y-63237D01*
X1153920Y-62903D01*
X1153337Y-62737D01*
X1152753Y-62820D01*
X1152253Y-63070D01*
X1151920Y-63653D01*
X1151753Y-64153D01*
Y-64653D01*
X1151920Y-65153D01*
X1152337Y-65653D01*
X1152837Y-65987D01*
X1153420Y-66070D01*
X1154003Y-65903D01*
X1154587Y-65403D01*
G01X1164370Y-61070D02*
Y-66070D01*
G01X1163203Y-62737D02*
X1165537D01*
G01X1168553Y-66070D02*
Y-61070D01*
G01Y-63487D02*
X1168970Y-63070D01*
X1169387Y-62820D01*
X1170053Y-62737D01*
X1170553Y-62820D01*
X1171137Y-63153D01*
X1171387Y-63653D01*
Y-66070D01*
G01X1175570Y-62737D02*
Y-66070D01*
G01Y-61403D02*
X1175403Y-61320D01*
Y-61153D01*
X1175570Y-61070D01*
X1175737Y-61153D01*
Y-61320D01*
X1175570Y-61403D01*
G01X1179920Y-65487D02*
X1180337Y-65820D01*
X1180920Y-66070D01*
X1181420D01*
X1181920Y-65903D01*
X1182253Y-65653D01*
X1182420Y-65320D01*
X1182337Y-64820D01*
X1182003Y-64570D01*
X1180503Y-64070D01*
X1180170Y-63487D01*
X1180337Y-63070D01*
X1180670Y-62820D01*
X1181170Y-62737D01*
X1181670Y-62820D01*
X1182170Y-63070D01*
G01X1191203Y-66070D02*
Y-62737D01*
G01Y-63403D02*
X1191620Y-63070D01*
X1192037Y-62820D01*
X1192620Y-62737D01*
X1193037Y-62820D01*
X1193537Y-63070D01*
G01X1196720Y-63820D02*
X1199387D01*
X1199137Y-63237D01*
X1198720Y-62903D01*
X1198137Y-62737D01*
X1197553Y-62820D01*
X1197053Y-63070D01*
X1196720Y-63653D01*
X1196553Y-64153D01*
Y-64653D01*
X1196720Y-65153D01*
X1197137Y-65653D01*
X1197637Y-65987D01*
X1198220Y-66070D01*
X1198803Y-65903D01*
X1199387Y-65403D01*
G01X1205070Y-67737D02*
Y-62737D01*
G01Y-63487D02*
X1204653Y-63070D01*
X1204153Y-62820D01*
X1203570Y-62737D01*
X1203070Y-62820D01*
X1202487Y-63237D01*
X1202153Y-63820D01*
X1202070Y-64403D01*
X1202153Y-64987D01*
X1202487Y-65570D01*
X1203070Y-65987D01*
X1203570Y-66070D01*
X1204153Y-65987D01*
X1204653Y-65737D01*
X1205070Y-65320D01*
G01X1207753Y-62737D02*
Y-65070D01*
X1208087Y-65653D01*
X1208587Y-65987D01*
X1209170Y-66070D01*
X1209753Y-65987D01*
X1210253Y-65653D01*
X1210587Y-65070D01*
G01Y-66070D02*
Y-62737D01*
G01X1213520Y-63820D02*
X1216187D01*
X1215937Y-63237D01*
X1215520Y-62903D01*
X1214937Y-62737D01*
X1214353Y-62820D01*
X1213853Y-63070D01*
X1213520Y-63653D01*
X1213353Y-64153D01*
Y-64653D01*
X1213520Y-65153D01*
X1213937Y-65653D01*
X1214437Y-65987D01*
X1215020Y-66070D01*
X1215603Y-65903D01*
X1216187Y-65403D01*
G01X1219120Y-65487D02*
X1219537Y-65820D01*
X1220120Y-66070D01*
X1220620D01*
X1221120Y-65903D01*
X1221453Y-65653D01*
X1221620Y-65320D01*
X1221537Y-64820D01*
X1221203Y-64570D01*
X1219703Y-64070D01*
X1219370Y-63487D01*
X1219537Y-63070D01*
X1219870Y-62820D01*
X1220370Y-62737D01*
X1220870Y-62820D01*
X1221370Y-63070D01*
G01X1225970Y-61070D02*
Y-66070D01*
G01X1224803Y-62737D02*
X1227137D01*
G01X1231570Y-66237D02*
X1231403Y-66153D01*
Y-65987D01*
X1231570Y-65903D01*
X1231737Y-65987D01*
Y-66153D01*
X1231570Y-66237D01*
G01X713000Y-53000D02*
X1343000D01*
G01X713000Y850500D02*
Y-73000D01*
X1343000D01*
Y782000D01*
X713000D01*
G01X722667Y-38250D02*
X723167Y-38667D01*
X723750Y-38917D01*
X724500Y-39000D01*
X725250Y-38833D01*
X725833Y-38500D01*
X726250Y-37917D01*
X726333Y-37250D01*
X726167Y-36583D01*
X725750Y-36167D01*
X725167Y-35833D01*
X724583Y-35750D01*
X724000Y-35833D01*
X723250Y-36167D01*
X723500Y-34000D01*
X725750D01*
G01X730100Y-39167D02*
X729933Y-39083D01*
Y-38917D01*
X730100Y-38833D01*
X730267Y-38917D01*
Y-39083D01*
X730100Y-39167D01*
G01X739633Y-39000D02*
Y-34000D01*
X741717D01*
X742383Y-34250D01*
X742800Y-34583D01*
X742967Y-35250D01*
X742800Y-35917D01*
X742300Y-36333D01*
X741717Y-36583D01*
X739633D01*
G01X741717D02*
X742967Y-39000D01*
G01X745650Y-36750D02*
X748317D01*
X748067Y-36167D01*
X747650Y-35833D01*
X747067Y-35667D01*
X746483Y-35750D01*
X745983Y-36000D01*
X745650Y-36583D01*
X745483Y-37083D01*
Y-37583D01*
X745650Y-38083D01*
X746067Y-38583D01*
X746567Y-38917D01*
X747150Y-39000D01*
X747733Y-38833D01*
X748317Y-38333D01*
G01X750000Y-39000D02*
Y-35667D01*
G01Y-36583D02*
X750250Y-36167D01*
X750667Y-35833D01*
X751250Y-35667D01*
X751833Y-35833D01*
X752250Y-36167D01*
X752500Y-36583D01*
Y-39000D01*
G01Y-36583D02*
X752750Y-36167D01*
X753167Y-35833D01*
X753750Y-35667D01*
X754333Y-35833D01*
X754750Y-36167D01*
X755000Y-36667D01*
Y-39000D01*
G01X759600D02*
Y-35667D01*
G01Y-36250D02*
X759267Y-35917D01*
X758767Y-35750D01*
X758183Y-35667D01*
X757600Y-35833D01*
X757100Y-36167D01*
X756767Y-36667D01*
X756600Y-37333D01*
X756767Y-38000D01*
X757100Y-38500D01*
X757600Y-38833D01*
X758183Y-39000D01*
X758767Y-38917D01*
X759267Y-38667D01*
X759600Y-38333D01*
G01X762533Y-39000D02*
Y-35667D01*
G01Y-36333D02*
X762950Y-36000D01*
X763367Y-35750D01*
X763950Y-35667D01*
X764367Y-35750D01*
X764867Y-36000D01*
G01X767883Y-39000D02*
Y-34000D01*
G01X770550Y-35667D02*
X767883Y-37583D01*
G01X768967Y-36833D02*
X770717Y-39000D01*
G01X773067Y-39167D02*
X776733Y-35500D01*
G01X774900Y-34833D02*
Y-39833D01*
G01X776733Y-39167D02*
X773067Y-35500D01*
G01X772400Y-37333D02*
X777400D01*
G01X713000Y-23000D02*
X1343000D01*
G01X777583Y104700D02*
Y99700D01*
X780917D01*
G01X783600Y103033D02*
X786100Y99700D01*
G01Y103033D02*
X783600Y99700D01*
G01X790450Y99533D02*
X790283Y99617D01*
Y99783D01*
X790450Y99867D01*
X790617Y99783D01*
Y99617D01*
X790450Y99533D01*
G01Y101783D02*
X790283Y101867D01*
Y102033D01*
X790450Y102117D01*
X790617Y102033D01*
Y101867D01*
X790450Y101783D01*
G01X799150Y99700D02*
Y103033D01*
G01Y102117D02*
X799400Y102533D01*
X799817Y102867D01*
X800400Y103033D01*
X800983Y102867D01*
X801400Y102533D01*
X801650Y102117D01*
Y99700D01*
G01Y102117D02*
X801900Y102533D01*
X802317Y102867D01*
X802900Y103033D01*
X803483Y102867D01*
X803900Y102533D01*
X804150Y102033D01*
Y99700D01*
G01X805833Y103033D02*
Y100700D01*
X806167Y100117D01*
X806667Y99783D01*
X807250Y99700D01*
X807833Y99783D01*
X808333Y100117D01*
X808667Y100700D01*
G01Y99700D02*
Y103033D01*
G01X811600Y100283D02*
X812017Y99950D01*
X812600Y99700D01*
X813100D01*
X813600Y99867D01*
X813933Y100117D01*
X814100Y100450D01*
X814017Y100950D01*
X813683Y101200D01*
X812183Y101700D01*
X811850Y102283D01*
X812017Y102700D01*
X812350Y102950D01*
X812850Y103033D01*
X813350Y102950D01*
X813850Y102700D01*
G01X818450Y104700D02*
Y99700D01*
G01X817283Y103033D02*
X819617D01*
G01X828150Y99700D02*
Y104700D01*
G01Y102200D02*
X828567Y102700D01*
X829067Y102950D01*
X829567Y103033D01*
X830317Y102867D01*
X830817Y102533D01*
X831150Y101950D01*
Y101283D01*
X830983Y100617D01*
X830650Y100117D01*
X830067Y99783D01*
X829567Y99700D01*
X829067Y99783D01*
X828567Y100033D01*
X828150Y100450D01*
G01X834000Y101950D02*
X836667D01*
X836417Y102533D01*
X836000Y102867D01*
X835417Y103033D01*
X834833Y102950D01*
X834333Y102700D01*
X834000Y102117D01*
X833833Y101617D01*
Y101117D01*
X834000Y100617D01*
X834417Y100117D01*
X834917Y99783D01*
X835500Y99700D01*
X836083Y99867D01*
X836667Y100367D01*
G01X844950Y99700D02*
Y104700D01*
G01Y102200D02*
X845367Y102700D01*
X845867Y102950D01*
X846367Y103033D01*
X847117Y102867D01*
X847617Y102533D01*
X847950Y101950D01*
Y101283D01*
X847783Y100617D01*
X847450Y100117D01*
X846867Y99783D01*
X846367Y99700D01*
X845867Y99783D01*
X845367Y100033D01*
X844950Y100450D01*
G01X850883Y99700D02*
Y103033D01*
G01Y102367D02*
X851300Y102700D01*
X851717Y102950D01*
X852300Y103033D01*
X852717Y102950D01*
X853217Y102700D01*
G01X857650Y99700D02*
X857150Y99783D01*
X856650Y100117D01*
X856317Y100700D01*
X856150Y101367D01*
X856317Y102033D01*
X856650Y102617D01*
X857150Y102950D01*
X857650Y103033D01*
X858150Y102950D01*
X858650Y102617D01*
X858983Y102033D01*
X859067Y101367D01*
X858983Y100700D01*
X858650Y100117D01*
X858150Y99783D01*
X857650Y99700D01*
G01X861833D02*
Y104700D01*
G01X864500Y103033D02*
X861833Y101117D01*
G01X862917Y101867D02*
X864667Y99700D01*
G01X867600Y101950D02*
X870267D01*
X870017Y102533D01*
X869600Y102867D01*
X869017Y103033D01*
X868433Y102950D01*
X867933Y102700D01*
X867600Y102117D01*
X867433Y101617D01*
Y101117D01*
X867600Y100617D01*
X868017Y100117D01*
X868517Y99783D01*
X869100Y99700D01*
X869683Y99867D01*
X870267Y100367D01*
G01X873033Y99700D02*
Y103033D01*
G01Y102200D02*
X873367Y102617D01*
X873867Y102950D01*
X874533Y103033D01*
X875117Y102950D01*
X875617Y102617D01*
X875867Y102033D01*
Y99700D01*
G01X885650D02*
Y104700D01*
G01X892750Y99700D02*
Y103033D01*
G01Y102450D02*
X892417Y102783D01*
X891917Y102950D01*
X891333Y103033D01*
X890750Y102867D01*
X890250Y102533D01*
X889917Y102033D01*
X889750Y101367D01*
X889917Y100700D01*
X890250Y100200D01*
X890750Y99867D01*
X891333Y99700D01*
X891917Y99783D01*
X892417Y100033D01*
X892750Y100367D01*
G01X895100Y98200D02*
X895600Y98033D01*
X896267Y98200D01*
X896683Y98533D01*
X897017Y98950D01*
X897517Y100283D01*
X898600Y103033D01*
G01X895933D02*
X897517Y100283D01*
G01X901200Y101950D02*
X903867D01*
X903617Y102533D01*
X903200Y102867D01*
X902617Y103033D01*
X902033Y102950D01*
X901533Y102700D01*
X901200Y102117D01*
X901033Y101617D01*
Y101117D01*
X901200Y100617D01*
X901617Y100117D01*
X902117Y99783D01*
X902700Y99700D01*
X903283Y99867D01*
X903867Y100367D01*
G01X906883Y99700D02*
Y103033D01*
G01Y102367D02*
X907300Y102700D01*
X907717Y102950D01*
X908300Y103033D01*
X908717Y102950D01*
X909217Y102700D01*
G01X776983Y116310D02*
Y111310D01*
X780317D01*
G01X782833D02*
Y114643D01*
G01Y113810D02*
X783167Y114227D01*
X783667Y114560D01*
X784333Y114643D01*
X784917Y114560D01*
X785417Y114227D01*
X785667Y113643D01*
Y111310D01*
G01X789850Y111143D02*
X789683Y111227D01*
Y111393D01*
X789850Y111477D01*
X790017Y111393D01*
Y111227D01*
X789850Y111143D01*
G01Y113393D02*
X789683Y113477D01*
Y113643D01*
X789850Y113727D01*
X790017Y113643D01*
Y113477D01*
X789850Y113393D01*
G01X802383Y114227D02*
X801800Y114560D01*
X801300Y114643D01*
X800633Y114477D01*
X800133Y114143D01*
X799800Y113560D01*
X799717Y112977D01*
X799800Y112393D01*
X800133Y111893D01*
X800633Y111477D01*
X801300Y111310D01*
X801883Y111477D01*
X802383Y111810D01*
G01X808150Y111310D02*
Y114643D01*
G01Y114060D02*
X807817Y114393D01*
X807317Y114560D01*
X806733Y114643D01*
X806150Y114477D01*
X805650Y114143D01*
X805317Y113643D01*
X805150Y112977D01*
X805317Y112310D01*
X805650Y111810D01*
X806150Y111477D01*
X806733Y111310D01*
X807317Y111393D01*
X807817Y111643D01*
X808150Y111977D01*
G01X810833Y111310D02*
Y114643D01*
G01Y113810D02*
X811167Y114227D01*
X811667Y114560D01*
X812333Y114643D01*
X812917Y114560D01*
X813417Y114227D01*
X813667Y113643D01*
Y111310D01*
G01X817850Y114643D02*
X818683Y115685D01*
Y116310D01*
X818058D01*
Y115685D01*
X818683D01*
G01X823450Y116310D02*
Y111310D01*
G01X822283Y114643D02*
X824617D01*
G01X833150Y111310D02*
Y116310D01*
G01Y113810D02*
X833567Y114310D01*
X834067Y114560D01*
X834567Y114643D01*
X835317Y114477D01*
X835817Y114143D01*
X836150Y113560D01*
Y112893D01*
X835983Y112227D01*
X835650Y111727D01*
X835067Y111393D01*
X834567Y111310D01*
X834067Y111393D01*
X833567Y111643D01*
X833150Y112060D01*
G01X839000Y113560D02*
X841667D01*
X841417Y114143D01*
X841000Y114477D01*
X840417Y114643D01*
X839833Y114560D01*
X839333Y114310D01*
X839000Y113727D01*
X838833Y113227D01*
Y112727D01*
X839000Y112227D01*
X839417Y111727D01*
X839917Y111393D01*
X840500Y111310D01*
X841083Y111477D01*
X841667Y111977D01*
G01X849950Y111310D02*
Y116310D01*
G01Y113810D02*
X850367Y114310D01*
X850867Y114560D01*
X851367Y114643D01*
X852117Y114477D01*
X852617Y114143D01*
X852950Y113560D01*
Y112893D01*
X852783Y112227D01*
X852450Y111727D01*
X851867Y111393D01*
X851367Y111310D01*
X850867Y111393D01*
X850367Y111643D01*
X849950Y112060D01*
G01X855883Y111310D02*
Y114643D01*
G01Y113977D02*
X856300Y114310D01*
X856717Y114560D01*
X857300Y114643D01*
X857717Y114560D01*
X858217Y114310D01*
G01X862650Y111310D02*
X862150Y111393D01*
X861650Y111727D01*
X861317Y112310D01*
X861150Y112977D01*
X861317Y113643D01*
X861650Y114227D01*
X862150Y114560D01*
X862650Y114643D01*
X863150Y114560D01*
X863650Y114227D01*
X863983Y113643D01*
X864067Y112977D01*
X863983Y112310D01*
X863650Y111727D01*
X863150Y111393D01*
X862650Y111310D01*
G01X866833D02*
Y116310D01*
G01X869500Y114643D02*
X866833Y112727D01*
G01X867917Y113477D02*
X869667Y111310D01*
G01X872600Y113560D02*
X875267D01*
X875017Y114143D01*
X874600Y114477D01*
X874017Y114643D01*
X873433Y114560D01*
X872933Y114310D01*
X872600Y113727D01*
X872433Y113227D01*
Y112727D01*
X872600Y112227D01*
X873017Y111727D01*
X873517Y111393D01*
X874100Y111310D01*
X874683Y111477D01*
X875267Y111977D01*
G01X878033Y111310D02*
Y114643D01*
G01Y113810D02*
X878367Y114227D01*
X878867Y114560D01*
X879533Y114643D01*
X880117Y114560D01*
X880617Y114227D01*
X880867Y113643D01*
Y111310D01*
G01X890650D02*
Y116310D01*
G01X897750Y111310D02*
Y114643D01*
G01Y114060D02*
X897417Y114393D01*
X896917Y114560D01*
X896333Y114643D01*
X895750Y114477D01*
X895250Y114143D01*
X894917Y113643D01*
X894750Y112977D01*
X894917Y112310D01*
X895250Y111810D01*
X895750Y111477D01*
X896333Y111310D01*
X896917Y111393D01*
X897417Y111643D01*
X897750Y111977D01*
G01X900100Y109810D02*
X900600Y109643D01*
X901267Y109810D01*
X901683Y110143D01*
X902017Y110560D01*
X902517Y111893D01*
X903600Y114643D01*
G01X900933D02*
X902517Y111893D01*
G01X906200Y113560D02*
X908867D01*
X908617Y114143D01*
X908200Y114477D01*
X907617Y114643D01*
X907033Y114560D01*
X906533Y114310D01*
X906200Y113727D01*
X906033Y113227D01*
Y112727D01*
X906200Y112227D01*
X906617Y111727D01*
X907117Y111393D01*
X907700Y111310D01*
X908283Y111477D01*
X908867Y111977D01*
G01X911883Y111310D02*
Y114643D01*
G01Y113977D02*
X912300Y114310D01*
X912717Y114560D01*
X913300Y114643D01*
X913717Y114560D01*
X914217Y114310D01*
G01X713000Y85500D02*
X1343000D01*
G01X777167Y123000D02*
Y128000D01*
X778833D01*
X779500Y127750D01*
X780000Y127417D01*
X780417Y126917D01*
X780750Y126333D01*
X780833Y125500D01*
X780750Y124667D01*
X780417Y124083D01*
X780000Y123583D01*
X779500Y123250D01*
X778833Y123000D01*
X777167D01*
G01X783433D02*
Y126333D01*
G01Y125667D02*
X783850Y126000D01*
X784267Y126250D01*
X784850Y126333D01*
X785267Y126250D01*
X785767Y126000D01*
G01X790200Y126333D02*
Y123000D01*
G01Y127667D02*
X790033Y127750D01*
Y127917D01*
X790200Y128000D01*
X790367Y127917D01*
Y127750D01*
X790200Y127667D01*
G01X795800Y123000D02*
Y128000D01*
G01X801400Y123000D02*
Y128000D01*
G01X811017Y123000D02*
Y128000D01*
X814183D01*
G01X813017Y125583D02*
X811017D01*
G01X817033Y123000D02*
Y126333D01*
G01Y125667D02*
X817450Y126000D01*
X817867Y126250D01*
X818450Y126333D01*
X818867Y126250D01*
X819367Y126000D01*
G01X823800Y123000D02*
X823300Y123083D01*
X822800Y123417D01*
X822467Y124000D01*
X822300Y124667D01*
X822467Y125333D01*
X822800Y125917D01*
X823300Y126250D01*
X823800Y126333D01*
X824300Y126250D01*
X824800Y125917D01*
X825133Y125333D01*
X825217Y124667D01*
X825133Y124000D01*
X824800Y123417D01*
X824300Y123083D01*
X823800Y123000D01*
G01X826900D02*
Y126333D01*
G01Y125417D02*
X827150Y125833D01*
X827567Y126167D01*
X828150Y126333D01*
X828733Y126167D01*
X829150Y125833D01*
X829400Y125417D01*
Y123000D01*
G01Y125417D02*
X829650Y125833D01*
X830067Y126167D01*
X830650Y126333D01*
X831233Y126167D01*
X831650Y125833D01*
X831900Y125333D01*
Y123000D01*
G01X838933Y128000D02*
Y123000D01*
X842267D01*
G01X846200D02*
Y128000D01*
X845200Y127000D01*
G01Y123000D02*
X847200D01*
G01X856983Y121333D02*
X856150Y122167D01*
X855733Y123000D01*
Y126333D01*
X856150Y127167D01*
X856983Y128000D01*
G01X863000D02*
Y123000D01*
G01X861083Y128000D02*
X864917D01*
G01X868600Y123000D02*
X867933Y123083D01*
X867350Y123417D01*
X866850Y123917D01*
X866517Y124500D01*
X866350Y125167D01*
Y125833D01*
X866517Y126500D01*
X866850Y127083D01*
X867350Y127583D01*
X867933Y127917D01*
X868600Y128000D01*
X869267Y127917D01*
X869850Y127583D01*
X870350Y127083D01*
X870683Y126500D01*
X870850Y125833D01*
Y125167D01*
X870683Y124500D01*
X870350Y123917D01*
X869850Y123417D01*
X869267Y123083D01*
X868600Y123000D01*
G01X872533D02*
Y128000D01*
X874533D01*
X875200Y127750D01*
X875700Y127167D01*
X875867Y126500D01*
X875700Y125833D01*
X875283Y125333D01*
X874533Y125083D01*
X872533D01*
G01X880217Y121333D02*
X881050Y122167D01*
X881467Y123000D01*
Y126333D01*
X881050Y127167D01*
X880217Y128000D01*
G01X891000D02*
Y123000D01*
G01X889833Y126333D02*
X892167D01*
G01X896600Y123000D02*
X896100Y123083D01*
X895600Y123417D01*
X895267Y124000D01*
X895100Y124667D01*
X895267Y125333D01*
X895600Y125917D01*
X896100Y126250D01*
X896600Y126333D01*
X897100Y126250D01*
X897600Y125917D01*
X897933Y125333D01*
X898017Y124667D01*
X897933Y124000D01*
X897600Y123417D01*
X897100Y123083D01*
X896600Y123000D01*
G01X906133Y128000D02*
Y123000D01*
X909467D01*
G01X912150Y126333D02*
X914650Y123000D01*
G01Y126333D02*
X912150Y123000D01*
G01X725500Y349500D02*
Y354500D01*
X722417Y350917D01*
X726583D01*
G01X730100Y349333D02*
X729933Y349417D01*
Y349583D01*
X730100Y349667D01*
X730267Y349583D01*
Y349417D01*
X730100Y349333D01*
G01X739800Y349500D02*
Y354500D01*
G01Y352000D02*
X740217Y352500D01*
X740717Y352750D01*
X741217Y352833D01*
X741967Y352667D01*
X742467Y352333D01*
X742800Y351750D01*
Y351083D01*
X742633Y350417D01*
X742300Y349917D01*
X741717Y349583D01*
X741217Y349500D01*
X740717Y349583D01*
X740217Y349833D01*
X739800Y350250D01*
G01X748400Y349500D02*
Y352833D01*
G01Y352250D02*
X748067Y352583D01*
X747567Y352750D01*
X746983Y352833D01*
X746400Y352667D01*
X745900Y352333D01*
X745567Y351833D01*
X745400Y351167D01*
X745567Y350500D01*
X745900Y350000D01*
X746400Y349667D01*
X746983Y349500D01*
X747567Y349583D01*
X748067Y349833D01*
X748400Y350167D01*
G01X753833Y352417D02*
X753250Y352750D01*
X752750Y352833D01*
X752083Y352667D01*
X751583Y352333D01*
X751250Y351750D01*
X751167Y351167D01*
X751250Y350583D01*
X751583Y350083D01*
X752083Y349667D01*
X752750Y349500D01*
X753333Y349667D01*
X753833Y350000D01*
G01X756683Y349500D02*
Y354500D01*
G01X759350Y352833D02*
X756683Y350917D01*
G01X757767Y351667D02*
X759517Y349500D01*
G01X765200Y354500D02*
Y349500D01*
G01Y350250D02*
X764867Y349833D01*
X764367Y349583D01*
X763783Y349500D01*
X763117Y349667D01*
X762617Y350083D01*
X762283Y350583D01*
X762200Y351167D01*
X762283Y351750D01*
X762617Y352250D01*
X763117Y352667D01*
X763783Y352833D01*
X764367Y352750D01*
X764783Y352583D01*
X765200Y352250D01*
G01X768133Y349500D02*
Y352833D01*
G01Y352167D02*
X768550Y352500D01*
X768967Y352750D01*
X769550Y352833D01*
X769967Y352750D01*
X770467Y352500D01*
G01X774900Y352833D02*
Y349500D01*
G01Y354167D02*
X774733Y354250D01*
Y354417D01*
X774900Y354500D01*
X775067Y354417D01*
Y354250D01*
X774900Y354167D01*
G01X780500Y349500D02*
Y354500D01*
G01X786100Y349500D02*
Y354500D01*
G01X798800Y349500D02*
Y352833D01*
G01Y352250D02*
X798467Y352583D01*
X797967Y352750D01*
X797383Y352833D01*
X796800Y352667D01*
X796300Y352333D01*
X795967Y351833D01*
X795800Y351167D01*
X795967Y350500D01*
X796300Y350000D01*
X796800Y349667D01*
X797383Y349500D01*
X797967Y349583D01*
X798467Y349833D01*
X798800Y350167D01*
G01X801483Y349500D02*
Y352833D01*
G01Y352000D02*
X801817Y352417D01*
X802317Y352750D01*
X802983Y352833D01*
X803567Y352750D01*
X804067Y352417D01*
X804317Y351833D01*
Y349500D01*
G01X810000Y354500D02*
Y349500D01*
G01Y350250D02*
X809667Y349833D01*
X809167Y349583D01*
X808583Y349500D01*
X807917Y349667D01*
X807417Y350083D01*
X807083Y350583D01*
X807000Y351167D01*
X807083Y351750D01*
X807417Y352250D01*
X807917Y352667D01*
X808583Y352833D01*
X809167Y352750D01*
X809583Y352583D01*
X810000Y352250D01*
G01X818450Y350083D02*
X818867Y349750D01*
X819450Y349500D01*
X819950D01*
X820450Y349667D01*
X820783Y349917D01*
X820950Y350250D01*
X820867Y350750D01*
X820533Y351000D01*
X819033Y351500D01*
X818700Y352083D01*
X818867Y352500D01*
X819200Y352750D01*
X819700Y352833D01*
X820200Y352750D01*
X820700Y352500D01*
G01X826800Y347833D02*
Y352833D01*
G01Y352083D02*
X826383Y352500D01*
X825883Y352750D01*
X825300Y352833D01*
X824800Y352750D01*
X824217Y352333D01*
X823883Y351750D01*
X823800Y351167D01*
X823883Y350583D01*
X824217Y350000D01*
X824800Y349583D01*
X825300Y349500D01*
X825883Y349583D01*
X826383Y349833D01*
X826800Y350250D01*
G01X829483Y352833D02*
Y350500D01*
X829817Y349917D01*
X830317Y349583D01*
X830900Y349500D01*
X831483Y349583D01*
X831983Y349917D01*
X832317Y350500D01*
G01Y349500D02*
Y352833D01*
G01X838000Y349500D02*
Y352833D01*
G01Y352250D02*
X837667Y352583D01*
X837167Y352750D01*
X836583Y352833D01*
X836000Y352667D01*
X835500Y352333D01*
X835167Y351833D01*
X835000Y351167D01*
X835167Y350500D01*
X835500Y350000D01*
X836000Y349667D01*
X836583Y349500D01*
X837167Y349583D01*
X837667Y349833D01*
X838000Y350167D01*
G01X840933Y349500D02*
Y352833D01*
G01Y352167D02*
X841350Y352500D01*
X841767Y352750D01*
X842350Y352833D01*
X842767Y352750D01*
X843267Y352500D01*
G01X846450Y351750D02*
X849117D01*
X848867Y352333D01*
X848450Y352667D01*
X847867Y352833D01*
X847283Y352750D01*
X846783Y352500D01*
X846450Y351917D01*
X846283Y351417D01*
Y350917D01*
X846450Y350417D01*
X846867Y349917D01*
X847367Y349583D01*
X847950Y349500D01*
X848533Y349667D01*
X849117Y350167D01*
G01X857483Y349500D02*
Y354500D01*
G01Y352083D02*
X857900Y352500D01*
X858317Y352750D01*
X858983Y352833D01*
X859483Y352750D01*
X860067Y352417D01*
X860317Y351917D01*
Y349500D01*
G01X864500D02*
X864000Y349583D01*
X863500Y349917D01*
X863167Y350500D01*
X863000Y351167D01*
X863167Y351833D01*
X863500Y352417D01*
X864000Y352750D01*
X864500Y352833D01*
X865000Y352750D01*
X865500Y352417D01*
X865833Y351833D01*
X865917Y351167D01*
X865833Y350500D01*
X865500Y349917D01*
X865000Y349583D01*
X864500Y349500D01*
G01X870100D02*
Y354500D01*
G01X874450Y351750D02*
X877117D01*
X876867Y352333D01*
X876450Y352667D01*
X875867Y352833D01*
X875283Y352750D01*
X874783Y352500D01*
X874450Y351917D01*
X874283Y351417D01*
Y350917D01*
X874450Y350417D01*
X874867Y349917D01*
X875367Y349583D01*
X875950Y349500D01*
X876533Y349667D01*
X877117Y350167D01*
G01X881300Y349333D02*
X881133Y349417D01*
Y349583D01*
X881300Y349667D01*
X881467Y349583D01*
Y349417D01*
X881300Y349333D01*
G01Y351583D02*
X881133Y351667D01*
Y351833D01*
X881300Y351917D01*
X881467Y351833D01*
Y351667D01*
X881300Y351583D01*
G01X713000Y335500D02*
X1343000D01*
G01X721407Y374673D02*
X725073Y378340D01*
G01X723240Y379007D02*
Y374007D01*
G01X725073Y374673D02*
X721407Y378340D01*
G01X720740Y376507D02*
X725740D01*
G01X728423Y373173D02*
X727590Y374007D01*
X727173Y374840D01*
Y378173D01*
X727590Y379007D01*
X728423Y379840D01*
G01X732607Y375590D02*
X733107Y375173D01*
X733690Y374923D01*
X734440Y374840D01*
X735190Y375007D01*
X735773Y375340D01*
X736190Y375923D01*
X736273Y376590D01*
X736107Y377257D01*
X735690Y377673D01*
X735107Y378007D01*
X734523Y378090D01*
X733940Y378007D01*
X733190Y377673D01*
X733440Y379840D01*
X735690D01*
G01X740040Y374673D02*
X739873Y374757D01*
Y374923D01*
X740040Y375007D01*
X740207Y374923D01*
Y374757D01*
X740040Y374673D01*
G01X745640Y374840D02*
Y379840D01*
X744640Y378840D01*
G01Y374840D02*
X746640D01*
G01X751657Y373173D02*
X752490Y374007D01*
X752907Y374840D01*
Y378173D01*
X752490Y379007D01*
X751657Y379840D01*
G01X721107Y408303D02*
X724773Y411970D01*
G01X722940Y412637D02*
Y407637D01*
G01X724773Y408303D02*
X721107Y411970D01*
G01X720440Y410137D02*
X725440D01*
G01X728123Y406803D02*
X727290Y407637D01*
X726873Y408470D01*
Y411803D01*
X727290Y412637D01*
X728123Y413470D01*
G01X732307Y409220D02*
X732807Y408803D01*
X733390Y408553D01*
X734140Y408470D01*
X734890Y408637D01*
X735473Y408970D01*
X735890Y409553D01*
X735973Y410220D01*
X735807Y410887D01*
X735390Y411303D01*
X734807Y411637D01*
X734223Y411720D01*
X733640Y411637D01*
X732890Y411303D01*
X733140Y413470D01*
X735390D01*
G01X739740Y408303D02*
X739573Y408387D01*
Y408553D01*
X739740Y408637D01*
X739907Y408553D01*
Y408387D01*
X739740Y408303D01*
G01X745340Y408470D02*
Y413470D01*
X744340Y412470D01*
G01Y408470D02*
X746340D01*
G01X751357Y406803D02*
X752190Y407637D01*
X752607Y408470D01*
Y411803D01*
X752190Y412637D01*
X751357Y413470D01*
G01X721217Y391740D02*
X723300Y386740D01*
X725383Y391740D01*
G01X728900Y390073D02*
Y386740D01*
G01Y391407D02*
X728733Y391490D01*
Y391657D01*
X728900Y391740D01*
X729067Y391657D01*
Y391490D01*
X728900Y391407D01*
G01X736000Y386740D02*
Y390073D01*
G01Y389490D02*
X735667Y389823D01*
X735167Y389990D01*
X734583Y390073D01*
X734000Y389907D01*
X733500Y389573D01*
X733167Y389073D01*
X733000Y388407D01*
X733167Y387740D01*
X733500Y387240D01*
X734000Y386907D01*
X734583Y386740D01*
X735167Y386823D01*
X735667Y387073D01*
X736000Y387407D01*
G01X744700Y391740D02*
X746700D01*
G01X745700D02*
Y386740D01*
G01X744700D02*
X746700D01*
G01X749883D02*
Y390073D01*
G01Y389240D02*
X750217Y389657D01*
X750717Y389990D01*
X751383Y390073D01*
X751967Y389990D01*
X752467Y389657D01*
X752717Y389073D01*
Y386740D01*
G01X760833D02*
Y391740D01*
X762833D01*
X763500Y391490D01*
X764000Y390907D01*
X764167Y390240D01*
X764000Y389573D01*
X763583Y389073D01*
X762833Y388823D01*
X760833D01*
G01X769600Y386740D02*
Y390073D01*
G01Y389490D02*
X769267Y389823D01*
X768767Y389990D01*
X768183Y390073D01*
X767600Y389907D01*
X767100Y389573D01*
X766767Y389073D01*
X766600Y388407D01*
X766767Y387740D01*
X767100Y387240D01*
X767600Y386907D01*
X768183Y386740D01*
X768767Y386823D01*
X769267Y387073D01*
X769600Y387407D01*
G01X775200Y391740D02*
Y386740D01*
G01Y387490D02*
X774867Y387073D01*
X774367Y386823D01*
X773783Y386740D01*
X773117Y386907D01*
X772617Y387323D01*
X772283Y387823D01*
X772200Y388407D01*
X772283Y388990D01*
X772617Y389490D01*
X773117Y389907D01*
X773783Y390073D01*
X774367Y389990D01*
X774783Y389823D01*
X775200Y389490D01*
G01X778883Y385073D02*
X778050Y385907D01*
X777633Y386740D01*
Y390073D01*
X778050Y390907D01*
X778883Y391740D01*
G01X782817D02*
X784900Y386740D01*
X786983Y391740D01*
G01X789500D02*
X791500D01*
G01X790500D02*
Y386740D01*
G01X789500D02*
X791500D01*
G01X794433D02*
Y391740D01*
X796433D01*
X797100Y391490D01*
X797600Y390907D01*
X797767Y390240D01*
X797600Y389573D01*
X797183Y389073D01*
X796433Y388823D01*
X794433D01*
G01X802117Y385073D02*
X802950Y385907D01*
X803367Y386740D01*
Y390073D01*
X802950Y390907D01*
X802117Y391740D01*
G01X720917Y424500D02*
X723000Y419500D01*
X725083Y424500D01*
G01X728600Y422833D02*
Y419500D01*
G01Y424167D02*
X728433Y424250D01*
Y424417D01*
X728600Y424500D01*
X728767Y424417D01*
Y424250D01*
X728600Y424167D01*
G01X735700Y419500D02*
Y422833D01*
G01Y422250D02*
X735367Y422583D01*
X734867Y422750D01*
X734283Y422833D01*
X733700Y422667D01*
X733200Y422333D01*
X732867Y421833D01*
X732700Y421167D01*
X732867Y420500D01*
X733200Y420000D01*
X733700Y419667D01*
X734283Y419500D01*
X734867Y419583D01*
X735367Y419833D01*
X735700Y420167D01*
G01X745400Y419500D02*
X744733Y419583D01*
X744150Y419917D01*
X743650Y420417D01*
X743317Y421000D01*
X743150Y421667D01*
Y422333D01*
X743317Y423000D01*
X743650Y423583D01*
X744150Y424083D01*
X744733Y424417D01*
X745400Y424500D01*
X746067Y424417D01*
X746650Y424083D01*
X747150Y423583D01*
X747483Y423000D01*
X747650Y422333D01*
Y421667D01*
X747483Y421000D01*
X747150Y420417D01*
X746650Y419917D01*
X746067Y419583D01*
X745400Y419500D01*
G01X749583D02*
Y422833D01*
G01Y422000D02*
X749917Y422417D01*
X750417Y422750D01*
X751083Y422833D01*
X751667Y422750D01*
X752167Y422417D01*
X752417Y421833D01*
Y419500D01*
G01X760533D02*
Y424500D01*
X762533D01*
X763200Y424250D01*
X763700Y423667D01*
X763867Y423000D01*
X763700Y422333D01*
X763283Y421833D01*
X762533Y421583D01*
X760533D01*
G01X769300Y419500D02*
Y422833D01*
G01Y422250D02*
X768967Y422583D01*
X768467Y422750D01*
X767883Y422833D01*
X767300Y422667D01*
X766800Y422333D01*
X766467Y421833D01*
X766300Y421167D01*
X766467Y420500D01*
X766800Y420000D01*
X767300Y419667D01*
X767883Y419500D01*
X768467Y419583D01*
X768967Y419833D01*
X769300Y420167D01*
G01X774900Y424500D02*
Y419500D01*
G01Y420250D02*
X774567Y419833D01*
X774067Y419583D01*
X773483Y419500D01*
X772817Y419667D01*
X772317Y420083D01*
X771983Y420583D01*
X771900Y421167D01*
X771983Y421750D01*
X772317Y422250D01*
X772817Y422667D01*
X773483Y422833D01*
X774067Y422750D01*
X774483Y422583D01*
X774900Y422250D01*
G01X778583Y417833D02*
X777750Y418667D01*
X777333Y419500D01*
Y422833D01*
X777750Y423667D01*
X778583Y424500D01*
G01X782517D02*
X784600Y419500D01*
X786683Y424500D01*
G01X790200Y419500D02*
X789533Y419583D01*
X788950Y419917D01*
X788450Y420417D01*
X788117Y421000D01*
X787950Y421667D01*
Y422333D01*
X788117Y423000D01*
X788450Y423583D01*
X788950Y424083D01*
X789533Y424417D01*
X790200Y424500D01*
X790867Y424417D01*
X791450Y424083D01*
X791950Y423583D01*
X792283Y423000D01*
X792450Y422333D01*
Y421667D01*
X792283Y421000D01*
X791950Y420417D01*
X791450Y419917D01*
X790867Y419583D01*
X790200Y419500D01*
G01X794133D02*
Y424500D01*
X796133D01*
X796800Y424250D01*
X797300Y423667D01*
X797467Y423000D01*
X797300Y422333D01*
X796883Y421833D01*
X796133Y421583D01*
X794133D01*
G01X801817Y417833D02*
X802650Y418667D01*
X803067Y419500D01*
Y422833D01*
X802650Y423667D01*
X801817Y424500D01*
G01X723667Y443167D02*
X724000Y443417D01*
X724250Y443833D01*
X724417Y444417D01*
X724250Y444917D01*
X723917Y445250D01*
X723333Y445500D01*
X721083D01*
Y440500D01*
X723833D01*
X724417Y440833D01*
X724750Y441333D01*
X724917Y441917D01*
X724750Y442500D01*
X724250Y443000D01*
X723667Y443167D01*
X721083D01*
G01X727183Y443833D02*
Y441500D01*
X727517Y440917D01*
X728017Y440583D01*
X728600Y440500D01*
X729183Y440583D01*
X729683Y440917D01*
X730017Y441500D01*
G01Y440500D02*
Y443833D01*
G01X733033Y440500D02*
Y443833D01*
G01Y443167D02*
X733450Y443500D01*
X733867Y443750D01*
X734450Y443833D01*
X734867Y443750D01*
X735367Y443500D01*
G01X739800Y443833D02*
Y440500D01*
G01Y445167D02*
X739633Y445250D01*
Y445417D01*
X739800Y445500D01*
X739967Y445417D01*
Y445250D01*
X739800Y445167D01*
G01X744150Y442750D02*
X746817D01*
X746567Y443333D01*
X746150Y443667D01*
X745567Y443833D01*
X744983Y443750D01*
X744483Y443500D01*
X744150Y442917D01*
X743983Y442417D01*
Y441917D01*
X744150Y441417D01*
X744567Y440917D01*
X745067Y440583D01*
X745650Y440500D01*
X746233Y440667D01*
X746817Y441167D01*
G01X752500Y445500D02*
Y440500D01*
G01Y441250D02*
X752167Y440833D01*
X751667Y440583D01*
X751083Y440500D01*
X750417Y440667D01*
X749917Y441083D01*
X749583Y441583D01*
X749500Y442167D01*
X749583Y442750D01*
X749917Y443250D01*
X750417Y443667D01*
X751083Y443833D01*
X751667Y443750D01*
X752083Y443583D01*
X752500Y443250D01*
G01X760783Y440500D02*
Y445500D01*
G01Y443083D02*
X761200Y443500D01*
X761617Y443750D01*
X762283Y443833D01*
X762783Y443750D01*
X763367Y443417D01*
X763617Y442917D01*
Y440500D01*
G01X767800D02*
X767300Y440583D01*
X766800Y440917D01*
X766467Y441500D01*
X766300Y442167D01*
X766467Y442833D01*
X766800Y443417D01*
X767300Y443750D01*
X767800Y443833D01*
X768300Y443750D01*
X768800Y443417D01*
X769133Y442833D01*
X769217Y442167D01*
X769133Y441500D01*
X768800Y440917D01*
X768300Y440583D01*
X767800Y440500D01*
G01X773400D02*
Y445500D01*
G01X777750Y442750D02*
X780417D01*
X780167Y443333D01*
X779750Y443667D01*
X779167Y443833D01*
X778583Y443750D01*
X778083Y443500D01*
X777750Y442917D01*
X777583Y442417D01*
Y441917D01*
X777750Y441417D01*
X778167Y440917D01*
X778667Y440583D01*
X779250Y440500D01*
X779833Y440667D01*
X780417Y441167D01*
G01X713000Y365500D02*
X1343000D01*
G01X713000Y400500D02*
X1343000D01*
G01X713000Y435500D02*
X1343000D01*
G01X721417Y461500D02*
Y466500D01*
X724583D01*
G01X723417Y464083D02*
X721417D01*
G01X727183Y464833D02*
Y462500D01*
X727517Y461917D01*
X728017Y461583D01*
X728600Y461500D01*
X729183Y461583D01*
X729683Y461917D01*
X730017Y462500D01*
G01Y461500D02*
Y464833D01*
G01X734200Y461500D02*
Y466500D01*
G01X739800Y461500D02*
Y466500D01*
G01X749500Y459833D02*
Y464833D01*
G01Y464083D02*
X749917Y464500D01*
X750333Y464750D01*
X751000Y464833D01*
X751583Y464750D01*
X752167Y464333D01*
X752417Y463750D01*
X752500Y463167D01*
X752417Y462583D01*
X752167Y462000D01*
X751667Y461667D01*
X751000Y461500D01*
X750417Y461583D01*
X749833Y461833D01*
X749500Y462167D01*
G01X756600Y461500D02*
Y466500D01*
G01X760783Y464833D02*
Y462500D01*
X761117Y461917D01*
X761617Y461583D01*
X762200Y461500D01*
X762783Y461583D01*
X763283Y461917D01*
X763617Y462500D01*
G01Y461500D02*
Y464833D01*
G01X766633Y460250D02*
X767217Y459917D01*
X767883Y459833D01*
X768467Y459917D01*
X768967Y460333D01*
X769300Y460917D01*
Y464833D01*
G01Y464167D02*
X768967Y464500D01*
X768467Y464750D01*
X767883Y464833D01*
X767217Y464667D01*
X766800Y464333D01*
X766467Y463750D01*
X766300Y463167D01*
X766383Y462667D01*
X766717Y462083D01*
X767217Y461667D01*
X767883Y461500D01*
X768383Y461583D01*
X768967Y461917D01*
X769300Y462250D01*
G01X772233Y460250D02*
X772817Y459917D01*
X773483Y459833D01*
X774067Y459917D01*
X774567Y460333D01*
X774900Y460917D01*
Y464833D01*
G01Y464167D02*
X774567Y464500D01*
X774067Y464750D01*
X773483Y464833D01*
X772817Y464667D01*
X772400Y464333D01*
X772067Y463750D01*
X771900Y463167D01*
X771983Y462667D01*
X772317Y462083D01*
X772817Y461667D01*
X773483Y461500D01*
X773983Y461583D01*
X774567Y461917D01*
X774900Y462250D01*
G01X779000Y464833D02*
Y461500D01*
G01Y466167D02*
X778833Y466250D01*
Y466417D01*
X779000Y466500D01*
X779167Y466417D01*
Y466250D01*
X779000Y466167D01*
G01X783183Y461500D02*
Y464833D01*
G01Y464000D02*
X783517Y464417D01*
X784017Y464750D01*
X784683Y464833D01*
X785267Y464750D01*
X785767Y464417D01*
X786017Y463833D01*
Y461500D01*
G01X789033Y460250D02*
X789617Y459917D01*
X790283Y459833D01*
X790867Y459917D01*
X791367Y460333D01*
X791700Y460917D01*
Y464833D01*
G01Y464167D02*
X791367Y464500D01*
X790867Y464750D01*
X790283Y464833D01*
X789617Y464667D01*
X789200Y464333D01*
X788867Y463750D01*
X788700Y463167D01*
X788783Y462667D01*
X789117Y462083D01*
X789617Y461667D01*
X790283Y461500D01*
X790783Y461583D01*
X791367Y461917D01*
X791700Y462250D01*
G01X721250Y530000D02*
Y535000D01*
G01X724750D02*
Y530000D01*
G01Y532500D02*
X721250D01*
G01X730100Y530000D02*
Y533333D01*
G01Y532750D02*
X729767Y533083D01*
X729267Y533250D01*
X728683Y533333D01*
X728100Y533167D01*
X727600Y532833D01*
X727267Y532333D01*
X727100Y531667D01*
X727267Y531000D01*
X727600Y530500D01*
X728100Y530167D01*
X728683Y530000D01*
X729267Y530083D01*
X729767Y530333D01*
X730100Y530667D01*
G01X734200Y530000D02*
Y535000D01*
G01X739300Y530000D02*
Y534250D01*
X739467Y534667D01*
X739800Y534917D01*
X740300Y535000D01*
X740800Y534833D01*
X741050Y534417D01*
G01X740050Y533000D02*
X738383D01*
G01X749333Y530000D02*
Y535000D01*
X751333D01*
X752000Y534750D01*
X752500Y534167D01*
X752667Y533500D01*
X752500Y532833D01*
X752083Y532333D01*
X751333Y532083D01*
X749333D01*
G01X756600Y530000D02*
Y535000D01*
G01X760783Y533333D02*
Y531000D01*
X761117Y530417D01*
X761617Y530083D01*
X762200Y530000D01*
X762783Y530083D01*
X763283Y530417D01*
X763617Y531000D01*
G01Y530000D02*
Y533333D01*
G01X766633Y528750D02*
X767217Y528417D01*
X767883Y528333D01*
X768467Y528417D01*
X768967Y528833D01*
X769300Y529417D01*
Y533333D01*
G01Y532667D02*
X768967Y533000D01*
X768467Y533250D01*
X767883Y533333D01*
X767217Y533167D01*
X766800Y532833D01*
X766467Y532250D01*
X766300Y531667D01*
X766383Y531167D01*
X766717Y530583D01*
X767217Y530167D01*
X767883Y530000D01*
X768383Y530083D01*
X768967Y530417D01*
X769300Y530750D01*
G01X772233Y528750D02*
X772817Y528417D01*
X773483Y528333D01*
X774067Y528417D01*
X774567Y528833D01*
X774900Y529417D01*
Y533333D01*
G01Y532667D02*
X774567Y533000D01*
X774067Y533250D01*
X773483Y533333D01*
X772817Y533167D01*
X772400Y532833D01*
X772067Y532250D01*
X771900Y531667D01*
X771983Y531167D01*
X772317Y530583D01*
X772817Y530167D01*
X773483Y530000D01*
X773983Y530083D01*
X774567Y530417D01*
X774900Y530750D01*
G01X779000Y533333D02*
Y530000D01*
G01Y534667D02*
X778833Y534750D01*
Y534917D01*
X779000Y535000D01*
X779167Y534917D01*
Y534750D01*
X779000Y534667D01*
G01X783183Y530000D02*
Y533333D01*
G01Y532500D02*
X783517Y532917D01*
X784017Y533250D01*
X784683Y533333D01*
X785267Y533250D01*
X785767Y532917D01*
X786017Y532333D01*
Y530000D01*
G01X789033Y528750D02*
X789617Y528417D01*
X790283Y528333D01*
X790867Y528417D01*
X791367Y528833D01*
X791700Y529417D01*
Y533333D01*
G01Y532667D02*
X791367Y533000D01*
X790867Y533250D01*
X790283Y533333D01*
X789617Y533167D01*
X789200Y532833D01*
X788867Y532250D01*
X788700Y531667D01*
X788783Y531167D01*
X789117Y530583D01*
X789617Y530167D01*
X790283Y530000D01*
X790783Y530083D01*
X791367Y530417D01*
X791700Y530750D01*
G01X713000Y450500D02*
X1343000D01*
G01X713000Y477500D02*
X1343000D01*
G01X722833Y589000D02*
Y594000D01*
X724833D01*
X725500Y593750D01*
X726000Y593167D01*
X726167Y592500D01*
X726000Y591833D01*
X725583Y591333D01*
X724833Y591083D01*
X722833D01*
G01X730100Y589000D02*
Y594000D01*
G01X734283Y592333D02*
Y590000D01*
X734617Y589417D01*
X735117Y589083D01*
X735700Y589000D01*
X736283Y589083D01*
X736783Y589417D01*
X737117Y590000D01*
G01Y589000D02*
Y592333D01*
G01X740133Y587750D02*
X740717Y587417D01*
X741383Y587333D01*
X741967Y587417D01*
X742467Y587833D01*
X742800Y588417D01*
Y592333D01*
G01Y591667D02*
X742467Y592000D01*
X741967Y592250D01*
X741383Y592333D01*
X740717Y592167D01*
X740300Y591833D01*
X739967Y591250D01*
X739800Y590667D01*
X739883Y590167D01*
X740217Y589583D01*
X740717Y589167D01*
X741383Y589000D01*
X741883Y589083D01*
X742467Y589417D01*
X742800Y589750D01*
G01X745733Y587750D02*
X746317Y587417D01*
X746983Y587333D01*
X747567Y587417D01*
X748067Y587833D01*
X748400Y588417D01*
Y592333D01*
G01Y591667D02*
X748067Y592000D01*
X747567Y592250D01*
X746983Y592333D01*
X746317Y592167D01*
X745900Y591833D01*
X745567Y591250D01*
X745400Y590667D01*
X745483Y590167D01*
X745817Y589583D01*
X746317Y589167D01*
X746983Y589000D01*
X747483Y589083D01*
X748067Y589417D01*
X748400Y589750D01*
G01X752500Y592333D02*
Y589000D01*
G01Y593667D02*
X752333Y593750D01*
Y593917D01*
X752500Y594000D01*
X752667Y593917D01*
Y593750D01*
X752500Y593667D01*
G01X756683Y589000D02*
Y592333D01*
G01Y591500D02*
X757017Y591917D01*
X757517Y592250D01*
X758183Y592333D01*
X758767Y592250D01*
X759267Y591917D01*
X759517Y591333D01*
Y589000D01*
G01X762533Y587750D02*
X763117Y587417D01*
X763783Y587333D01*
X764367Y587417D01*
X764867Y587833D01*
X765200Y588417D01*
Y592333D01*
G01Y591667D02*
X764867Y592000D01*
X764367Y592250D01*
X763783Y592333D01*
X763117Y592167D01*
X762700Y591833D01*
X762367Y591250D01*
X762200Y590667D01*
X762283Y590167D01*
X762617Y589583D01*
X763117Y589167D01*
X763783Y589000D01*
X764283Y589083D01*
X764867Y589417D01*
X765200Y589750D01*
G01X776400Y594000D02*
Y589000D01*
G01Y589750D02*
X776067Y589333D01*
X775567Y589083D01*
X774983Y589000D01*
X774317Y589167D01*
X773817Y589583D01*
X773483Y590083D01*
X773400Y590667D01*
X773483Y591250D01*
X773817Y591750D01*
X774317Y592167D01*
X774983Y592333D01*
X775567Y592250D01*
X775983Y592083D01*
X776400Y591750D01*
G01X779250Y591250D02*
X781917D01*
X781667Y591833D01*
X781250Y592167D01*
X780667Y592333D01*
X780083Y592250D01*
X779583Y592000D01*
X779250Y591417D01*
X779083Y590917D01*
Y590417D01*
X779250Y589917D01*
X779667Y589417D01*
X780167Y589083D01*
X780750Y589000D01*
X781333Y589167D01*
X781917Y589667D01*
G01X785600Y589000D02*
Y593250D01*
X785767Y593667D01*
X786100Y593917D01*
X786600Y594000D01*
X787100Y593833D01*
X787350Y593417D01*
G01X786350Y592000D02*
X784683D01*
G01X791700Y592333D02*
Y589000D01*
G01Y593667D02*
X791533Y593750D01*
Y593917D01*
X791700Y594000D01*
X791867Y593917D01*
Y593750D01*
X791700Y593667D01*
G01X795883Y589000D02*
Y592333D01*
G01Y591500D02*
X796217Y591917D01*
X796717Y592250D01*
X797383Y592333D01*
X797967Y592250D01*
X798467Y591917D01*
X798717Y591333D01*
Y589000D01*
G01X801650Y591250D02*
X804317D01*
X804067Y591833D01*
X803650Y592167D01*
X803067Y592333D01*
X802483Y592250D01*
X801983Y592000D01*
X801650Y591417D01*
X801483Y590917D01*
Y590417D01*
X801650Y589917D01*
X802067Y589417D01*
X802567Y589083D01*
X803150Y589000D01*
X803733Y589167D01*
X804317Y589667D01*
G01X713000Y579500D02*
X1343000D01*
G01X713000Y604500D02*
X1343000D01*
G01X722667Y765000D02*
X723167Y764417D01*
X723833Y764083D01*
X724583Y764000D01*
X725250Y764083D01*
X725917Y764500D01*
X726333Y765000D01*
X726417Y765500D01*
X726250Y766083D01*
X725667Y766500D01*
X725083Y766667D01*
X724333D01*
G01X725083D02*
X725583Y766917D01*
X726000Y767333D01*
X726167Y767833D01*
X726000Y768333D01*
X725583Y768750D01*
X724833Y769000D01*
X724083Y768917D01*
X723333Y768583D01*
G01X730100Y763833D02*
X729933Y763917D01*
Y764083D01*
X730100Y764167D01*
X730267Y764083D01*
Y763917D01*
X730100Y763833D01*
G01X739633Y764000D02*
Y769000D01*
X741633D01*
X742300Y768750D01*
X742800Y768167D01*
X742967Y767500D01*
X742800Y766833D01*
X742383Y766333D01*
X741633Y766083D01*
X739633D01*
G01X746900Y764000D02*
Y769000D01*
G01X751083Y767333D02*
Y765000D01*
X751417Y764417D01*
X751917Y764083D01*
X752500Y764000D01*
X753083Y764083D01*
X753583Y764417D01*
X753917Y765000D01*
G01Y764000D02*
Y767333D01*
G01X756933Y762750D02*
X757517Y762417D01*
X758183Y762333D01*
X758767Y762417D01*
X759267Y762833D01*
X759600Y763417D01*
Y767333D01*
G01Y766667D02*
X759267Y767000D01*
X758767Y767250D01*
X758183Y767333D01*
X757517Y767167D01*
X757100Y766833D01*
X756767Y766250D01*
X756600Y765667D01*
X756683Y765167D01*
X757017Y764583D01*
X757517Y764167D01*
X758183Y764000D01*
X758683Y764083D01*
X759267Y764417D01*
X759600Y764750D01*
G01X767800Y767333D02*
X769300Y764000D01*
X770800Y767333D01*
G01X774900D02*
Y764000D01*
G01Y768667D02*
X774733Y768750D01*
Y768917D01*
X774900Y769000D01*
X775067Y768917D01*
Y768750D01*
X774900Y768667D01*
G01X782000Y764000D02*
Y767333D01*
G01Y766750D02*
X781667Y767083D01*
X781167Y767250D01*
X780583Y767333D01*
X780000Y767167D01*
X779500Y766833D01*
X779167Y766333D01*
X779000Y765667D01*
X779167Y765000D01*
X779500Y764500D01*
X780000Y764167D01*
X780583Y764000D01*
X781167Y764083D01*
X781667Y764333D01*
X782000Y764667D01*
G01X790200Y763833D02*
X793200Y769000D01*
G01X795217D02*
X797300Y764000D01*
X799383Y769000D01*
G01X802900Y764000D02*
X802233Y764083D01*
X801650Y764417D01*
X801150Y764917D01*
X800817Y765500D01*
X800650Y766167D01*
Y766833D01*
X800817Y767500D01*
X801150Y768083D01*
X801650Y768583D01*
X802233Y768917D01*
X802900Y769000D01*
X803567Y768917D01*
X804150Y768583D01*
X804650Y768083D01*
X804983Y767500D01*
X805150Y766833D01*
Y766167D01*
X804983Y765500D01*
X804650Y764917D01*
X804150Y764417D01*
X803567Y764083D01*
X802900Y764000D01*
G01X806833D02*
Y769000D01*
X808833D01*
X809500Y768750D01*
X810000Y768167D01*
X810167Y767500D01*
X810000Y766833D01*
X809583Y766333D01*
X808833Y766083D01*
X806833D01*
G01X812600Y763833D02*
X815600Y769000D01*
G01X817617D02*
X819700Y764000D01*
X821783Y769000D01*
G01X824300D02*
X826300D01*
G01X825300D02*
Y764000D01*
G01X824300D02*
X826300D01*
G01X829233D02*
Y769000D01*
X831233D01*
X831900Y768750D01*
X832400Y768167D01*
X832567Y767500D01*
X832400Y766833D01*
X831983Y766333D01*
X831233Y766083D01*
X829233D01*
G01X836500Y763833D02*
X836333Y763917D01*
Y764083D01*
X836500Y764167D01*
X836667Y764083D01*
Y763917D01*
X836500Y763833D01*
G01Y766083D02*
X836333Y766167D01*
Y766333D01*
X836500Y766417D01*
X836667Y766333D01*
Y766167D01*
X836500Y766083D01*
G01X713000Y752000D02*
X1344500D01*
G01X724813Y813000D02*
Y818000D01*
X726897D01*
X727563Y817750D01*
X727980Y817417D01*
X728147Y816750D01*
X727980Y816083D01*
X727480Y815667D01*
X726897Y815417D01*
X724813D01*
G01X726897D02*
X728147Y813000D01*
G01X732080D02*
X731580Y813083D01*
X731080Y813417D01*
X730747Y814000D01*
X730580Y814667D01*
X730747Y815333D01*
X731080Y815917D01*
X731580Y816250D01*
X732080Y816333D01*
X732580Y816250D01*
X733080Y815917D01*
X733413Y815333D01*
X733497Y814667D01*
X733413Y814000D01*
X733080Y813417D01*
X732580Y813083D01*
X732080Y813000D01*
G01X736263Y816333D02*
Y814000D01*
X736597Y813417D01*
X737097Y813083D01*
X737680Y813000D01*
X738263Y813083D01*
X738763Y813417D01*
X739097Y814000D01*
G01Y813000D02*
Y816333D01*
G01X743280Y818000D02*
Y813000D01*
G01X742113Y816333D02*
X744447D01*
G01X748880D02*
Y813000D01*
G01Y817667D02*
X748713Y817750D01*
Y817917D01*
X748880Y818000D01*
X749047Y817917D01*
Y817750D01*
X748880Y817667D01*
G01X753063Y813000D02*
Y816333D01*
G01Y815500D02*
X753397Y815917D01*
X753897Y816250D01*
X754563Y816333D01*
X755147Y816250D01*
X755647Y815917D01*
X755897Y815333D01*
Y813000D01*
G01X758913Y811750D02*
X759497Y811417D01*
X760163Y811333D01*
X760747Y811417D01*
X761247Y811833D01*
X761580Y812417D01*
Y816333D01*
G01Y815667D02*
X761247Y816000D01*
X760747Y816250D01*
X760163Y816333D01*
X759497Y816167D01*
X759080Y815833D01*
X758747Y815250D01*
X758580Y814667D01*
X758663Y814167D01*
X758997Y813583D01*
X759497Y813167D01*
X760163Y813000D01*
X760663Y813083D01*
X761247Y813417D01*
X761580Y813750D01*
G01X712980Y850500D02*
X1343000D01*
G01X802167Y-15500D02*
Y-10500D01*
X803833D01*
X804500Y-10750D01*
X805000Y-11083D01*
X805417Y-11583D01*
X805750Y-12167D01*
X805833Y-13000D01*
X805750Y-13833D01*
X805417Y-14417D01*
X805000Y-14917D01*
X804500Y-15250D01*
X803833Y-15500D01*
X802167D01*
G01X809600D02*
Y-10500D01*
X808600Y-11500D01*
G01Y-15500D02*
X810600D01*
G01X813617Y-13417D02*
X814200Y-12833D01*
X814700Y-12500D01*
X815367Y-12333D01*
X815950Y-12500D01*
X816367Y-12833D01*
X816700Y-13333D01*
X816783Y-13917D01*
X816700Y-14417D01*
X816367Y-14917D01*
X815867Y-15333D01*
X815283Y-15500D01*
X814617Y-15333D01*
X814033Y-14833D01*
X813700Y-14083D01*
X813617Y-13250D01*
X813783Y-12167D01*
X814033Y-11583D01*
X814450Y-11000D01*
X815033Y-10583D01*
X815617Y-10500D01*
X816200Y-10667D01*
X816617Y-11083D01*
G01X827667Y150500D02*
Y155500D01*
X829333D01*
X830000Y155250D01*
X830500Y154917D01*
X830917Y154417D01*
X831250Y153833D01*
X831333Y153000D01*
X831250Y152167D01*
X830917Y151583D01*
X830500Y151083D01*
X830000Y150750D01*
X829333Y150500D01*
X827667D01*
G01X835100D02*
Y155500D01*
X834100Y154500D01*
G01Y150500D02*
X836100D01*
G01X825667Y314500D02*
Y319500D01*
X827333D01*
X828000Y319250D01*
X828500Y318917D01*
X828917Y318417D01*
X829250Y317833D01*
X829333Y317000D01*
X829250Y316167D01*
X828917Y315583D01*
X828500Y315083D01*
X828000Y314750D01*
X827333Y314500D01*
X825667D01*
G01X831517Y318667D02*
X832017Y319167D01*
X832600Y319417D01*
X833267Y319500D01*
X834100Y319333D01*
X834683Y318917D01*
X834850Y318417D01*
X834767Y317917D01*
X834433Y317500D01*
X832767Y316667D01*
X832017Y316083D01*
X831517Y315250D01*
X831350Y314500D01*
X834850D01*
G01X821590Y376450D02*
Y379783D01*
G01Y379200D02*
X821257Y379533D01*
X820757Y379700D01*
X820173Y379783D01*
X819590Y379617D01*
X819090Y379283D01*
X818757Y378783D01*
X818590Y378117D01*
X818757Y377450D01*
X819090Y376950D01*
X819590Y376617D01*
X820173Y376450D01*
X820757Y376533D01*
X821257Y376783D01*
X821590Y377117D01*
G01X824273Y376450D02*
Y379783D01*
G01Y378950D02*
X824607Y379367D01*
X825107Y379700D01*
X825773Y379783D01*
X826357Y379700D01*
X826857Y379367D01*
X827107Y378783D01*
Y376450D01*
G01X832790Y381450D02*
Y376450D01*
G01Y377200D02*
X832457Y376783D01*
X831957Y376533D01*
X831373Y376450D01*
X830707Y376617D01*
X830207Y377033D01*
X829873Y377533D01*
X829790Y378117D01*
X829873Y378700D01*
X830207Y379200D01*
X830707Y379617D01*
X831373Y379783D01*
X831957Y379700D01*
X832373Y379533D01*
X832790Y379200D01*
G01X843823Y379367D02*
X843240Y379700D01*
X842740Y379783D01*
X842073Y379617D01*
X841573Y379283D01*
X841240Y378700D01*
X841157Y378117D01*
X841240Y377533D01*
X841573Y377033D01*
X842073Y376617D01*
X842740Y376450D01*
X843323Y376617D01*
X843823Y376950D01*
G01X848090Y376450D02*
X847590Y376533D01*
X847090Y376867D01*
X846757Y377450D01*
X846590Y378117D01*
X846757Y378783D01*
X847090Y379367D01*
X847590Y379700D01*
X848090Y379783D01*
X848590Y379700D01*
X849090Y379367D01*
X849423Y378783D01*
X849507Y378117D01*
X849423Y377450D01*
X849090Y376867D01*
X848590Y376533D01*
X848090Y376450D01*
G01X852190Y379783D02*
X853690Y376450D01*
X855190Y379783D01*
G01X858040Y378700D02*
X860707D01*
X860457Y379283D01*
X860040Y379617D01*
X859457Y379783D01*
X858873Y379700D01*
X858373Y379450D01*
X858040Y378867D01*
X857873Y378367D01*
Y377867D01*
X858040Y377367D01*
X858457Y376867D01*
X858957Y376533D01*
X859540Y376450D01*
X860123Y376617D01*
X860707Y377117D01*
G01X863723Y376450D02*
Y379783D01*
G01Y379117D02*
X864140Y379450D01*
X864557Y379700D01*
X865140Y379783D01*
X865557Y379700D01*
X866057Y379450D01*
G01X869240Y378700D02*
X871907D01*
X871657Y379283D01*
X871240Y379617D01*
X870657Y379783D01*
X870073Y379700D01*
X869573Y379450D01*
X869240Y378867D01*
X869073Y378367D01*
Y377867D01*
X869240Y377367D01*
X869657Y376867D01*
X870157Y376533D01*
X870740Y376450D01*
X871323Y376617D01*
X871907Y377117D01*
G01X877590Y381450D02*
Y376450D01*
G01Y377200D02*
X877257Y376783D01*
X876757Y376533D01*
X876173Y376450D01*
X875507Y376617D01*
X875007Y377033D01*
X874673Y377533D01*
X874590Y378117D01*
X874673Y378700D01*
X875007Y379200D01*
X875507Y379617D01*
X876173Y379783D01*
X876757Y379700D01*
X877173Y379533D01*
X877590Y379200D01*
G01X885207Y379783D02*
X886207Y376450D01*
X887290Y379783D01*
X888373Y376450D01*
X889373Y379783D01*
G01X892890D02*
Y376450D01*
G01Y381117D02*
X892723Y381200D01*
Y381367D01*
X892890Y381450D01*
X893057Y381367D01*
Y381200D01*
X892890Y381117D01*
G01X898490Y381450D02*
Y376450D01*
G01X897323Y379783D02*
X899657D01*
G01X902673Y376450D02*
Y381450D01*
G01Y379033D02*
X903090Y379450D01*
X903507Y379700D01*
X904173Y379783D01*
X904673Y379700D01*
X905257Y379367D01*
X905507Y378867D01*
Y376450D01*
G01X916623Y379367D02*
X916040Y379700D01*
X915540Y379783D01*
X914873Y379617D01*
X914373Y379283D01*
X914040Y378700D01*
X913957Y378117D01*
X914040Y377533D01*
X914373Y377033D01*
X914873Y376617D01*
X915540Y376450D01*
X916123Y376617D01*
X916623Y376950D01*
G01X920890Y376450D02*
X920390Y376533D01*
X919890Y376867D01*
X919557Y377450D01*
X919390Y378117D01*
X919557Y378783D01*
X919890Y379367D01*
X920390Y379700D01*
X920890Y379783D01*
X921390Y379700D01*
X921890Y379367D01*
X922223Y378783D01*
X922307Y378117D01*
X922223Y377450D01*
X921890Y376867D01*
X921390Y376533D01*
X920890Y376450D01*
G01X924990Y374783D02*
Y379783D01*
G01Y379033D02*
X925407Y379450D01*
X925823Y379700D01*
X926490Y379783D01*
X927073Y379700D01*
X927657Y379283D01*
X927907Y378700D01*
X927990Y378117D01*
X927907Y377533D01*
X927657Y376950D01*
X927157Y376617D01*
X926490Y376450D01*
X925907Y376533D01*
X925323Y376783D01*
X924990Y377117D01*
G01X930590Y374783D02*
Y379783D01*
G01Y379033D02*
X931007Y379450D01*
X931423Y379700D01*
X932090Y379783D01*
X932673Y379700D01*
X933257Y379283D01*
X933507Y378700D01*
X933590Y378117D01*
X933507Y377533D01*
X933257Y376950D01*
X932757Y376617D01*
X932090Y376450D01*
X931507Y376533D01*
X930923Y376783D01*
X930590Y377117D01*
G01X936440Y378700D02*
X939107D01*
X938857Y379283D01*
X938440Y379617D01*
X937857Y379783D01*
X937273Y379700D01*
X936773Y379450D01*
X936440Y378867D01*
X936273Y378367D01*
Y377867D01*
X936440Y377367D01*
X936857Y376867D01*
X937357Y376533D01*
X937940Y376450D01*
X938523Y376617D01*
X939107Y377117D01*
G01X942123Y376450D02*
Y379783D01*
G01Y379117D02*
X942540Y379450D01*
X942957Y379700D01*
X943540Y379783D01*
X943957Y379700D01*
X944457Y379450D01*
G01X821500Y440500D02*
Y444750D01*
X821667Y445167D01*
X822000Y445417D01*
X822500Y445500D01*
X823000Y445333D01*
X823250Y444917D01*
G01X822250Y443500D02*
X820583D01*
G01X827600Y440500D02*
X827100Y440583D01*
X826600Y440917D01*
X826267Y441500D01*
X826100Y442167D01*
X826267Y442833D01*
X826600Y443417D01*
X827100Y443750D01*
X827600Y443833D01*
X828100Y443750D01*
X828600Y443417D01*
X828933Y442833D01*
X829017Y442167D01*
X828933Y441500D01*
X828600Y440917D01*
X828100Y440583D01*
X827600Y440500D01*
G01X833200D02*
Y445500D01*
G01X838800Y440500D02*
Y445500D01*
G01X844400Y440500D02*
X843900Y440583D01*
X843400Y440917D01*
X843067Y441500D01*
X842900Y442167D01*
X843067Y442833D01*
X843400Y443417D01*
X843900Y443750D01*
X844400Y443833D01*
X844900Y443750D01*
X845400Y443417D01*
X845733Y442833D01*
X845817Y442167D01*
X845733Y441500D01*
X845400Y440917D01*
X844900Y440583D01*
X844400Y440500D01*
G01X847917Y443833D02*
X848917Y440500D01*
X850000Y443833D01*
X851083Y440500D01*
X852083Y443833D01*
G01X861700Y443000D02*
X863367D01*
Y441500D01*
X862867Y441000D01*
X862283Y440667D01*
X861450Y440500D01*
X860617Y440667D01*
X860033Y441000D01*
X859533Y441500D01*
X859200Y442083D01*
X859033Y442750D01*
Y443333D01*
X859200Y443833D01*
X859533Y444417D01*
X860033Y444917D01*
X860533Y445250D01*
X861200Y445500D01*
X861783D01*
X862450Y445333D01*
X862950Y445000D01*
G01X865550Y442750D02*
X868217D01*
X867967Y443333D01*
X867550Y443667D01*
X866967Y443833D01*
X866383Y443750D01*
X865883Y443500D01*
X865550Y442917D01*
X865383Y442417D01*
Y441917D01*
X865550Y441417D01*
X865967Y440917D01*
X866467Y440583D01*
X867050Y440500D01*
X867633Y440667D01*
X868217Y441167D01*
G01X871233Y440500D02*
Y443833D01*
G01Y443167D02*
X871650Y443500D01*
X872067Y443750D01*
X872650Y443833D01*
X873067Y443750D01*
X873567Y443500D01*
G01X876500Y440500D02*
Y445500D01*
G01Y443000D02*
X876917Y443500D01*
X877417Y443750D01*
X877917Y443833D01*
X878667Y443667D01*
X879167Y443333D01*
X879500Y442750D01*
Y442083D01*
X879333Y441417D01*
X879000Y440917D01*
X878417Y440583D01*
X877917Y440500D01*
X877417Y440583D01*
X876917Y440833D01*
X876500Y441250D01*
G01X882350Y442750D02*
X885017D01*
X884767Y443333D01*
X884350Y443667D01*
X883767Y443833D01*
X883183Y443750D01*
X882683Y443500D01*
X882350Y442917D01*
X882183Y442417D01*
Y441917D01*
X882350Y441417D01*
X882767Y440917D01*
X883267Y440583D01*
X883850Y440500D01*
X884433Y440667D01*
X885017Y441167D01*
G01X888033Y440500D02*
Y443833D01*
G01Y443167D02*
X888450Y443500D01*
X888867Y443750D01*
X889450Y443833D01*
X889867Y443750D01*
X890367Y443500D01*
G01X821500Y419500D02*
Y423750D01*
X821667Y424167D01*
X822000Y424417D01*
X822500Y424500D01*
X823000Y424333D01*
X823250Y423917D01*
G01X822250Y422500D02*
X820583D01*
G01X827600Y419500D02*
X827100Y419583D01*
X826600Y419917D01*
X826267Y420500D01*
X826100Y421167D01*
X826267Y421833D01*
X826600Y422417D01*
X827100Y422750D01*
X827600Y422833D01*
X828100Y422750D01*
X828600Y422417D01*
X828933Y421833D01*
X829017Y421167D01*
X828933Y420500D01*
X828600Y419917D01*
X828100Y419583D01*
X827600Y419500D01*
G01X833200D02*
Y424500D01*
G01X838800Y419500D02*
Y424500D01*
G01X844400Y419500D02*
X843900Y419583D01*
X843400Y419917D01*
X843067Y420500D01*
X842900Y421167D01*
X843067Y421833D01*
X843400Y422417D01*
X843900Y422750D01*
X844400Y422833D01*
X844900Y422750D01*
X845400Y422417D01*
X845733Y421833D01*
X845817Y421167D01*
X845733Y420500D01*
X845400Y419917D01*
X844900Y419583D01*
X844400Y419500D01*
G01X847917Y422833D02*
X848917Y419500D01*
X850000Y422833D01*
X851083Y419500D01*
X852083Y422833D01*
G01X861700Y422000D02*
X863367D01*
Y420500D01*
X862867Y420000D01*
X862283Y419667D01*
X861450Y419500D01*
X860617Y419667D01*
X860033Y420000D01*
X859533Y420500D01*
X859200Y421083D01*
X859033Y421750D01*
Y422333D01*
X859200Y422833D01*
X859533Y423417D01*
X860033Y423917D01*
X860533Y424250D01*
X861200Y424500D01*
X861783D01*
X862450Y424333D01*
X862950Y424000D01*
G01X865550Y421750D02*
X868217D01*
X867967Y422333D01*
X867550Y422667D01*
X866967Y422833D01*
X866383Y422750D01*
X865883Y422500D01*
X865550Y421917D01*
X865383Y421417D01*
Y420917D01*
X865550Y420417D01*
X865967Y419917D01*
X866467Y419583D01*
X867050Y419500D01*
X867633Y419667D01*
X868217Y420167D01*
G01X871233Y419500D02*
Y422833D01*
G01Y422167D02*
X871650Y422500D01*
X872067Y422750D01*
X872650Y422833D01*
X873067Y422750D01*
X873567Y422500D01*
G01X876500Y419500D02*
Y424500D01*
G01Y422000D02*
X876917Y422500D01*
X877417Y422750D01*
X877917Y422833D01*
X878667Y422667D01*
X879167Y422333D01*
X879500Y421750D01*
Y421083D01*
X879333Y420417D01*
X879000Y419917D01*
X878417Y419583D01*
X877917Y419500D01*
X877417Y419583D01*
X876917Y419833D01*
X876500Y420250D01*
G01X882350Y421750D02*
X885017D01*
X884767Y422333D01*
X884350Y422667D01*
X883767Y422833D01*
X883183Y422750D01*
X882683Y422500D01*
X882350Y421917D01*
X882183Y421417D01*
Y420917D01*
X882350Y420417D01*
X882767Y419917D01*
X883267Y419583D01*
X883850Y419500D01*
X884433Y419667D01*
X885017Y420167D01*
G01X888033Y419500D02*
Y422833D01*
G01Y422167D02*
X888450Y422500D01*
X888867Y422750D01*
X889450Y422833D01*
X889867Y422750D01*
X890367Y422500D01*
G01X901900Y419500D02*
Y422833D01*
G01Y422250D02*
X901567Y422583D01*
X901067Y422750D01*
X900483Y422833D01*
X899900Y422667D01*
X899400Y422333D01*
X899067Y421833D01*
X898900Y421167D01*
X899067Y420500D01*
X899400Y420000D01*
X899900Y419667D01*
X900483Y419500D01*
X901067Y419583D01*
X901567Y419833D01*
X901900Y420167D01*
G01X904583Y419500D02*
Y422833D01*
G01Y422000D02*
X904917Y422417D01*
X905417Y422750D01*
X906083Y422833D01*
X906667Y422750D01*
X907167Y422417D01*
X907417Y421833D01*
Y419500D01*
G01X913100Y424500D02*
Y419500D01*
G01Y420250D02*
X912767Y419833D01*
X912267Y419583D01*
X911683Y419500D01*
X911017Y419667D01*
X910517Y420083D01*
X910183Y420583D01*
X910100Y421167D01*
X910183Y421750D01*
X910517Y422250D01*
X911017Y422667D01*
X911683Y422833D01*
X912267Y422750D01*
X912683Y422583D01*
X913100Y422250D01*
G01X921300Y417833D02*
Y422833D01*
G01Y422083D02*
X921717Y422500D01*
X922133Y422750D01*
X922800Y422833D01*
X923383Y422750D01*
X923967Y422333D01*
X924217Y421750D01*
X924300Y421167D01*
X924217Y420583D01*
X923967Y420000D01*
X923467Y419667D01*
X922800Y419500D01*
X922217Y419583D01*
X921633Y419833D01*
X921300Y420167D01*
G01X928400Y419500D02*
Y424500D01*
G01X932583Y422833D02*
Y420500D01*
X932917Y419917D01*
X933417Y419583D01*
X934000Y419500D01*
X934583Y419583D01*
X935083Y419917D01*
X935417Y420500D01*
G01Y419500D02*
Y422833D01*
G01X938433Y418250D02*
X939017Y417917D01*
X939683Y417833D01*
X940267Y417917D01*
X940767Y418333D01*
X941100Y418917D01*
Y422833D01*
G01Y422167D02*
X940767Y422500D01*
X940267Y422750D01*
X939683Y422833D01*
X939017Y422667D01*
X938600Y422333D01*
X938267Y421750D01*
X938100Y421167D01*
X938183Y420667D01*
X938517Y420083D01*
X939017Y419667D01*
X939683Y419500D01*
X940183Y419583D01*
X940767Y419917D01*
X941100Y420250D01*
G01X948717Y422833D02*
X949717Y419500D01*
X950800Y422833D01*
X951883Y419500D01*
X952883Y422833D01*
G01X956400D02*
Y419500D01*
G01Y424167D02*
X956233Y424250D01*
Y424417D01*
X956400Y424500D01*
X956567Y424417D01*
Y424250D01*
X956400Y424167D01*
G01X962000Y424500D02*
Y419500D01*
G01X960833Y422833D02*
X963167D01*
G01X966183Y419500D02*
Y424500D01*
G01Y422083D02*
X966600Y422500D01*
X967017Y422750D01*
X967683Y422833D01*
X968183Y422750D01*
X968767Y422417D01*
X969017Y421917D01*
Y419500D01*
G01X977633D02*
Y422833D01*
G01Y422167D02*
X978050Y422500D01*
X978467Y422750D01*
X979050Y422833D01*
X979467Y422750D01*
X979967Y422500D01*
G01X983150Y421750D02*
X985817D01*
X985567Y422333D01*
X985150Y422667D01*
X984567Y422833D01*
X983983Y422750D01*
X983483Y422500D01*
X983150Y421917D01*
X982983Y421417D01*
Y420917D01*
X983150Y420417D01*
X983567Y419917D01*
X984067Y419583D01*
X984650Y419500D01*
X985233Y419667D01*
X985817Y420167D01*
G01X988750Y420083D02*
X989167Y419750D01*
X989750Y419500D01*
X990250D01*
X990750Y419667D01*
X991083Y419917D01*
X991250Y420250D01*
X991167Y420750D01*
X990833Y421000D01*
X989333Y421500D01*
X989000Y422083D01*
X989167Y422500D01*
X989500Y422750D01*
X990000Y422833D01*
X990500Y422750D01*
X991000Y422500D01*
G01X995600Y422833D02*
Y419500D01*
G01Y424167D02*
X995433Y424250D01*
Y424417D01*
X995600Y424500D01*
X995767Y424417D01*
Y424250D01*
X995600Y424167D01*
G01X999783Y419500D02*
Y422833D01*
G01Y422000D02*
X1000117Y422417D01*
X1000617Y422750D01*
X1001283Y422833D01*
X1001867Y422750D01*
X1002367Y422417D01*
X1002617Y421833D01*
Y419500D01*
G01X819590Y389810D02*
Y394060D01*
X819757Y394477D01*
X820090Y394727D01*
X820590Y394810D01*
X821090Y394643D01*
X821340Y394227D01*
G01X820340Y392810D02*
X818673D01*
G01X825690Y389810D02*
X825190Y389893D01*
X824690Y390227D01*
X824357Y390810D01*
X824190Y391477D01*
X824357Y392143D01*
X824690Y392727D01*
X825190Y393060D01*
X825690Y393143D01*
X826190Y393060D01*
X826690Y392727D01*
X827023Y392143D01*
X827107Y391477D01*
X827023Y390810D01*
X826690Y390227D01*
X826190Y389893D01*
X825690Y389810D01*
G01X831290D02*
Y394810D01*
G01X836890Y389810D02*
Y394810D01*
G01X842490Y389810D02*
X841990Y389893D01*
X841490Y390227D01*
X841157Y390810D01*
X840990Y391477D01*
X841157Y392143D01*
X841490Y392727D01*
X841990Y393060D01*
X842490Y393143D01*
X842990Y393060D01*
X843490Y392727D01*
X843823Y392143D01*
X843907Y391477D01*
X843823Y390810D01*
X843490Y390227D01*
X842990Y389893D01*
X842490Y389810D01*
G01X846007Y393143D02*
X847007Y389810D01*
X848090Y393143D01*
X849173Y389810D01*
X850173Y393143D01*
G01X859790Y392310D02*
X861457D01*
Y390810D01*
X860957Y390310D01*
X860373Y389977D01*
X859540Y389810D01*
X858707Y389977D01*
X858123Y390310D01*
X857623Y390810D01*
X857290Y391393D01*
X857123Y392060D01*
Y392643D01*
X857290Y393143D01*
X857623Y393727D01*
X858123Y394227D01*
X858623Y394560D01*
X859290Y394810D01*
X859873D01*
X860540Y394643D01*
X861040Y394310D01*
G01X863640Y392060D02*
X866307D01*
X866057Y392643D01*
X865640Y392977D01*
X865057Y393143D01*
X864473Y393060D01*
X863973Y392810D01*
X863640Y392227D01*
X863473Y391727D01*
Y391227D01*
X863640Y390727D01*
X864057Y390227D01*
X864557Y389893D01*
X865140Y389810D01*
X865723Y389977D01*
X866307Y390477D01*
G01X869323Y389810D02*
Y393143D01*
G01Y392477D02*
X869740Y392810D01*
X870157Y393060D01*
X870740Y393143D01*
X871157Y393060D01*
X871657Y392810D01*
G01X874590Y389810D02*
Y394810D01*
G01Y392310D02*
X875007Y392810D01*
X875507Y393060D01*
X876007Y393143D01*
X876757Y392977D01*
X877257Y392643D01*
X877590Y392060D01*
Y391393D01*
X877423Y390727D01*
X877090Y390227D01*
X876507Y389893D01*
X876007Y389810D01*
X875507Y389893D01*
X875007Y390143D01*
X874590Y390560D01*
G01X880440Y392060D02*
X883107D01*
X882857Y392643D01*
X882440Y392977D01*
X881857Y393143D01*
X881273Y393060D01*
X880773Y392810D01*
X880440Y392227D01*
X880273Y391727D01*
Y391227D01*
X880440Y390727D01*
X880857Y390227D01*
X881357Y389893D01*
X881940Y389810D01*
X882523Y389977D01*
X883107Y390477D01*
G01X886123Y389810D02*
Y393143D01*
G01Y392477D02*
X886540Y392810D01*
X886957Y393060D01*
X887540Y393143D01*
X887957Y393060D01*
X888457Y392810D01*
G01X899990Y389810D02*
Y393143D01*
G01Y392560D02*
X899657Y392893D01*
X899157Y393060D01*
X898573Y393143D01*
X897990Y392977D01*
X897490Y392643D01*
X897157Y392143D01*
X896990Y391477D01*
X897157Y390810D01*
X897490Y390310D01*
X897990Y389977D01*
X898573Y389810D01*
X899157Y389893D01*
X899657Y390143D01*
X899990Y390477D01*
G01X902673Y389810D02*
Y393143D01*
G01Y392310D02*
X903007Y392727D01*
X903507Y393060D01*
X904173Y393143D01*
X904757Y393060D01*
X905257Y392727D01*
X905507Y392143D01*
Y389810D01*
G01X911190Y394810D02*
Y389810D01*
G01Y390560D02*
X910857Y390143D01*
X910357Y389893D01*
X909773Y389810D01*
X909107Y389977D01*
X908607Y390393D01*
X908273Y390893D01*
X908190Y391477D01*
X908273Y392060D01*
X908607Y392560D01*
X909107Y392977D01*
X909773Y393143D01*
X910357Y393060D01*
X910773Y392893D01*
X911190Y392560D01*
G01X919390Y388143D02*
Y393143D01*
G01Y392393D02*
X919807Y392810D01*
X920223Y393060D01*
X920890Y393143D01*
X921473Y393060D01*
X922057Y392643D01*
X922307Y392060D01*
X922390Y391477D01*
X922307Y390893D01*
X922057Y390310D01*
X921557Y389977D01*
X920890Y389810D01*
X920307Y389893D01*
X919723Y390143D01*
X919390Y390477D01*
G01X926490Y389810D02*
Y394810D01*
G01X930673Y393143D02*
Y390810D01*
X931007Y390227D01*
X931507Y389893D01*
X932090Y389810D01*
X932673Y389893D01*
X933173Y390227D01*
X933507Y390810D01*
G01Y389810D02*
Y393143D01*
G01X936523Y388560D02*
X937107Y388227D01*
X937773Y388143D01*
X938357Y388227D01*
X938857Y388643D01*
X939190Y389227D01*
Y393143D01*
G01Y392477D02*
X938857Y392810D01*
X938357Y393060D01*
X937773Y393143D01*
X937107Y392977D01*
X936690Y392643D01*
X936357Y392060D01*
X936190Y391477D01*
X936273Y390977D01*
X936607Y390393D01*
X937107Y389977D01*
X937773Y389810D01*
X938273Y389893D01*
X938857Y390227D01*
X939190Y390560D01*
G01X946807Y393143D02*
X947807Y389810D01*
X948890Y393143D01*
X949973Y389810D01*
X950973Y393143D01*
G01X954490D02*
Y389810D01*
G01Y394477D02*
X954323Y394560D01*
Y394727D01*
X954490Y394810D01*
X954657Y394727D01*
Y394560D01*
X954490Y394477D01*
G01X960090Y394810D02*
Y389810D01*
G01X958923Y393143D02*
X961257D01*
G01X964273Y389810D02*
Y394810D01*
G01Y392393D02*
X964690Y392810D01*
X965107Y393060D01*
X965773Y393143D01*
X966273Y393060D01*
X966857Y392727D01*
X967107Y392227D01*
Y389810D01*
G01X975723D02*
Y393143D01*
G01Y392477D02*
X976140Y392810D01*
X976557Y393060D01*
X977140Y393143D01*
X977557Y393060D01*
X978057Y392810D01*
G01X981240Y392060D02*
X983907D01*
X983657Y392643D01*
X983240Y392977D01*
X982657Y393143D01*
X982073Y393060D01*
X981573Y392810D01*
X981240Y392227D01*
X981073Y391727D01*
Y391227D01*
X981240Y390727D01*
X981657Y390227D01*
X982157Y389893D01*
X982740Y389810D01*
X983323Y389977D01*
X983907Y390477D01*
G01X986840Y390393D02*
X987257Y390060D01*
X987840Y389810D01*
X988340D01*
X988840Y389977D01*
X989173Y390227D01*
X989340Y390560D01*
X989257Y391060D01*
X988923Y391310D01*
X987423Y391810D01*
X987090Y392393D01*
X987257Y392810D01*
X987590Y393060D01*
X988090Y393143D01*
X988590Y393060D01*
X989090Y392810D01*
G01X993690Y393143D02*
Y389810D01*
G01Y394477D02*
X993523Y394560D01*
Y394727D01*
X993690Y394810D01*
X993857Y394727D01*
Y394560D01*
X993690Y394477D01*
G01X997873Y389810D02*
Y393143D01*
G01Y392310D02*
X998207Y392727D01*
X998707Y393060D01*
X999373Y393143D01*
X999957Y393060D01*
X1000457Y392727D01*
X1000707Y392143D01*
Y389810D01*
G01X812000Y604500D02*
Y366000D01*
G01X823500Y455500D02*
Y458833D01*
G01Y458250D02*
X823167Y458583D01*
X822667Y458750D01*
X822083Y458833D01*
X821500Y458667D01*
X821000Y458333D01*
X820667Y457833D01*
X820500Y457167D01*
X820667Y456500D01*
X821000Y456000D01*
X821500Y455667D01*
X822083Y455500D01*
X822667Y455583D01*
X823167Y455833D01*
X823500Y456167D01*
G01X826183Y455500D02*
Y458833D01*
G01Y458000D02*
X826517Y458417D01*
X827017Y458750D01*
X827683Y458833D01*
X828267Y458750D01*
X828767Y458417D01*
X829017Y457833D01*
Y455500D01*
G01X834700Y460500D02*
Y455500D01*
G01Y456250D02*
X834367Y455833D01*
X833867Y455583D01*
X833283Y455500D01*
X832617Y455667D01*
X832117Y456083D01*
X831783Y456583D01*
X831700Y457167D01*
X831783Y457750D01*
X832117Y458250D01*
X832617Y458667D01*
X833283Y458833D01*
X833867Y458750D01*
X834283Y458583D01*
X834700Y458250D01*
G01X842900Y455500D02*
Y460500D01*
G01Y458000D02*
X843317Y458500D01*
X843817Y458750D01*
X844317Y458833D01*
X845067Y458667D01*
X845567Y458333D01*
X845900Y457750D01*
Y457083D01*
X845733Y456417D01*
X845400Y455917D01*
X844817Y455583D01*
X844317Y455500D01*
X843817Y455583D01*
X843317Y455833D01*
X842900Y456250D01*
G01X850000Y455500D02*
X849500Y455583D01*
X849000Y455917D01*
X848667Y456500D01*
X848500Y457167D01*
X848667Y457833D01*
X849000Y458417D01*
X849500Y458750D01*
X850000Y458833D01*
X850500Y458750D01*
X851000Y458417D01*
X851333Y457833D01*
X851417Y457167D01*
X851333Y456500D01*
X851000Y455917D01*
X850500Y455583D01*
X850000Y455500D01*
G01X855600Y460500D02*
Y455500D01*
G01X854433Y458833D02*
X856767D01*
G01X861200Y460500D02*
Y455500D01*
G01X860033Y458833D02*
X862367D01*
G01X866800Y455500D02*
X866300Y455583D01*
X865800Y455917D01*
X865467Y456500D01*
X865300Y457167D01*
X865467Y457833D01*
X865800Y458417D01*
X866300Y458750D01*
X866800Y458833D01*
X867300Y458750D01*
X867800Y458417D01*
X868133Y457833D01*
X868217Y457167D01*
X868133Y456500D01*
X867800Y455917D01*
X867300Y455583D01*
X866800Y455500D01*
G01X869900D02*
Y458833D01*
G01Y457917D02*
X870150Y458333D01*
X870567Y458667D01*
X871150Y458833D01*
X871733Y458667D01*
X872150Y458333D01*
X872400Y457917D01*
Y455500D01*
G01Y457917D02*
X872650Y458333D01*
X873067Y458667D01*
X873650Y458833D01*
X874233Y458667D01*
X874650Y458333D01*
X874900Y457833D01*
Y455500D01*
G01X882350Y456083D02*
X882767Y455750D01*
X883350Y455500D01*
X883850D01*
X884350Y455667D01*
X884683Y455917D01*
X884850Y456250D01*
X884767Y456750D01*
X884433Y457000D01*
X882933Y457500D01*
X882600Y458083D01*
X882767Y458500D01*
X883100Y458750D01*
X883600Y458833D01*
X884100Y458750D01*
X884600Y458500D01*
G01X889200Y458833D02*
Y455500D01*
G01Y460167D02*
X889033Y460250D01*
Y460417D01*
X889200Y460500D01*
X889367Y460417D01*
Y460250D01*
X889200Y460167D01*
G01X896300Y460500D02*
Y455500D01*
G01Y456250D02*
X895967Y455833D01*
X895467Y455583D01*
X894883Y455500D01*
X894217Y455667D01*
X893717Y456083D01*
X893383Y456583D01*
X893300Y457167D01*
X893383Y457750D01*
X893717Y458250D01*
X894217Y458667D01*
X894883Y458833D01*
X895467Y458750D01*
X895883Y458583D01*
X896300Y458250D01*
G01X899150Y457750D02*
X901817D01*
X901567Y458333D01*
X901150Y458667D01*
X900567Y458833D01*
X899983Y458750D01*
X899483Y458500D01*
X899150Y457917D01*
X898983Y457417D01*
Y456917D01*
X899150Y456417D01*
X899567Y455917D01*
X900067Y455583D01*
X900650Y455500D01*
X901233Y455667D01*
X901817Y456167D01*
G01X819917Y470833D02*
X820917Y467500D01*
X822000Y470833D01*
X823083Y467500D01*
X824083Y470833D01*
G01X827600D02*
Y467500D01*
G01Y472167D02*
X827433Y472250D01*
Y472417D01*
X827600Y472500D01*
X827767Y472417D01*
Y472250D01*
X827600Y472167D01*
G01X833200Y472500D02*
Y467500D01*
G01X832033Y470833D02*
X834367D01*
G01X837383Y467500D02*
Y472500D01*
G01Y470083D02*
X837800Y470500D01*
X838217Y470750D01*
X838883Y470833D01*
X839383Y470750D01*
X839967Y470417D01*
X840217Y469917D01*
Y467500D01*
G01X844400D02*
X843900Y467583D01*
X843400Y467917D01*
X843067Y468500D01*
X842900Y469167D01*
X843067Y469833D01*
X843400Y470417D01*
X843900Y470750D01*
X844400Y470833D01*
X844900Y470750D01*
X845400Y470417D01*
X845733Y469833D01*
X845817Y469167D01*
X845733Y468500D01*
X845400Y467917D01*
X844900Y467583D01*
X844400Y467500D01*
G01X848583Y470833D02*
Y468500D01*
X848917Y467917D01*
X849417Y467583D01*
X850000Y467500D01*
X850583Y467583D01*
X851083Y467917D01*
X851417Y468500D01*
G01Y467500D02*
Y470833D01*
G01X855600Y472500D02*
Y467500D01*
G01X854433Y470833D02*
X856767D01*
G01X865550Y468083D02*
X865967Y467750D01*
X866550Y467500D01*
X867050D01*
X867550Y467667D01*
X867883Y467917D01*
X868050Y468250D01*
X867967Y468750D01*
X867633Y469000D01*
X866133Y469500D01*
X865800Y470083D01*
X865967Y470500D01*
X866300Y470750D01*
X866800Y470833D01*
X867300Y470750D01*
X867800Y470500D01*
G01X872400Y467500D02*
X871900Y467583D01*
X871400Y467917D01*
X871067Y468500D01*
X870900Y469167D01*
X871067Y469833D01*
X871400Y470417D01*
X871900Y470750D01*
X872400Y470833D01*
X872900Y470750D01*
X873400Y470417D01*
X873733Y469833D01*
X873817Y469167D01*
X873733Y468500D01*
X873400Y467917D01*
X872900Y467583D01*
X872400Y467500D01*
G01X878000D02*
Y472500D01*
G01X885100D02*
Y467500D01*
G01Y468250D02*
X884767Y467833D01*
X884267Y467583D01*
X883683Y467500D01*
X883017Y467667D01*
X882517Y468083D01*
X882183Y468583D01*
X882100Y469167D01*
X882183Y469750D01*
X882517Y470250D01*
X883017Y470667D01*
X883683Y470833D01*
X884267Y470750D01*
X884683Y470583D01*
X885100Y470250D01*
G01X887950Y469750D02*
X890617D01*
X890367Y470333D01*
X889950Y470667D01*
X889367Y470833D01*
X888783Y470750D01*
X888283Y470500D01*
X887950Y469917D01*
X887783Y469417D01*
Y468917D01*
X887950Y468417D01*
X888367Y467917D01*
X888867Y467583D01*
X889450Y467500D01*
X890033Y467667D01*
X890617Y468167D01*
G01X893633Y467500D02*
Y470833D01*
G01Y470167D02*
X894050Y470500D01*
X894467Y470750D01*
X895050Y470833D01*
X895467Y470750D01*
X895967Y470500D01*
G01X903500Y467500D02*
Y470833D01*
G01Y469917D02*
X903750Y470333D01*
X904167Y470667D01*
X904750Y470833D01*
X905333Y470667D01*
X905750Y470333D01*
X906000Y469917D01*
Y467500D01*
G01Y469917D02*
X906250Y470333D01*
X906667Y470667D01*
X907250Y470833D01*
X907833Y470667D01*
X908250Y470333D01*
X908500Y469833D01*
Y467500D01*
G01X913100D02*
Y470833D01*
G01Y470250D02*
X912767Y470583D01*
X912267Y470750D01*
X911683Y470833D01*
X911100Y470667D01*
X910600Y470333D01*
X910267Y469833D01*
X910100Y469167D01*
X910267Y468500D01*
X910600Y468000D01*
X911100Y467667D01*
X911683Y467500D01*
X912267Y467583D01*
X912767Y467833D01*
X913100Y468167D01*
G01X915950Y468083D02*
X916367Y467750D01*
X916950Y467500D01*
X917450D01*
X917950Y467667D01*
X918283Y467917D01*
X918450Y468250D01*
X918367Y468750D01*
X918033Y469000D01*
X916533Y469500D01*
X916200Y470083D01*
X916367Y470500D01*
X916700Y470750D01*
X917200Y470833D01*
X917700Y470750D01*
X918200Y470500D01*
G01X921383Y467500D02*
Y472500D01*
G01X924050Y470833D02*
X921383Y468917D01*
G01X922467Y469667D02*
X924217Y467500D01*
G01X932500Y465833D02*
Y470833D01*
G01Y470083D02*
X932917Y470500D01*
X933333Y470750D01*
X934000Y470833D01*
X934583Y470750D01*
X935167Y470333D01*
X935417Y469750D01*
X935500Y469167D01*
X935417Y468583D01*
X935167Y468000D01*
X934667Y467667D01*
X934000Y467500D01*
X933417Y467583D01*
X932833Y467833D01*
X932500Y468167D01*
G01X941100Y467500D02*
Y470833D01*
G01Y470250D02*
X940767Y470583D01*
X940267Y470750D01*
X939683Y470833D01*
X939100Y470667D01*
X938600Y470333D01*
X938267Y469833D01*
X938100Y469167D01*
X938267Y468500D01*
X938600Y468000D01*
X939100Y467667D01*
X939683Y467500D01*
X940267Y467583D01*
X940767Y467833D01*
X941100Y468167D01*
G01X946700Y472500D02*
Y467500D01*
G01Y468250D02*
X946367Y467833D01*
X945867Y467583D01*
X945283Y467500D01*
X944617Y467667D01*
X944117Y468083D01*
X943783Y468583D01*
X943700Y469167D01*
X943783Y469750D01*
X944117Y470250D01*
X944617Y470667D01*
X945283Y470833D01*
X945867Y470750D01*
X946283Y470583D01*
X946700Y470250D01*
G01X956400Y467500D02*
X955900Y467583D01*
X955400Y467917D01*
X955067Y468500D01*
X954900Y469167D01*
X955067Y469833D01*
X955400Y470417D01*
X955900Y470750D01*
X956400Y470833D01*
X956900Y470750D01*
X957400Y470417D01*
X957733Y469833D01*
X957817Y469167D01*
X957733Y468500D01*
X957400Y467917D01*
X956900Y467583D01*
X956400Y467500D01*
G01X960583D02*
Y470833D01*
G01Y470000D02*
X960917Y470417D01*
X961417Y470750D01*
X962083Y470833D01*
X962667Y470750D01*
X963167Y470417D01*
X963417Y469833D01*
Y467500D01*
G01X973200Y472500D02*
Y467500D01*
G01X972033Y470833D02*
X974367D01*
G01X978800Y467500D02*
X978300Y467583D01*
X977800Y467917D01*
X977467Y468500D01*
X977300Y469167D01*
X977467Y469833D01*
X977800Y470417D01*
X978300Y470750D01*
X978800Y470833D01*
X979300Y470750D01*
X979800Y470417D01*
X980133Y469833D01*
X980217Y469167D01*
X980133Y468500D01*
X979800Y467917D01*
X979300Y467583D01*
X978800Y467500D01*
G01X982900Y465833D02*
Y470833D01*
G01Y470083D02*
X983317Y470500D01*
X983733Y470750D01*
X984400Y470833D01*
X984983Y470750D01*
X985567Y470333D01*
X985817Y469750D01*
X985900Y469167D01*
X985817Y468583D01*
X985567Y468000D01*
X985067Y467667D01*
X984400Y467500D01*
X983817Y467583D01*
X983233Y467833D01*
X982900Y468167D01*
G01X829750Y542583D02*
X830167Y542250D01*
X830750Y542000D01*
X831250D01*
X831750Y542167D01*
X832083Y542417D01*
X832250Y542750D01*
X832167Y543250D01*
X831833Y543500D01*
X830333Y544000D01*
X830000Y544583D01*
X830167Y545000D01*
X830500Y545250D01*
X831000Y545333D01*
X831500Y545250D01*
X832000Y545000D01*
G01X836600Y542000D02*
X836100Y542083D01*
X835600Y542417D01*
X835267Y543000D01*
X835100Y543667D01*
X835267Y544333D01*
X835600Y544917D01*
X836100Y545250D01*
X836600Y545333D01*
X837100Y545250D01*
X837600Y544917D01*
X837933Y544333D01*
X838017Y543667D01*
X837933Y543000D01*
X837600Y542417D01*
X837100Y542083D01*
X836600Y542000D01*
G01X842200D02*
Y547000D01*
G01X849300D02*
Y542000D01*
G01Y542750D02*
X848967Y542333D01*
X848467Y542083D01*
X847883Y542000D01*
X847217Y542167D01*
X846717Y542583D01*
X846383Y543083D01*
X846300Y543667D01*
X846383Y544250D01*
X846717Y544750D01*
X847217Y545167D01*
X847883Y545333D01*
X848467Y545250D01*
X848883Y545083D01*
X849300Y544750D01*
G01X852150Y544250D02*
X854817D01*
X854567Y544833D01*
X854150Y545167D01*
X853567Y545333D01*
X852983Y545250D01*
X852483Y545000D01*
X852150Y544417D01*
X851983Y543917D01*
Y543417D01*
X852150Y542917D01*
X852567Y542417D01*
X853067Y542083D01*
X853650Y542000D01*
X854233Y542167D01*
X854817Y542667D01*
G01X857833Y542000D02*
Y545333D01*
G01Y544667D02*
X858250Y545000D01*
X858667Y545250D01*
X859250Y545333D01*
X859667Y545250D01*
X860167Y545000D01*
G01X867700Y542000D02*
Y545333D01*
G01Y544417D02*
X867950Y544833D01*
X868367Y545167D01*
X868950Y545333D01*
X869533Y545167D01*
X869950Y544833D01*
X870200Y544417D01*
Y542000D01*
G01Y544417D02*
X870450Y544833D01*
X870867Y545167D01*
X871450Y545333D01*
X872033Y545167D01*
X872450Y544833D01*
X872700Y544333D01*
Y542000D01*
G01X877300D02*
Y545333D01*
G01Y544750D02*
X876967Y545083D01*
X876467Y545250D01*
X875883Y545333D01*
X875300Y545167D01*
X874800Y544833D01*
X874467Y544333D01*
X874300Y543667D01*
X874467Y543000D01*
X874800Y542500D01*
X875300Y542167D01*
X875883Y542000D01*
X876467Y542083D01*
X876967Y542333D01*
X877300Y542667D01*
G01X880150Y542583D02*
X880567Y542250D01*
X881150Y542000D01*
X881650D01*
X882150Y542167D01*
X882483Y542417D01*
X882650Y542750D01*
X882567Y543250D01*
X882233Y543500D01*
X880733Y544000D01*
X880400Y544583D01*
X880567Y545000D01*
X880900Y545250D01*
X881400Y545333D01*
X881900Y545250D01*
X882400Y545000D01*
G01X885583Y542000D02*
Y547000D01*
G01X888250Y545333D02*
X885583Y543417D01*
G01X886667Y544167D02*
X888417Y542000D01*
G01X896700Y540333D02*
Y545333D01*
G01Y544583D02*
X897117Y545000D01*
X897533Y545250D01*
X898200Y545333D01*
X898783Y545250D01*
X899367Y544833D01*
X899617Y544250D01*
X899700Y543667D01*
X899617Y543083D01*
X899367Y542500D01*
X898867Y542167D01*
X898200Y542000D01*
X897617Y542083D01*
X897033Y542333D01*
X896700Y542667D01*
G01X905300Y542000D02*
Y545333D01*
G01Y544750D02*
X904967Y545083D01*
X904467Y545250D01*
X903883Y545333D01*
X903300Y545167D01*
X902800Y544833D01*
X902467Y544333D01*
X902300Y543667D01*
X902467Y543000D01*
X902800Y542500D01*
X903300Y542167D01*
X903883Y542000D01*
X904467Y542083D01*
X904967Y542333D01*
X905300Y542667D01*
G01X910900Y547000D02*
Y542000D01*
G01Y542750D02*
X910567Y542333D01*
X910067Y542083D01*
X909483Y542000D01*
X908817Y542167D01*
X908317Y542583D01*
X907983Y543083D01*
X907900Y543667D01*
X907983Y544250D01*
X908317Y544750D01*
X908817Y545167D01*
X909483Y545333D01*
X910067Y545250D01*
X910483Y545083D01*
X910900Y544750D01*
G01X829917Y563333D02*
X830917Y560000D01*
X832000Y563333D01*
X833083Y560000D01*
X834083Y563333D01*
G01X836183Y560000D02*
Y565000D01*
G01Y562583D02*
X836600Y563000D01*
X837017Y563250D01*
X837683Y563333D01*
X838183Y563250D01*
X838767Y562917D01*
X839017Y562417D01*
Y560000D01*
G01X843200Y563333D02*
Y560000D01*
G01Y564667D02*
X843033Y564750D01*
Y564917D01*
X843200Y565000D01*
X843367Y564917D01*
Y564750D01*
X843200Y564667D01*
G01X850133Y562917D02*
X849550Y563250D01*
X849050Y563333D01*
X848383Y563167D01*
X847883Y562833D01*
X847550Y562250D01*
X847467Y561667D01*
X847550Y561083D01*
X847883Y560583D01*
X848383Y560167D01*
X849050Y560000D01*
X849633Y560167D01*
X850133Y560500D01*
G01X852983Y560000D02*
Y565000D01*
G01Y562583D02*
X853400Y563000D01*
X853817Y563250D01*
X854483Y563333D01*
X854983Y563250D01*
X855567Y562917D01*
X855817Y562417D01*
Y560000D01*
G01X864350Y560583D02*
X864767Y560250D01*
X865350Y560000D01*
X865850D01*
X866350Y560167D01*
X866683Y560417D01*
X866850Y560750D01*
X866767Y561250D01*
X866433Y561500D01*
X864933Y562000D01*
X864600Y562583D01*
X864767Y563000D01*
X865100Y563250D01*
X865600Y563333D01*
X866100Y563250D01*
X866600Y563000D01*
G01X871200Y563333D02*
Y560000D01*
G01Y564667D02*
X871033Y564750D01*
Y564917D01*
X871200Y565000D01*
X871367Y564917D01*
Y564750D01*
X871200Y564667D01*
G01X875550Y563333D02*
X878050D01*
X875550Y560000D01*
X878050D01*
G01X881150Y562250D02*
X883817D01*
X883567Y562833D01*
X883150Y563167D01*
X882567Y563333D01*
X881983Y563250D01*
X881483Y563000D01*
X881150Y562417D01*
X880983Y561917D01*
Y561417D01*
X881150Y560917D01*
X881567Y560417D01*
X882067Y560083D01*
X882650Y560000D01*
X883233Y560167D01*
X883817Y560667D01*
G01X893600Y563333D02*
Y560000D01*
G01Y564667D02*
X893433Y564750D01*
Y564917D01*
X893600Y565000D01*
X893767Y564917D01*
Y564750D01*
X893600Y564667D01*
G01X897950Y560583D02*
X898367Y560250D01*
X898950Y560000D01*
X899450D01*
X899950Y560167D01*
X900283Y560417D01*
X900450Y560750D01*
X900367Y561250D01*
X900033Y561500D01*
X898533Y562000D01*
X898200Y562583D01*
X898367Y563000D01*
X898700Y563250D01*
X899200Y563333D01*
X899700Y563250D01*
X900200Y563000D01*
G01X908900Y560000D02*
Y565000D01*
G01Y562500D02*
X909317Y563000D01*
X909817Y563250D01*
X910317Y563333D01*
X911067Y563167D01*
X911567Y562833D01*
X911900Y562250D01*
Y561583D01*
X911733Y560917D01*
X911400Y560417D01*
X910817Y560083D01*
X910317Y560000D01*
X909817Y560083D01*
X909317Y560333D01*
X908900Y560750D01*
G01X916000Y563333D02*
Y560000D01*
G01Y564667D02*
X915833Y564750D01*
Y564917D01*
X916000Y565000D01*
X916167Y564917D01*
Y564750D01*
X916000Y564667D01*
G01X920433Y558750D02*
X921017Y558417D01*
X921683Y558333D01*
X922267Y558417D01*
X922767Y558833D01*
X923100Y559417D01*
Y563333D01*
G01Y562667D02*
X922767Y563000D01*
X922267Y563250D01*
X921683Y563333D01*
X921017Y563167D01*
X920600Y562833D01*
X920267Y562250D01*
X920100Y561667D01*
X920183Y561167D01*
X920517Y560583D01*
X921017Y560167D01*
X921683Y560000D01*
X922183Y560083D01*
X922767Y560417D01*
X923100Y560750D01*
G01X926033Y558750D02*
X926617Y558417D01*
X927283Y558333D01*
X927867Y558417D01*
X928367Y558833D01*
X928700Y559417D01*
Y563333D01*
G01Y562667D02*
X928367Y563000D01*
X927867Y563250D01*
X927283Y563333D01*
X926617Y563167D01*
X926200Y562833D01*
X925867Y562250D01*
X925700Y561667D01*
X925783Y561167D01*
X926117Y560583D01*
X926617Y560167D01*
X927283Y560000D01*
X927783Y560083D01*
X928367Y560417D01*
X928700Y560750D01*
G01X931550Y562250D02*
X934217D01*
X933967Y562833D01*
X933550Y563167D01*
X932967Y563333D01*
X932383Y563250D01*
X931883Y563000D01*
X931550Y562417D01*
X931383Y561917D01*
Y561417D01*
X931550Y560917D01*
X931967Y560417D01*
X932467Y560083D01*
X933050Y560000D01*
X933633Y560167D01*
X934217Y560667D01*
G01X937233Y560000D02*
Y563333D01*
G01Y562667D02*
X937650Y563000D01*
X938067Y563250D01*
X938650Y563333D01*
X939067Y563250D01*
X939567Y563000D01*
G01X949600Y565000D02*
Y560000D01*
G01X948433Y563333D02*
X950767D01*
G01X953783Y560000D02*
Y565000D01*
G01Y562583D02*
X954200Y563000D01*
X954617Y563250D01*
X955283Y563333D01*
X955783Y563250D01*
X956367Y562917D01*
X956617Y562417D01*
Y560000D01*
G01X962300D02*
Y563333D01*
G01Y562750D02*
X961967Y563083D01*
X961467Y563250D01*
X960883Y563333D01*
X960300Y563167D01*
X959800Y562833D01*
X959467Y562333D01*
X959300Y561667D01*
X959467Y561000D01*
X959800Y560500D01*
X960300Y560167D01*
X960883Y560000D01*
X961467Y560083D01*
X961967Y560333D01*
X962300Y560667D01*
G01X964983Y560000D02*
Y563333D01*
G01Y562500D02*
X965317Y562917D01*
X965817Y563250D01*
X966483Y563333D01*
X967067Y563250D01*
X967567Y562917D01*
X967817Y562333D01*
Y560000D01*
G01X979100D02*
Y563333D01*
G01Y562750D02*
X978767Y563083D01*
X978267Y563250D01*
X977683Y563333D01*
X977100Y563167D01*
X976600Y562833D01*
X976267Y562333D01*
X976100Y561667D01*
X976267Y561000D01*
X976600Y560500D01*
X977100Y560167D01*
X977683Y560000D01*
X978267Y560083D01*
X978767Y560333D01*
X979100Y560667D01*
G01X981783Y560000D02*
Y563333D01*
G01Y562500D02*
X982117Y562917D01*
X982617Y563250D01*
X983283Y563333D01*
X983867Y563250D01*
X984367Y562917D01*
X984617Y562333D01*
Y560000D01*
G01X987383D02*
Y563333D01*
G01Y562500D02*
X987717Y562917D01*
X988217Y563250D01*
X988883Y563333D01*
X989467Y563250D01*
X989967Y562917D01*
X990217Y562333D01*
Y560000D01*
G01X992983Y563333D02*
Y561000D01*
X993317Y560417D01*
X993817Y560083D01*
X994400Y560000D01*
X994983Y560083D01*
X995483Y560417D01*
X995817Y561000D01*
G01Y560000D02*
Y563333D01*
G01X1001500Y560000D02*
Y563333D01*
G01Y562750D02*
X1001167Y563083D01*
X1000667Y563250D01*
X1000083Y563333D01*
X999500Y563167D01*
X999000Y562833D01*
X998667Y562333D01*
X998500Y561667D01*
X998667Y561000D01*
X999000Y560500D01*
X999500Y560167D01*
X1000083Y560000D01*
X1000667Y560083D01*
X1001167Y560333D01*
X1001500Y560667D01*
G01X1005600Y560000D02*
Y565000D01*
G01X822000Y569000D02*
Y574000D01*
X821000Y573000D01*
G01Y569000D02*
X823000D01*
G01X827600Y568833D02*
X827433Y568917D01*
Y569083D01*
X827600Y569167D01*
X827767Y569083D01*
Y568917D01*
X827600Y568833D01*
G01X833200Y569000D02*
X832533Y569083D01*
X831950Y569417D01*
X831450Y569917D01*
X831117Y570500D01*
X830950Y571167D01*
Y571833D01*
X831117Y572500D01*
X831450Y573083D01*
X831950Y573583D01*
X832533Y573917D01*
X833200Y574000D01*
X833867Y573917D01*
X834450Y573583D01*
X834950Y573083D01*
X835283Y572500D01*
X835450Y571833D01*
Y571167D01*
X835283Y570500D01*
X834950Y569917D01*
X834450Y569417D01*
X833867Y569083D01*
X833200Y569000D01*
G01X837383D02*
Y572333D01*
G01Y571500D02*
X837717Y571917D01*
X838217Y572250D01*
X838883Y572333D01*
X839467Y572250D01*
X839967Y571917D01*
X840217Y571333D01*
Y569000D01*
G01X843150Y571250D02*
X845817D01*
X845567Y571833D01*
X845150Y572167D01*
X844567Y572333D01*
X843983Y572250D01*
X843483Y572000D01*
X843150Y571417D01*
X842983Y570917D01*
Y570417D01*
X843150Y569917D01*
X843567Y569417D01*
X844067Y569083D01*
X844650Y569000D01*
X845233Y569167D01*
X845817Y569667D01*
G01X854350Y569583D02*
X854767Y569250D01*
X855350Y569000D01*
X855850D01*
X856350Y569167D01*
X856683Y569417D01*
X856850Y569750D01*
X856767Y570250D01*
X856433Y570500D01*
X854933Y571000D01*
X854600Y571583D01*
X854767Y572000D01*
X855100Y572250D01*
X855600Y572333D01*
X856100Y572250D01*
X856600Y572000D01*
G01X861200Y572333D02*
Y569000D01*
G01Y573667D02*
X861033Y573750D01*
Y573917D01*
X861200Y574000D01*
X861367Y573917D01*
Y573750D01*
X861200Y573667D01*
G01X868300Y574000D02*
Y569000D01*
G01Y569750D02*
X867967Y569333D01*
X867467Y569083D01*
X866883Y569000D01*
X866217Y569167D01*
X865717Y569583D01*
X865383Y570083D01*
X865300Y570667D01*
X865383Y571250D01*
X865717Y571750D01*
X866217Y572167D01*
X866883Y572333D01*
X867467Y572250D01*
X867883Y572083D01*
X868300Y571750D01*
G01X871150Y571250D02*
X873817D01*
X873567Y571833D01*
X873150Y572167D01*
X872567Y572333D01*
X871983Y572250D01*
X871483Y572000D01*
X871150Y571417D01*
X870983Y570917D01*
Y570417D01*
X871150Y569917D01*
X871567Y569417D01*
X872067Y569083D01*
X872650Y569000D01*
X873233Y569167D01*
X873817Y569667D01*
G01X881517Y572333D02*
X882517Y569000D01*
X883600Y572333D01*
X884683Y569000D01*
X885683Y572333D01*
G01X889200D02*
Y569000D01*
G01Y573667D02*
X889033Y573750D01*
Y573917D01*
X889200Y574000D01*
X889367Y573917D01*
Y573750D01*
X889200Y573667D01*
G01X894800Y574000D02*
Y569000D01*
G01X893633Y572333D02*
X895967D01*
G01X898983Y569000D02*
Y574000D01*
G01Y571583D02*
X899400Y572000D01*
X899817Y572250D01*
X900483Y572333D01*
X900983Y572250D01*
X901567Y571917D01*
X901817Y571417D01*
Y569000D01*
G01X910350Y569583D02*
X910767Y569250D01*
X911350Y569000D01*
X911850D01*
X912350Y569167D01*
X912683Y569417D01*
X912850Y569750D01*
X912767Y570250D01*
X912433Y570500D01*
X910933Y571000D01*
X910600Y571583D01*
X910767Y572000D01*
X911100Y572250D01*
X911600Y572333D01*
X912100Y572250D01*
X912600Y572000D01*
G01X917200Y569000D02*
X916700Y569083D01*
X916200Y569417D01*
X915867Y570000D01*
X915700Y570667D01*
X915867Y571333D01*
X916200Y571917D01*
X916700Y572250D01*
X917200Y572333D01*
X917700Y572250D01*
X918200Y571917D01*
X918533Y571333D01*
X918617Y570667D01*
X918533Y570000D01*
X918200Y569417D01*
X917700Y569083D01*
X917200Y569000D01*
G01X922800D02*
Y574000D01*
G01X929900D02*
Y569000D01*
G01Y569750D02*
X929567Y569333D01*
X929067Y569083D01*
X928483Y569000D01*
X927817Y569167D01*
X927317Y569583D01*
X926983Y570083D01*
X926900Y570667D01*
X926983Y571250D01*
X927317Y571750D01*
X927817Y572167D01*
X928483Y572333D01*
X929067Y572250D01*
X929483Y572083D01*
X929900Y571750D01*
G01X932750Y571250D02*
X935417D01*
X935167Y571833D01*
X934750Y572167D01*
X934167Y572333D01*
X933583Y572250D01*
X933083Y572000D01*
X932750Y571417D01*
X932583Y570917D01*
Y570417D01*
X932750Y569917D01*
X933167Y569417D01*
X933667Y569083D01*
X934250Y569000D01*
X934833Y569167D01*
X935417Y569667D01*
G01X938433Y569000D02*
Y572333D01*
G01Y571667D02*
X938850Y572000D01*
X939267Y572250D01*
X939850Y572333D01*
X940267Y572250D01*
X940767Y572000D01*
G01X948300Y569000D02*
Y572333D01*
G01Y571417D02*
X948550Y571833D01*
X948967Y572167D01*
X949550Y572333D01*
X950133Y572167D01*
X950550Y571833D01*
X950800Y571417D01*
Y569000D01*
G01Y571417D02*
X951050Y571833D01*
X951467Y572167D01*
X952050Y572333D01*
X952633Y572167D01*
X953050Y571833D01*
X953300Y571333D01*
Y569000D01*
G01X957900D02*
Y572333D01*
G01Y571750D02*
X957567Y572083D01*
X957067Y572250D01*
X956483Y572333D01*
X955900Y572167D01*
X955400Y571833D01*
X955067Y571333D01*
X954900Y570667D01*
X955067Y570000D01*
X955400Y569500D01*
X955900Y569167D01*
X956483Y569000D01*
X957067Y569083D01*
X957567Y569333D01*
X957900Y569667D01*
G01X960750Y569583D02*
X961167Y569250D01*
X961750Y569000D01*
X962250D01*
X962750Y569167D01*
X963083Y569417D01*
X963250Y569750D01*
X963167Y570250D01*
X962833Y570500D01*
X961333Y571000D01*
X961000Y571583D01*
X961167Y572000D01*
X961500Y572250D01*
X962000Y572333D01*
X962500Y572250D01*
X963000Y572000D01*
G01X966183Y569000D02*
Y574000D01*
G01X968850Y572333D02*
X966183Y570417D01*
G01X967267Y571167D02*
X969017Y569000D01*
G01X977300Y567333D02*
Y572333D01*
G01Y571583D02*
X977717Y572000D01*
X978133Y572250D01*
X978800Y572333D01*
X979383Y572250D01*
X979967Y571833D01*
X980217Y571250D01*
X980300Y570667D01*
X980217Y570083D01*
X979967Y569500D01*
X979467Y569167D01*
X978800Y569000D01*
X978217Y569083D01*
X977633Y569333D01*
X977300Y569667D01*
G01X985900Y569000D02*
Y572333D01*
G01Y571750D02*
X985567Y572083D01*
X985067Y572250D01*
X984483Y572333D01*
X983900Y572167D01*
X983400Y571833D01*
X983067Y571333D01*
X982900Y570667D01*
X983067Y570000D01*
X983400Y569500D01*
X983900Y569167D01*
X984483Y569000D01*
X985067Y569083D01*
X985567Y569333D01*
X985900Y569667D01*
G01X991500Y574000D02*
Y569000D01*
G01Y569750D02*
X991167Y569333D01*
X990667Y569083D01*
X990083Y569000D01*
X989417Y569167D01*
X988917Y569583D01*
X988583Y570083D01*
X988500Y570667D01*
X988583Y571250D01*
X988917Y571750D01*
X989417Y572167D01*
X990083Y572333D01*
X990667Y572250D01*
X991083Y572083D01*
X991500Y571750D01*
G01X831333Y551000D02*
Y554333D01*
G01Y553667D02*
X831750Y554000D01*
X832167Y554250D01*
X832750Y554333D01*
X833167Y554250D01*
X833667Y554000D01*
G01X838100Y554333D02*
Y551000D01*
G01Y555667D02*
X837933Y555750D01*
Y555917D01*
X838100Y556000D01*
X838267Y555917D01*
Y555750D01*
X838100Y555667D01*
G01X842283Y551000D02*
Y554333D01*
G01Y553500D02*
X842617Y553917D01*
X843117Y554250D01*
X843783Y554333D01*
X844367Y554250D01*
X844867Y553917D01*
X845117Y553333D01*
Y551000D01*
G01X848133Y549750D02*
X848717Y549417D01*
X849383Y549333D01*
X849967Y549417D01*
X850467Y549833D01*
X850800Y550417D01*
Y554333D01*
G01Y553667D02*
X850467Y554000D01*
X849967Y554250D01*
X849383Y554333D01*
X848717Y554167D01*
X848300Y553833D01*
X847967Y553250D01*
X847800Y552667D01*
X847883Y552167D01*
X848217Y551583D01*
X848717Y551167D01*
X849383Y551000D01*
X849883Y551083D01*
X850467Y551417D01*
X850800Y551750D01*
G01X859250Y551583D02*
X859667Y551250D01*
X860250Y551000D01*
X860750D01*
X861250Y551167D01*
X861583Y551417D01*
X861750Y551750D01*
X861667Y552250D01*
X861333Y552500D01*
X859833Y553000D01*
X859500Y553583D01*
X859667Y554000D01*
X860000Y554250D01*
X860500Y554333D01*
X861000Y554250D01*
X861500Y554000D01*
G01X866100Y554333D02*
Y551000D01*
G01Y555667D02*
X865933Y555750D01*
Y555917D01*
X866100Y556000D01*
X866267Y555917D01*
Y555750D01*
X866100Y555667D01*
G01X870450Y554333D02*
X872950D01*
X870450Y551000D01*
X872950D01*
G01X876050Y553250D02*
X878717D01*
X878467Y553833D01*
X878050Y554167D01*
X877467Y554333D01*
X876883Y554250D01*
X876383Y554000D01*
X876050Y553417D01*
X875883Y552917D01*
Y552417D01*
X876050Y551917D01*
X876467Y551417D01*
X876967Y551083D01*
X877550Y551000D01*
X878133Y551167D01*
X878717Y551667D01*
G01X888333Y550083D02*
X888667Y551167D01*
G01X794500Y674500D02*
Y669500D01*
G01X793333Y672833D02*
X795667D01*
G01X798683Y669500D02*
Y674500D01*
G01Y672083D02*
X799100Y672500D01*
X799517Y672750D01*
X800183Y672833D01*
X800683Y672750D01*
X801267Y672417D01*
X801517Y671917D01*
Y669500D01*
G01X805700Y672833D02*
Y669500D01*
G01Y674167D02*
X805533Y674250D01*
Y674417D01*
X805700Y674500D01*
X805867Y674417D01*
Y674250D01*
X805700Y674167D01*
G01X812633Y672417D02*
X812050Y672750D01*
X811550Y672833D01*
X810883Y672667D01*
X810383Y672333D01*
X810050Y671750D01*
X809967Y671167D01*
X810050Y670583D01*
X810383Y670083D01*
X810883Y669667D01*
X811550Y669500D01*
X812133Y669667D01*
X812633Y670000D01*
G01X815483Y669500D02*
Y674500D01*
G01X818150Y672833D02*
X815483Y670917D01*
G01X816567Y671667D02*
X818317Y669500D01*
G01X821083D02*
Y672833D01*
G01Y672000D02*
X821417Y672417D01*
X821917Y672750D01*
X822583Y672833D01*
X823167Y672750D01*
X823667Y672417D01*
X823917Y671833D01*
Y669500D01*
G01X826850Y671750D02*
X829517D01*
X829267Y672333D01*
X828850Y672667D01*
X828267Y672833D01*
X827683Y672750D01*
X827183Y672500D01*
X826850Y671917D01*
X826683Y671417D01*
Y670917D01*
X826850Y670417D01*
X827267Y669917D01*
X827767Y669583D01*
X828350Y669500D01*
X828933Y669667D01*
X829517Y670167D01*
G01X832450Y670083D02*
X832867Y669750D01*
X833450Y669500D01*
X833950D01*
X834450Y669667D01*
X834783Y669917D01*
X834950Y670250D01*
X834867Y670750D01*
X834533Y671000D01*
X833033Y671500D01*
X832700Y672083D01*
X832867Y672500D01*
X833200Y672750D01*
X833700Y672833D01*
X834200Y672750D01*
X834700Y672500D01*
G01X838050Y670083D02*
X838467Y669750D01*
X839050Y669500D01*
X839550D01*
X840050Y669667D01*
X840383Y669917D01*
X840550Y670250D01*
X840467Y670750D01*
X840133Y671000D01*
X838633Y671500D01*
X838300Y672083D01*
X838467Y672500D01*
X838800Y672750D01*
X839300Y672833D01*
X839800Y672750D01*
X840300Y672500D01*
G01X809000Y686500D02*
Y691500D01*
G01Y689000D02*
X809417Y689500D01*
X809917Y689750D01*
X810417Y689833D01*
X811167Y689667D01*
X811667Y689333D01*
X812000Y688750D01*
Y688083D01*
X811833Y687417D01*
X811500Y686917D01*
X810917Y686583D01*
X810417Y686500D01*
X809917Y686583D01*
X809417Y686833D01*
X809000Y687250D01*
G01X816100Y686500D02*
X815600Y686583D01*
X815100Y686917D01*
X814767Y687500D01*
X814600Y688167D01*
X814767Y688833D01*
X815100Y689417D01*
X815600Y689750D01*
X816100Y689833D01*
X816600Y689750D01*
X817100Y689417D01*
X817433Y688833D01*
X817517Y688167D01*
X817433Y687500D01*
X817100Y686917D01*
X816600Y686583D01*
X816100Y686500D01*
G01X823200D02*
Y689833D01*
G01Y689250D02*
X822867Y689583D01*
X822367Y689750D01*
X821783Y689833D01*
X821200Y689667D01*
X820700Y689333D01*
X820367Y688833D01*
X820200Y688167D01*
X820367Y687500D01*
X820700Y687000D01*
X821200Y686667D01*
X821783Y686500D01*
X822367Y686583D01*
X822867Y686833D01*
X823200Y687167D01*
G01X826133Y686500D02*
Y689833D01*
G01Y689167D02*
X826550Y689500D01*
X826967Y689750D01*
X827550Y689833D01*
X827967Y689750D01*
X828467Y689500D01*
G01X834400Y691500D02*
Y686500D01*
G01Y687250D02*
X834067Y686833D01*
X833567Y686583D01*
X832983Y686500D01*
X832317Y686667D01*
X831817Y687083D01*
X831483Y687583D01*
X831400Y688167D01*
X831483Y688750D01*
X831817Y689250D01*
X832317Y689667D01*
X832983Y689833D01*
X833567Y689750D01*
X833983Y689583D01*
X834400Y689250D01*
G01X843083Y734500D02*
Y739500D01*
G01Y737083D02*
X843500Y737500D01*
X843917Y737750D01*
X844583Y737833D01*
X845083Y737750D01*
X845667Y737417D01*
X845917Y736917D01*
Y734500D01*
G01X851600D02*
Y737833D01*
G01Y737250D02*
X851267Y737583D01*
X850767Y737750D01*
X850183Y737833D01*
X849600Y737667D01*
X849100Y737333D01*
X848767Y736833D01*
X848600Y736167D01*
X848767Y735500D01*
X849100Y735000D01*
X849600Y734667D01*
X850183Y734500D01*
X850767Y734583D01*
X851267Y734833D01*
X851600Y735167D01*
G01X855700Y734500D02*
Y739500D01*
G01X860800Y734500D02*
Y738750D01*
X860967Y739167D01*
X861300Y739417D01*
X861800Y739500D01*
X862300Y739333D01*
X862550Y738917D01*
G01X861550Y737500D02*
X859883D01*
G01X871000Y732833D02*
Y737833D01*
G01Y737083D02*
X871417Y737500D01*
X871833Y737750D01*
X872500Y737833D01*
X873083Y737750D01*
X873667Y737333D01*
X873917Y736750D01*
X874000Y736167D01*
X873917Y735583D01*
X873667Y735000D01*
X873167Y734667D01*
X872500Y734500D01*
X871917Y734583D01*
X871333Y734833D01*
X871000Y735167D01*
G01X878100Y734500D02*
Y739500D01*
G01X882283Y737833D02*
Y735500D01*
X882617Y734917D01*
X883117Y734583D01*
X883700Y734500D01*
X884283Y734583D01*
X884783Y734917D01*
X885117Y735500D01*
G01Y734500D02*
Y737833D01*
G01X888133Y733250D02*
X888717Y732917D01*
X889383Y732833D01*
X889967Y732917D01*
X890467Y733333D01*
X890800Y733917D01*
Y737833D01*
G01Y737167D02*
X890467Y737500D01*
X889967Y737750D01*
X889383Y737833D01*
X888717Y737667D01*
X888300Y737333D01*
X887967Y736750D01*
X887800Y736167D01*
X887883Y735667D01*
X888217Y735083D01*
X888717Y734667D01*
X889383Y734500D01*
X889883Y734583D01*
X890467Y734917D01*
X890800Y735250D01*
G01X893733Y733250D02*
X894317Y732917D01*
X894983Y732833D01*
X895567Y732917D01*
X896067Y733333D01*
X896400Y733917D01*
Y737833D01*
G01Y737167D02*
X896067Y737500D01*
X895567Y737750D01*
X894983Y737833D01*
X894317Y737667D01*
X893900Y737333D01*
X893567Y736750D01*
X893400Y736167D01*
X893483Y735667D01*
X893817Y735083D01*
X894317Y734667D01*
X894983Y734500D01*
X895483Y734583D01*
X896067Y734917D01*
X896400Y735250D01*
G01X900500Y737833D02*
Y734500D01*
G01Y739167D02*
X900333Y739250D01*
Y739417D01*
X900500Y739500D01*
X900667Y739417D01*
Y739250D01*
X900500Y739167D01*
G01X904683Y734500D02*
Y737833D01*
G01Y737000D02*
X905017Y737417D01*
X905517Y737750D01*
X906183Y737833D01*
X906767Y737750D01*
X907267Y737417D01*
X907517Y736833D01*
Y734500D01*
G01X910533Y733250D02*
X911117Y732917D01*
X911783Y732833D01*
X912367Y732917D01*
X912867Y733333D01*
X913200Y733917D01*
Y737833D01*
G01Y737167D02*
X912867Y737500D01*
X912367Y737750D01*
X911783Y737833D01*
X911117Y737667D01*
X910700Y737333D01*
X910367Y736750D01*
X910200Y736167D01*
X910283Y735667D01*
X910617Y735083D01*
X911117Y734667D01*
X911783Y734500D01*
X912283Y734583D01*
X912867Y734917D01*
X913200Y735250D01*
G01X798500Y795500D02*
Y790500D01*
G01X796583Y795500D02*
X800417D01*
G01X802017Y793833D02*
X803017Y790500D01*
X804100Y793833D01*
X805183Y790500D01*
X806183Y793833D01*
G01X809700D02*
Y790500D01*
G01Y795167D02*
X809533Y795250D01*
Y795417D01*
X809700Y795500D01*
X809867Y795417D01*
Y795250D01*
X809700Y795167D01*
G01X814050Y791083D02*
X814467Y790750D01*
X815050Y790500D01*
X815550D01*
X816050Y790667D01*
X816383Y790917D01*
X816550Y791250D01*
X816467Y791750D01*
X816133Y792000D01*
X814633Y792500D01*
X814300Y793083D01*
X814467Y793500D01*
X814800Y793750D01*
X815300Y793833D01*
X815800Y793750D01*
X816300Y793500D01*
G01X820900Y795500D02*
Y790500D01*
G01X819733Y793833D02*
X822067D01*
G01X833600Y790500D02*
Y793833D01*
G01Y793250D02*
X833267Y793583D01*
X832767Y793750D01*
X832183Y793833D01*
X831600Y793667D01*
X831100Y793333D01*
X830767Y792833D01*
X830600Y792167D01*
X830767Y791500D01*
X831100Y791000D01*
X831600Y790667D01*
X832183Y790500D01*
X832767Y790583D01*
X833267Y790833D01*
X833600Y791167D01*
G01X836283Y790500D02*
Y793833D01*
G01Y793000D02*
X836617Y793417D01*
X837117Y793750D01*
X837783Y793833D01*
X838367Y793750D01*
X838867Y793417D01*
X839117Y792833D01*
Y790500D01*
G01X844800Y795500D02*
Y790500D01*
G01Y791250D02*
X844467Y790833D01*
X843967Y790583D01*
X843383Y790500D01*
X842717Y790667D01*
X842217Y791083D01*
X841883Y791583D01*
X841800Y792167D01*
X841883Y792750D01*
X842217Y793250D01*
X842717Y793667D01*
X843383Y793833D01*
X843967Y793750D01*
X844383Y793583D01*
X844800Y793250D01*
G01X853000Y790500D02*
Y795500D01*
G01Y793000D02*
X853417Y793500D01*
X853917Y793750D01*
X854417Y793833D01*
X855167Y793667D01*
X855667Y793333D01*
X856000Y792750D01*
Y792083D01*
X855833Y791417D01*
X855500Y790917D01*
X854917Y790583D01*
X854417Y790500D01*
X853917Y790583D01*
X853417Y790833D01*
X853000Y791250D01*
G01X860100Y790500D02*
X859600Y790583D01*
X859100Y790917D01*
X858767Y791500D01*
X858600Y792167D01*
X858767Y792833D01*
X859100Y793417D01*
X859600Y793750D01*
X860100Y793833D01*
X860600Y793750D01*
X861100Y793417D01*
X861433Y792833D01*
X861517Y792167D01*
X861433Y791500D01*
X861100Y790917D01*
X860600Y790583D01*
X860100Y790500D01*
G01X863617Y793833D02*
X864617Y790500D01*
X865700Y793833D01*
X866783Y790500D01*
X867783Y793833D01*
G01X796833Y826500D02*
Y831500D01*
X798917D01*
X799583Y831250D01*
X800000Y830917D01*
X800167Y830250D01*
X800000Y829583D01*
X799500Y829167D01*
X798917Y828917D01*
X796833D01*
G01X798917D02*
X800167Y826500D01*
G01X804100D02*
X803600Y826583D01*
X803100Y826917D01*
X802767Y827500D01*
X802600Y828167D01*
X802767Y828833D01*
X803100Y829417D01*
X803600Y829750D01*
X804100Y829833D01*
X804600Y829750D01*
X805100Y829417D01*
X805433Y828833D01*
X805517Y828167D01*
X805433Y827500D01*
X805100Y826917D01*
X804600Y826583D01*
X804100Y826500D01*
G01X808283Y829833D02*
Y827500D01*
X808617Y826917D01*
X809117Y826583D01*
X809700Y826500D01*
X810283Y826583D01*
X810783Y826917D01*
X811117Y827500D01*
G01Y826500D02*
Y829833D01*
G01X815300Y831500D02*
Y826500D01*
G01X814133Y829833D02*
X816467D01*
G01X820900D02*
Y826500D01*
G01Y831167D02*
X820733Y831250D01*
Y831417D01*
X820900Y831500D01*
X821067Y831417D01*
Y831250D01*
X820900Y831167D01*
G01X825083Y826500D02*
Y829833D01*
G01Y829000D02*
X825417Y829417D01*
X825917Y829750D01*
X826583Y829833D01*
X827167Y829750D01*
X827667Y829417D01*
X827917Y828833D01*
Y826500D01*
G01X830933Y825250D02*
X831517Y824917D01*
X832183Y824833D01*
X832767Y824917D01*
X833267Y825333D01*
X833600Y825917D01*
Y829833D01*
G01Y829167D02*
X833267Y829500D01*
X832767Y829750D01*
X832183Y829833D01*
X831517Y829667D01*
X831100Y829333D01*
X830767Y828750D01*
X830600Y828167D01*
X830683Y827667D01*
X831017Y827083D01*
X831517Y826667D01*
X832183Y826500D01*
X832683Y826583D01*
X833267Y826917D01*
X833600Y827250D01*
G01X843300Y831500D02*
Y826500D01*
G01X842133Y829833D02*
X844467D01*
G01X848900Y826500D02*
X848400Y826583D01*
X847900Y826917D01*
X847567Y827500D01*
X847400Y828167D01*
X847567Y828833D01*
X847900Y829417D01*
X848400Y829750D01*
X848900Y829833D01*
X849400Y829750D01*
X849900Y829417D01*
X850233Y828833D01*
X850317Y828167D01*
X850233Y827500D01*
X849900Y826917D01*
X849400Y826583D01*
X848900Y826500D01*
G01X854500D02*
Y831500D01*
G01X858850Y828750D02*
X861517D01*
X861267Y829333D01*
X860850Y829667D01*
X860267Y829833D01*
X859683Y829750D01*
X859183Y829500D01*
X858850Y828917D01*
X858683Y828417D01*
Y827917D01*
X858850Y827417D01*
X859267Y826917D01*
X859767Y826583D01*
X860350Y826500D01*
X860933Y826667D01*
X861517Y827167D01*
G01X864533Y826500D02*
Y829833D01*
G01Y829167D02*
X864950Y829500D01*
X865367Y829750D01*
X865950Y829833D01*
X866367Y829750D01*
X866867Y829500D01*
G01X872800Y826500D02*
Y829833D01*
G01Y829250D02*
X872467Y829583D01*
X871967Y829750D01*
X871383Y829833D01*
X870800Y829667D01*
X870300Y829333D01*
X869967Y828833D01*
X869800Y828167D01*
X869967Y827500D01*
X870300Y827000D01*
X870800Y826667D01*
X871383Y826500D01*
X871967Y826583D01*
X872467Y826833D01*
X872800Y827167D01*
G01X875483Y826500D02*
Y829833D01*
G01Y829000D02*
X875817Y829417D01*
X876317Y829750D01*
X876983Y829833D01*
X877567Y829750D01*
X878067Y829417D01*
X878317Y828833D01*
Y826500D01*
G01X883833Y829417D02*
X883250Y829750D01*
X882750Y829833D01*
X882083Y829667D01*
X881583Y829333D01*
X881250Y828750D01*
X881167Y828167D01*
X881250Y827583D01*
X881583Y827083D01*
X882083Y826667D01*
X882750Y826500D01*
X883333Y826667D01*
X883833Y827000D01*
G01X886850Y828750D02*
X889517D01*
X889267Y829333D01*
X888850Y829667D01*
X888267Y829833D01*
X887683Y829750D01*
X887183Y829500D01*
X886850Y828917D01*
X886683Y828417D01*
Y827917D01*
X886850Y827417D01*
X887267Y826917D01*
X887767Y826583D01*
X888350Y826500D01*
X888933Y826667D01*
X889517Y827167D01*
G01X788000Y850610D02*
Y782110D01*
G01Y805500D02*
X1343000D01*
G01X928583Y23083D02*
X929167Y22667D01*
X929833Y22500D01*
X930500Y22667D01*
X931083Y23167D01*
X931500Y23917D01*
X931667Y24667D01*
Y25583D01*
X931500Y26333D01*
X931083Y27000D01*
X930583Y27333D01*
X930000Y27500D01*
X929333Y27333D01*
X928833Y27000D01*
X928500Y26500D01*
X928333Y25833D01*
X928500Y25250D01*
X928917Y24667D01*
X929417Y24333D01*
X930000Y24250D01*
X930667Y24417D01*
X931167Y24833D01*
X931667Y25583D01*
G01X934017Y24583D02*
X934600Y25167D01*
X935100Y25500D01*
X935767Y25667D01*
X936350Y25500D01*
X936767Y25167D01*
X937100Y24667D01*
X937183Y24083D01*
X937100Y23583D01*
X936767Y23083D01*
X936267Y22667D01*
X935683Y22500D01*
X935017Y22667D01*
X934433Y23167D01*
X934100Y23917D01*
X934017Y24750D01*
X934183Y25833D01*
X934433Y26417D01*
X934850Y27000D01*
X935433Y27417D01*
X936017Y27500D01*
X936600Y27333D01*
X937017Y26917D01*
G01X909000Y67500D02*
Y72500D01*
X905917Y68917D01*
X910083D01*
G01X911767Y68250D02*
X912267Y67833D01*
X912850Y67583D01*
X913600Y67500D01*
X914350Y67667D01*
X914933Y68000D01*
X915350Y68583D01*
X915433Y69250D01*
X915267Y69917D01*
X914850Y70333D01*
X914267Y70667D01*
X913683Y70750D01*
X913100Y70667D01*
X912350Y70333D01*
X912600Y72500D01*
X914850D01*
G01X909250Y184083D02*
X909667Y183750D01*
X910250Y183500D01*
X910750D01*
X911250Y183667D01*
X911583Y183917D01*
X911750Y184250D01*
X911667Y184750D01*
X911333Y185000D01*
X909833Y185500D01*
X909500Y186083D01*
X909667Y186500D01*
X910000Y186750D01*
X910500Y186833D01*
X911000Y186750D01*
X911500Y186500D01*
G01X916100Y188500D02*
Y183500D01*
G01X914933Y186833D02*
X917267D01*
G01X920283D02*
Y184500D01*
X920617Y183917D01*
X921117Y183583D01*
X921700Y183500D01*
X922283Y183583D01*
X922783Y183917D01*
X923117Y184500D01*
G01Y183500D02*
Y186833D01*
G01X925800Y183500D02*
Y188500D01*
G01Y186000D02*
X926217Y186500D01*
X926717Y186750D01*
X927217Y186833D01*
X927967Y186667D01*
X928467Y186333D01*
X928800Y185750D01*
Y185083D01*
X928633Y184417D01*
X928300Y183917D01*
X927717Y183583D01*
X927217Y183500D01*
X926717Y183583D01*
X926217Y183833D01*
X925800Y184250D01*
G01X938500Y183500D02*
Y188500D01*
G01X942850Y185750D02*
X945517D01*
X945267Y186333D01*
X944850Y186667D01*
X944267Y186833D01*
X943683Y186750D01*
X943183Y186500D01*
X942850Y185917D01*
X942683Y185417D01*
Y184917D01*
X942850Y184417D01*
X943267Y183917D01*
X943767Y183583D01*
X944350Y183500D01*
X944933Y183667D01*
X945517Y184167D01*
G01X948283Y183500D02*
Y186833D01*
G01Y186000D02*
X948617Y186417D01*
X949117Y186750D01*
X949783Y186833D01*
X950367Y186750D01*
X950867Y186417D01*
X951117Y185833D01*
Y183500D01*
G01X954133Y182250D02*
X954717Y181917D01*
X955383Y181833D01*
X955967Y181917D01*
X956467Y182333D01*
X956800Y182917D01*
Y186833D01*
G01Y186167D02*
X956467Y186500D01*
X955967Y186750D01*
X955383Y186833D01*
X954717Y186667D01*
X954300Y186333D01*
X953967Y185750D01*
X953800Y185167D01*
X953883Y184667D01*
X954217Y184083D01*
X954717Y183667D01*
X955383Y183500D01*
X955883Y183583D01*
X956467Y183917D01*
X956800Y184250D01*
G01X960900Y188500D02*
Y183500D01*
G01X959733Y186833D02*
X962067D01*
G01X965083Y183500D02*
Y188500D01*
G01Y186083D02*
X965500Y186500D01*
X965917Y186750D01*
X966583Y186833D01*
X967083Y186750D01*
X967667Y186417D01*
X967917Y185917D01*
Y183500D01*
G01X971017Y184417D02*
X973183D01*
G01Y185917D02*
X971017D01*
G01X976117Y185583D02*
X976700Y186167D01*
X977200Y186500D01*
X977867Y186667D01*
X978450Y186500D01*
X978867Y186167D01*
X979200Y185667D01*
X979283Y185083D01*
X979200Y184583D01*
X978867Y184083D01*
X978367Y183667D01*
X977783Y183500D01*
X977117Y183667D01*
X976533Y184167D01*
X976200Y184917D01*
X976117Y185750D01*
X976283Y186833D01*
X976533Y187417D01*
X976950Y188000D01*
X977533Y188417D01*
X978117Y188500D01*
X978700Y188333D01*
X979117Y187917D01*
G01X982383Y185167D02*
X984383D01*
G01X983300Y186250D02*
Y184083D01*
G01X987400Y183333D02*
X990400Y188500D01*
G01X993417Y185167D02*
X995583D01*
G01X998267Y184250D02*
X998767Y183833D01*
X999350Y183583D01*
X1000100Y183500D01*
X1000850Y183667D01*
X1001433Y184000D01*
X1001850Y184583D01*
X1001933Y185250D01*
X1001767Y185917D01*
X1001350Y186333D01*
X1000767Y186667D01*
X1000183Y186750D01*
X999600Y186667D01*
X998850Y186333D01*
X999100Y188500D01*
X1001350D01*
G01X1003200Y183500D02*
Y186833D01*
G01Y185917D02*
X1003450Y186333D01*
X1003867Y186667D01*
X1004450Y186833D01*
X1005033Y186667D01*
X1005450Y186333D01*
X1005700Y185917D01*
Y183500D01*
G01Y185917D02*
X1005950Y186333D01*
X1006367Y186667D01*
X1006950Y186833D01*
X1007533Y186667D01*
X1007950Y186333D01*
X1008200Y185833D01*
Y183500D01*
G01X1011300Y186833D02*
Y183500D01*
G01Y188167D02*
X1011133Y188250D01*
Y188417D01*
X1011300Y188500D01*
X1011467Y188417D01*
Y188250D01*
X1011300Y188167D01*
G01X1016900Y183500D02*
Y188500D01*
G01X868250Y152000D02*
Y157000D01*
G01X871750D02*
Y152000D01*
G01Y154500D02*
X868250D01*
G01X875600Y152000D02*
X874933Y152083D01*
X874350Y152417D01*
X873850Y152917D01*
X873517Y153500D01*
X873350Y154167D01*
Y154833D01*
X873517Y155500D01*
X873850Y156083D01*
X874350Y156583D01*
X874933Y156917D01*
X875600Y157000D01*
X876267Y156917D01*
X876850Y156583D01*
X877350Y156083D01*
X877683Y155500D01*
X877850Y154833D01*
Y154167D01*
X877683Y153500D01*
X877350Y152917D01*
X876850Y152417D01*
X876267Y152083D01*
X875600Y152000D01*
G01X879533Y157000D02*
Y152000D01*
X882867D01*
G01X888467D02*
X885133D01*
Y157000D01*
X888467D01*
G01X887133Y154583D02*
X885133D01*
G01X912300Y152000D02*
Y155333D01*
G01Y154417D02*
X912550Y154833D01*
X912967Y155167D01*
X913550Y155333D01*
X914133Y155167D01*
X914550Y154833D01*
X914800Y154417D01*
Y152000D01*
G01Y154417D02*
X915050Y154833D01*
X915467Y155167D01*
X916050Y155333D01*
X916633Y155167D01*
X917050Y154833D01*
X917300Y154333D01*
Y152000D01*
G01X920400Y155333D02*
Y152000D01*
G01Y156667D02*
X920233Y156750D01*
Y156917D01*
X920400Y157000D01*
X920567Y156917D01*
Y156750D01*
X920400Y156667D01*
G01X926000Y152000D02*
Y157000D01*
G01X930350Y152583D02*
X930767Y152250D01*
X931350Y152000D01*
X931850D01*
X932350Y152167D01*
X932683Y152417D01*
X932850Y152750D01*
X932767Y153250D01*
X932433Y153500D01*
X930933Y154000D01*
X930600Y154583D01*
X930767Y155000D01*
X931100Y155250D01*
X931600Y155333D01*
X932100Y155250D01*
X932600Y155000D01*
G01X936783Y150333D02*
X935950Y151167D01*
X935533Y152000D01*
Y155333D01*
X935950Y156167D01*
X936783Y157000D01*
G01X941133Y152000D02*
Y157000D01*
X943133D01*
X943800Y156750D01*
X944300Y156167D01*
X944467Y155500D01*
X944300Y154833D01*
X943883Y154333D01*
X943133Y154083D01*
X941133D01*
G01X948400Y157000D02*
Y152000D01*
G01X946483Y157000D02*
X950317D01*
G01X952250Y152000D02*
Y157000D01*
G01X955750D02*
Y152000D01*
G01Y154500D02*
X952250D01*
G01X960017Y150333D02*
X960850Y151167D01*
X961267Y152000D01*
Y155333D01*
X960850Y156167D01*
X960017Y157000D01*
G01X900833Y214500D02*
Y209500D01*
X904167D01*
G01X906683D02*
Y212833D01*
G01Y212000D02*
X907017Y212417D01*
X907517Y212750D01*
X908183Y212833D01*
X908767Y212750D01*
X909267Y212417D01*
X909517Y211833D01*
Y209500D01*
G01X902833Y255500D02*
Y250500D01*
X906167D01*
G01X908850Y253833D02*
X911350Y250500D01*
G01Y253833D02*
X908850Y250500D01*
G01X889267Y349073D02*
X892933Y352740D01*
G01X891100Y353407D02*
Y348407D01*
G01X892933Y349073D02*
X889267Y352740D01*
G01X888600Y350907D02*
X893600D01*
G01X896283Y347573D02*
X895450Y348407D01*
X895033Y349240D01*
Y352573D01*
X895450Y353407D01*
X896283Y354240D01*
G01X900467Y349990D02*
X900967Y349573D01*
X901550Y349323D01*
X902300Y349240D01*
X903050Y349407D01*
X903633Y349740D01*
X904050Y350323D01*
X904133Y350990D01*
X903967Y351657D01*
X903550Y352073D01*
X902967Y352407D01*
X902383Y352490D01*
X901800Y352407D01*
X901050Y352073D01*
X901300Y354240D01*
X903550D01*
G01X907900Y349073D02*
X907733Y349157D01*
Y349323D01*
X907900Y349407D01*
X908067Y349323D01*
Y349157D01*
X907900Y349073D01*
G01X913500Y349240D02*
Y354240D01*
X912500Y353240D01*
G01Y349240D02*
X914500D01*
G01X919517Y347573D02*
X920350Y348407D01*
X920767Y349240D01*
Y352573D01*
X920350Y353407D01*
X919517Y354240D01*
G01X868167Y308167D02*
X868500Y308417D01*
X868750Y308833D01*
X868917Y309417D01*
X868750Y309917D01*
X868417Y310250D01*
X867833Y310500D01*
X865583D01*
Y305500D01*
X868333D01*
X868917Y305833D01*
X869250Y306333D01*
X869417Y306917D01*
X869250Y307500D01*
X868750Y308000D01*
X868167Y308167D01*
X865583D01*
G01X871017Y305500D02*
X873100Y310500D01*
X875183Y305500D01*
G01X874433Y307250D02*
X871767D01*
G01X880533Y310083D02*
X880033Y310333D01*
X879450Y310500D01*
X878783D01*
X878033Y310250D01*
X877450Y309833D01*
X877033Y309333D01*
X876700Y308500D01*
X876617Y307750D01*
X876783Y307000D01*
X877033Y306500D01*
X877533Y306000D01*
X878117Y305667D01*
X878700Y305500D01*
X879283D01*
X879867Y305667D01*
X880367Y305917D01*
X880783Y306250D01*
G01X882467Y305500D02*
Y310500D01*
G01X885633D02*
X882467Y307417D01*
G01X886133Y305500D02*
X883883Y308833D01*
G01X893667Y305500D02*
Y310500D01*
X895333D01*
X896000Y310250D01*
X896500Y309917D01*
X896917Y309417D01*
X897250Y308833D01*
X897333Y308000D01*
X897250Y307167D01*
X896917Y306583D01*
X896500Y306083D01*
X896000Y305750D01*
X895333Y305500D01*
X893667D01*
G01X899433D02*
Y310500D01*
X901517D01*
X902183Y310250D01*
X902600Y309917D01*
X902767Y309250D01*
X902600Y308583D01*
X902100Y308167D01*
X901517Y307917D01*
X899433D01*
G01X901517D02*
X902767Y305500D01*
G01X905700Y310500D02*
X907700D01*
G01X906700D02*
Y305500D01*
G01X905700D02*
X907700D01*
G01X910633Y310500D02*
Y305500D01*
X913967D01*
G01X916233Y310500D02*
Y305500D01*
X919567D01*
G01X943400D02*
Y308833D01*
G01Y307917D02*
X943650Y308333D01*
X944067Y308667D01*
X944650Y308833D01*
X945233Y308667D01*
X945650Y308333D01*
X945900Y307917D01*
Y305500D01*
G01Y307917D02*
X946150Y308333D01*
X946567Y308667D01*
X947150Y308833D01*
X947733Y308667D01*
X948150Y308333D01*
X948400Y307833D01*
Y305500D01*
G01X951500Y308833D02*
Y305500D01*
G01Y310167D02*
X951333Y310250D01*
Y310417D01*
X951500Y310500D01*
X951667Y310417D01*
Y310250D01*
X951500Y310167D01*
G01X957100Y305500D02*
Y310500D01*
G01X961450Y306083D02*
X961867Y305750D01*
X962450Y305500D01*
X962950D01*
X963450Y305667D01*
X963783Y305917D01*
X963950Y306250D01*
X963867Y306750D01*
X963533Y307000D01*
X962033Y307500D01*
X961700Y308083D01*
X961867Y308500D01*
X962200Y308750D01*
X962700Y308833D01*
X963200Y308750D01*
X963700Y308500D01*
G01X967883Y303833D02*
X967050Y304667D01*
X966633Y305500D01*
Y308833D01*
X967050Y309667D01*
X967883Y310500D01*
G01X971983Y305500D02*
Y310500D01*
X975817Y305500D01*
Y310500D01*
G01X977833Y305500D02*
Y310500D01*
X979833D01*
X980500Y310250D01*
X981000Y309667D01*
X981167Y309000D01*
X981000Y308333D01*
X980583Y307833D01*
X979833Y307583D01*
X977833D01*
G01X985100Y310500D02*
Y305500D01*
G01X983183Y310500D02*
X987017D01*
G01X988950Y305500D02*
Y310500D01*
G01X992450D02*
Y305500D01*
G01Y308000D02*
X988950D01*
G01X996717Y303833D02*
X997550Y304667D01*
X997967Y305500D01*
Y308833D01*
X997550Y309667D01*
X996717Y310500D01*
G01X894000Y556000D02*
Y551000D01*
G01X892833Y554333D02*
X895167D01*
G01X898183Y551000D02*
Y556000D01*
G01Y553583D02*
X898600Y554000D01*
X899017Y554250D01*
X899683Y554333D01*
X900183Y554250D01*
X900767Y553917D01*
X901017Y553417D01*
Y551000D01*
G01X903950Y553250D02*
X906617D01*
X906367Y553833D01*
X905950Y554167D01*
X905367Y554333D01*
X904783Y554250D01*
X904283Y554000D01*
X903950Y553417D01*
X903783Y552917D01*
Y552417D01*
X903950Y551917D01*
X904367Y551417D01*
X904867Y551083D01*
X905450Y551000D01*
X906033Y551167D01*
X906617Y551667D01*
G01X916400Y551000D02*
X915900Y551083D01*
X915400Y551417D01*
X915067Y552000D01*
X914900Y552667D01*
X915067Y553333D01*
X915400Y553917D01*
X915900Y554250D01*
X916400Y554333D01*
X916900Y554250D01*
X917400Y553917D01*
X917733Y553333D01*
X917817Y552667D01*
X917733Y552000D01*
X917400Y551417D01*
X916900Y551083D01*
X916400Y551000D01*
G01X922000Y556000D02*
Y551000D01*
G01X920833Y554333D02*
X923167D01*
G01X926183Y551000D02*
Y556000D01*
G01Y553583D02*
X926600Y554000D01*
X927017Y554250D01*
X927683Y554333D01*
X928183Y554250D01*
X928767Y553917D01*
X929017Y553417D01*
Y551000D01*
G01X931950Y553250D02*
X934617D01*
X934367Y553833D01*
X933950Y554167D01*
X933367Y554333D01*
X932783Y554250D01*
X932283Y554000D01*
X931950Y553417D01*
X931783Y552917D01*
Y552417D01*
X931950Y551917D01*
X932367Y551417D01*
X932867Y551083D01*
X933450Y551000D01*
X934033Y551167D01*
X934617Y551667D01*
G01X937633Y551000D02*
Y554333D01*
G01Y553667D02*
X938050Y554000D01*
X938467Y554250D01*
X939050Y554333D01*
X939467Y554250D01*
X939967Y554000D01*
G01X948750Y551583D02*
X949167Y551250D01*
X949750Y551000D01*
X950250D01*
X950750Y551167D01*
X951083Y551417D01*
X951250Y551750D01*
X951167Y552250D01*
X950833Y552500D01*
X949333Y553000D01*
X949000Y553583D01*
X949167Y554000D01*
X949500Y554250D01*
X950000Y554333D01*
X950500Y554250D01*
X951000Y554000D01*
G01X955600Y554333D02*
Y551000D01*
G01Y555667D02*
X955433Y555750D01*
Y555917D01*
X955600Y556000D01*
X955767Y555917D01*
Y555750D01*
X955600Y555667D01*
G01X962700Y556000D02*
Y551000D01*
G01Y551750D02*
X962367Y551333D01*
X961867Y551083D01*
X961283Y551000D01*
X960617Y551167D01*
X960117Y551583D01*
X959783Y552083D01*
X959700Y552667D01*
X959783Y553250D01*
X960117Y553750D01*
X960617Y554167D01*
X961283Y554333D01*
X961867Y554250D01*
X962283Y554083D01*
X962700Y553750D01*
G01X965550Y553250D02*
X968217D01*
X967967Y553833D01*
X967550Y554167D01*
X966967Y554333D01*
X966383Y554250D01*
X965883Y554000D01*
X965550Y553417D01*
X965383Y552917D01*
Y552417D01*
X965550Y551917D01*
X965967Y551417D01*
X966467Y551083D01*
X967050Y551000D01*
X967633Y551167D01*
X968217Y551667D01*
G01X975917Y554333D02*
X976917Y551000D01*
X978000Y554333D01*
X979083Y551000D01*
X980083Y554333D01*
G01X983600D02*
Y551000D01*
G01Y555667D02*
X983433Y555750D01*
Y555917D01*
X983600Y556000D01*
X983767Y555917D01*
Y555750D01*
X983600Y555667D01*
G01X989200Y556000D02*
Y551000D01*
G01X988033Y554333D02*
X990367D01*
G01X993383Y551000D02*
Y556000D01*
G01Y553583D02*
X993800Y554000D01*
X994217Y554250D01*
X994883Y554333D01*
X995383Y554250D01*
X995967Y553917D01*
X996217Y553417D01*
Y551000D01*
G01X1000400D02*
X999900Y551083D01*
X999400Y551417D01*
X999067Y552000D01*
X998900Y552667D01*
X999067Y553333D01*
X999400Y553917D01*
X999900Y554250D01*
X1000400Y554333D01*
X1000900Y554250D01*
X1001400Y553917D01*
X1001733Y553333D01*
X1001817Y552667D01*
X1001733Y552000D01*
X1001400Y551417D01*
X1000900Y551083D01*
X1000400Y551000D01*
G01X1004583Y554333D02*
Y552000D01*
X1004917Y551417D01*
X1005417Y551083D01*
X1006000Y551000D01*
X1006583Y551083D01*
X1007083Y551417D01*
X1007417Y552000D01*
G01Y551000D02*
Y554333D01*
G01X1011600Y556000D02*
Y551000D01*
G01X1010433Y554333D02*
X1012767D01*
G01X878000Y591500D02*
X879667D01*
Y590000D01*
X879167Y589500D01*
X878583Y589167D01*
X877750Y589000D01*
X876917Y589167D01*
X876333Y589500D01*
X875833Y590000D01*
X875500Y590583D01*
X875333Y591250D01*
Y591833D01*
X875500Y592333D01*
X875833Y592917D01*
X876333Y593417D01*
X876833Y593750D01*
X877500Y594000D01*
X878083D01*
X878750Y593833D01*
X879250Y593500D01*
G01X881850Y591250D02*
X884517D01*
X884267Y591833D01*
X883850Y592167D01*
X883267Y592333D01*
X882683Y592250D01*
X882183Y592000D01*
X881850Y591417D01*
X881683Y590917D01*
Y590417D01*
X881850Y589917D01*
X882267Y589417D01*
X882767Y589083D01*
X883350Y589000D01*
X883933Y589167D01*
X884517Y589667D01*
G01X887533Y589000D02*
Y592333D01*
G01Y591667D02*
X887950Y592000D01*
X888367Y592250D01*
X888950Y592333D01*
X889367Y592250D01*
X889867Y592000D01*
G01X892800Y589000D02*
Y594000D01*
G01Y591500D02*
X893217Y592000D01*
X893717Y592250D01*
X894217Y592333D01*
X894967Y592167D01*
X895467Y591833D01*
X895800Y591250D01*
Y590583D01*
X895633Y589917D01*
X895300Y589417D01*
X894717Y589083D01*
X894217Y589000D01*
X893717Y589083D01*
X893217Y589333D01*
X892800Y589750D01*
G01X898650Y591250D02*
X901317D01*
X901067Y591833D01*
X900650Y592167D01*
X900067Y592333D01*
X899483Y592250D01*
X898983Y592000D01*
X898650Y591417D01*
X898483Y590917D01*
Y590417D01*
X898650Y589917D01*
X899067Y589417D01*
X899567Y589083D01*
X900150Y589000D01*
X900733Y589167D01*
X901317Y589667D01*
G01X904333Y589000D02*
Y592333D01*
G01Y591667D02*
X904750Y592000D01*
X905167Y592250D01*
X905750Y592333D01*
X906167Y592250D01*
X906667Y592000D01*
G01X918200Y594000D02*
Y589000D01*
G01Y589750D02*
X917867Y589333D01*
X917367Y589083D01*
X916783Y589000D01*
X916117Y589167D01*
X915617Y589583D01*
X915283Y590083D01*
X915200Y590667D01*
X915283Y591250D01*
X915617Y591750D01*
X916117Y592167D01*
X916783Y592333D01*
X917367Y592250D01*
X917783Y592083D01*
X918200Y591750D01*
G01X921050Y591250D02*
X923717D01*
X923467Y591833D01*
X923050Y592167D01*
X922467Y592333D01*
X921883Y592250D01*
X921383Y592000D01*
X921050Y591417D01*
X920883Y590917D01*
Y590417D01*
X921050Y589917D01*
X921467Y589417D01*
X921967Y589083D01*
X922550Y589000D01*
X923133Y589167D01*
X923717Y589667D01*
G01X926650Y589583D02*
X927067Y589250D01*
X927650Y589000D01*
X928150D01*
X928650Y589167D01*
X928983Y589417D01*
X929150Y589750D01*
X929067Y590250D01*
X928733Y590500D01*
X927233Y591000D01*
X926900Y591583D01*
X927067Y592000D01*
X927400Y592250D01*
X927900Y592333D01*
X928400Y592250D01*
X928900Y592000D01*
G01X933500Y592333D02*
Y589000D01*
G01Y593667D02*
X933333Y593750D01*
Y593917D01*
X933500Y594000D01*
X933667Y593917D01*
Y593750D01*
X933500Y593667D01*
G01X937933Y587750D02*
X938517Y587417D01*
X939183Y587333D01*
X939767Y587417D01*
X940267Y587833D01*
X940600Y588417D01*
Y592333D01*
G01Y591667D02*
X940267Y592000D01*
X939767Y592250D01*
X939183Y592333D01*
X938517Y592167D01*
X938100Y591833D01*
X937767Y591250D01*
X937600Y590667D01*
X937683Y590167D01*
X938017Y589583D01*
X938517Y589167D01*
X939183Y589000D01*
X939683Y589083D01*
X940267Y589417D01*
X940600Y589750D01*
G01X943283Y589000D02*
Y592333D01*
G01Y591500D02*
X943617Y591917D01*
X944117Y592250D01*
X944783Y592333D01*
X945367Y592250D01*
X945867Y591917D01*
X946117Y591333D01*
Y589000D01*
G01X929000Y734500D02*
Y738750D01*
X929167Y739167D01*
X929500Y739417D01*
X930000Y739500D01*
X930500Y739333D01*
X930750Y738917D01*
G01X929750Y737500D02*
X928083D01*
G01X933683Y737833D02*
Y735500D01*
X934017Y734917D01*
X934517Y734583D01*
X935100Y734500D01*
X935683Y734583D01*
X936183Y734917D01*
X936517Y735500D01*
G01Y734500D02*
Y737833D01*
G01X940700Y734500D02*
Y739500D01*
G01X946300Y734500D02*
Y739500D01*
G01X956000Y732833D02*
Y737833D01*
G01Y737083D02*
X956417Y737500D01*
X956833Y737750D01*
X957500Y737833D01*
X958083Y737750D01*
X958667Y737333D01*
X958917Y736750D01*
X959000Y736167D01*
X958917Y735583D01*
X958667Y735000D01*
X958167Y734667D01*
X957500Y734500D01*
X956917Y734583D01*
X956333Y734833D01*
X956000Y735167D01*
G01X963100Y734500D02*
Y739500D01*
G01X967283Y737833D02*
Y735500D01*
X967617Y734917D01*
X968117Y734583D01*
X968700Y734500D01*
X969283Y734583D01*
X969783Y734917D01*
X970117Y735500D01*
G01Y734500D02*
Y737833D01*
G01X973133Y733250D02*
X973717Y732917D01*
X974383Y732833D01*
X974967Y732917D01*
X975467Y733333D01*
X975800Y733917D01*
Y737833D01*
G01Y737167D02*
X975467Y737500D01*
X974967Y737750D01*
X974383Y737833D01*
X973717Y737667D01*
X973300Y737333D01*
X972967Y736750D01*
X972800Y736167D01*
X972883Y735667D01*
X973217Y735083D01*
X973717Y734667D01*
X974383Y734500D01*
X974883Y734583D01*
X975467Y734917D01*
X975800Y735250D01*
G01X978733Y733250D02*
X979317Y732917D01*
X979983Y732833D01*
X980567Y732917D01*
X981067Y733333D01*
X981400Y733917D01*
Y737833D01*
G01Y737167D02*
X981067Y737500D01*
X980567Y737750D01*
X979983Y737833D01*
X979317Y737667D01*
X978900Y737333D01*
X978567Y736750D01*
X978400Y736167D01*
X978483Y735667D01*
X978817Y735083D01*
X979317Y734667D01*
X979983Y734500D01*
X980483Y734583D01*
X981067Y734917D01*
X981400Y735250D01*
G01X985500Y737833D02*
Y734500D01*
G01Y739167D02*
X985333Y739250D01*
Y739417D01*
X985500Y739500D01*
X985667Y739417D01*
Y739250D01*
X985500Y739167D01*
G01X989683Y734500D02*
Y737833D01*
G01Y737000D02*
X990017Y737417D01*
X990517Y737750D01*
X991183Y737833D01*
X991767Y737750D01*
X992267Y737417D01*
X992517Y736833D01*
Y734500D01*
G01X995533Y733250D02*
X996117Y732917D01*
X996783Y732833D01*
X997367Y732917D01*
X997867Y733333D01*
X998200Y733917D01*
Y737833D01*
G01Y737167D02*
X997867Y737500D01*
X997367Y737750D01*
X996783Y737833D01*
X996117Y737667D01*
X995700Y737333D01*
X995367Y736750D01*
X995200Y736167D01*
X995283Y735667D01*
X995617Y735083D01*
X996117Y734667D01*
X996783Y734500D01*
X997283Y734583D01*
X997867Y734917D01*
X998200Y735250D01*
G01X995667Y5500D02*
Y10500D01*
X997333D01*
X998000Y10250D01*
X998500Y9917D01*
X998917Y9417D01*
X999250Y8833D01*
X999333Y8000D01*
X999250Y7167D01*
X998917Y6583D01*
X998500Y6083D01*
X998000Y5750D01*
X997333Y5500D01*
X995667D01*
G01X1003100D02*
Y10500D01*
X1002100Y9500D01*
G01Y5500D02*
X1004100D01*
G01X1007117Y7583D02*
X1007700Y8167D01*
X1008200Y8500D01*
X1008867Y8667D01*
X1009450Y8500D01*
X1009867Y8167D01*
X1010200Y7667D01*
X1010283Y7083D01*
X1010200Y6583D01*
X1009867Y6083D01*
X1009367Y5667D01*
X1008783Y5500D01*
X1008117Y5667D01*
X1007533Y6167D01*
X1007200Y6917D01*
X1007117Y7750D01*
X1007283Y8833D01*
X1007533Y9417D01*
X1007950Y10000D01*
X1008533Y10417D01*
X1009117Y10500D01*
X1009700Y10333D01*
X1010117Y9917D01*
G01X1014300Y5333D02*
X1014133Y5417D01*
Y5583D01*
X1014300Y5667D01*
X1014467Y5583D01*
Y5417D01*
X1014300Y5333D01*
G01Y7583D02*
X1014133Y7667D01*
Y7833D01*
X1014300Y7917D01*
X1014467Y7833D01*
Y7667D01*
X1014300Y7583D01*
G01X1018067Y5500D02*
Y10500D01*
X1019733D01*
X1020400Y10250D01*
X1020900Y9917D01*
X1021317Y9417D01*
X1021650Y8833D01*
X1021733Y8000D01*
X1021650Y7167D01*
X1021317Y6583D01*
X1020900Y6083D01*
X1020400Y5750D01*
X1019733Y5500D01*
X1018067D01*
G01X1025500Y8833D02*
Y5500D01*
G01Y10167D02*
X1025333Y10250D01*
Y10417D01*
X1025500Y10500D01*
X1025667Y10417D01*
Y10250D01*
X1025500Y10167D01*
G01X1032600Y5500D02*
Y8833D01*
G01Y8250D02*
X1032267Y8583D01*
X1031767Y8750D01*
X1031183Y8833D01*
X1030600Y8667D01*
X1030100Y8333D01*
X1029767Y7833D01*
X1029600Y7167D01*
X1029767Y6500D01*
X1030100Y6000D01*
X1030600Y5667D01*
X1031183Y5500D01*
X1031767Y5583D01*
X1032267Y5833D01*
X1032600Y6167D01*
G01X1034200Y5500D02*
Y8833D01*
G01Y7917D02*
X1034450Y8333D01*
X1034867Y8667D01*
X1035450Y8833D01*
X1036033Y8667D01*
X1036450Y8333D01*
X1036700Y7917D01*
Y5500D01*
G01Y7917D02*
X1036950Y8333D01*
X1037367Y8667D01*
X1037950Y8833D01*
X1038533Y8667D01*
X1038950Y8333D01*
X1039200Y7833D01*
Y5500D01*
G01X1041050Y7750D02*
X1043717D01*
X1043467Y8333D01*
X1043050Y8667D01*
X1042467Y8833D01*
X1041883Y8750D01*
X1041383Y8500D01*
X1041050Y7917D01*
X1040883Y7417D01*
Y6917D01*
X1041050Y6417D01*
X1041467Y5917D01*
X1041967Y5583D01*
X1042550Y5500D01*
X1043133Y5667D01*
X1043717Y6167D01*
G01X1047900Y10500D02*
Y5500D01*
G01X1046733Y8833D02*
X1049067D01*
G01X1052250Y7750D02*
X1054917D01*
X1054667Y8333D01*
X1054250Y8667D01*
X1053667Y8833D01*
X1053083Y8750D01*
X1052583Y8500D01*
X1052250Y7917D01*
X1052083Y7417D01*
Y6917D01*
X1052250Y6417D01*
X1052667Y5917D01*
X1053167Y5583D01*
X1053750Y5500D01*
X1054333Y5667D01*
X1054917Y6167D01*
G01X1057933Y5500D02*
Y8833D01*
G01Y8167D02*
X1058350Y8500D01*
X1058767Y8750D01*
X1059350Y8833D01*
X1059767Y8750D01*
X1060267Y8500D01*
G01X1070300Y5500D02*
Y10500D01*
X1069300Y9500D01*
G01Y5500D02*
X1071300D01*
G01X1074317Y7583D02*
X1074900Y8167D01*
X1075400Y8500D01*
X1076067Y8667D01*
X1076650Y8500D01*
X1077067Y8167D01*
X1077400Y7667D01*
X1077483Y7083D01*
X1077400Y6583D01*
X1077067Y6083D01*
X1076567Y5667D01*
X1075983Y5500D01*
X1075317Y5667D01*
X1074733Y6167D01*
X1074400Y6917D01*
X1074317Y7750D01*
X1074483Y8833D01*
X1074733Y9417D01*
X1075150Y10000D01*
X1075733Y10417D01*
X1076317Y10500D01*
X1076900Y10333D01*
X1077317Y9917D01*
G01X1079000Y5500D02*
Y8833D01*
G01Y7917D02*
X1079250Y8333D01*
X1079667Y8667D01*
X1080250Y8833D01*
X1080833Y8667D01*
X1081250Y8333D01*
X1081500Y7917D01*
Y5500D01*
G01Y7917D02*
X1081750Y8333D01*
X1082167Y8667D01*
X1082750Y8833D01*
X1083333Y8667D01*
X1083750Y8333D01*
X1084000Y7833D01*
Y5500D01*
G01X1087100Y8833D02*
Y5500D01*
G01Y10167D02*
X1086933Y10250D01*
Y10417D01*
X1087100Y10500D01*
X1087267Y10417D01*
Y10250D01*
X1087100Y10167D01*
G01X1092700Y5500D02*
Y10500D01*
G01X980667Y16500D02*
X977333D01*
Y21500D01*
X980667D01*
G01X979333Y19083D02*
X977333D01*
G01X983350Y19833D02*
X985850Y16500D01*
G01Y19833D02*
X983350Y16500D01*
G01X990200Y16333D02*
X990033Y16417D01*
Y16583D01*
X990200Y16667D01*
X990367Y16583D01*
Y16417D01*
X990200Y16333D01*
G01X994050Y16500D02*
Y21500D01*
G01X997550D02*
Y16500D01*
G01Y19000D02*
X994050D01*
G01X999733Y16500D02*
Y21500D01*
X1001817D01*
X1002483Y21250D01*
X1002900Y20917D01*
X1003067Y20250D01*
X1002900Y19583D01*
X1002400Y19167D01*
X1001817Y18917D01*
X999733D01*
G01X1001817D02*
X1003067Y16500D01*
G01X1008667D02*
X1005333D01*
Y21500D01*
X1008667D01*
G01X1007333Y19083D02*
X1005333D01*
G01X1013600Y16500D02*
Y21500D01*
X1010517Y17917D01*
X1014683D01*
G01X1016367Y17250D02*
X1016867Y16833D01*
X1017450Y16583D01*
X1018200Y16500D01*
X1018950Y16667D01*
X1019533Y17000D01*
X1019950Y17583D01*
X1020033Y18250D01*
X1019867Y18917D01*
X1019450Y19333D01*
X1018867Y19667D01*
X1018283Y19750D01*
X1017700Y19667D01*
X1016950Y19333D01*
X1017200Y21500D01*
X1019450D01*
G01X1022050Y16500D02*
X1025550Y21500D01*
G01X1022050D02*
X1025550Y16500D01*
G01X1027983Y17083D02*
X1028567Y16667D01*
X1029233Y16500D01*
X1029900Y16667D01*
X1030483Y17167D01*
X1030900Y17917D01*
X1031067Y18667D01*
Y19583D01*
X1030900Y20333D01*
X1030483Y21000D01*
X1029983Y21333D01*
X1029400Y21500D01*
X1028733Y21333D01*
X1028233Y21000D01*
X1027900Y20500D01*
X1027733Y19833D01*
X1027900Y19250D01*
X1028317Y18667D01*
X1028817Y18333D01*
X1029400Y18250D01*
X1030067Y18417D01*
X1030567Y18833D01*
X1031067Y19583D01*
G01X1033417Y18583D02*
X1034000Y19167D01*
X1034500Y19500D01*
X1035167Y19667D01*
X1035750Y19500D01*
X1036167Y19167D01*
X1036500Y18667D01*
X1036583Y18083D01*
X1036500Y17583D01*
X1036167Y17083D01*
X1035667Y16667D01*
X1035083Y16500D01*
X1034417Y16667D01*
X1033833Y17167D01*
X1033500Y17917D01*
X1033417Y18750D01*
X1033583Y19833D01*
X1033833Y20417D01*
X1034250Y21000D01*
X1034833Y21417D01*
X1035417Y21500D01*
X1036000Y21333D01*
X1036417Y20917D01*
G01X1040183Y14833D02*
X1039350Y15667D01*
X1038933Y16500D01*
Y19833D01*
X1039350Y20667D01*
X1040183Y21500D01*
G01X1044367Y16500D02*
Y21500D01*
X1046033D01*
X1046700Y21250D01*
X1047200Y20917D01*
X1047617Y20417D01*
X1047950Y19833D01*
X1048033Y19000D01*
X1047950Y18167D01*
X1047617Y17583D01*
X1047200Y17083D01*
X1046700Y16750D01*
X1046033Y16500D01*
X1044367D01*
G01X1051800D02*
Y21500D01*
X1050800Y20500D01*
G01Y16500D02*
X1052800D01*
G01X1055817Y18583D02*
X1056400Y19167D01*
X1056900Y19500D01*
X1057567Y19667D01*
X1058150Y19500D01*
X1058567Y19167D01*
X1058900Y18667D01*
X1058983Y18083D01*
X1058900Y17583D01*
X1058567Y17083D01*
X1058067Y16667D01*
X1057483Y16500D01*
X1056817Y16667D01*
X1056233Y17167D01*
X1055900Y17917D01*
X1055817Y18750D01*
X1055983Y19833D01*
X1056233Y20417D01*
X1056650Y21000D01*
X1057233Y21417D01*
X1057817Y21500D01*
X1058400Y21333D01*
X1058817Y20917D01*
G01X1061250Y16500D02*
X1064750Y21500D01*
G01X1061250D02*
X1064750Y16500D01*
G01X1069600D02*
Y21500D01*
X1066517Y17917D01*
X1070683D01*
G01X1074617Y14833D02*
X1075450Y15667D01*
X1075867Y16500D01*
Y19833D01*
X1075450Y20667D01*
X1074617Y21500D01*
G01X977333Y65500D02*
Y70500D01*
X979417D01*
X980083Y70250D01*
X980500Y69917D01*
X980667Y69250D01*
X980500Y68583D01*
X980000Y68167D01*
X979417Y67917D01*
X977333D01*
G01X979417D02*
X980667Y65500D01*
G01X986267D02*
X982933D01*
Y70500D01*
X986267D01*
G01X984933Y68083D02*
X982933D01*
G01X992033Y70083D02*
X991533Y70333D01*
X990950Y70500D01*
X990283D01*
X989533Y70250D01*
X988950Y69833D01*
X988533Y69333D01*
X988200Y68500D01*
X988117Y67750D01*
X988283Y67000D01*
X988533Y66500D01*
X989033Y66000D01*
X989617Y65667D01*
X990200Y65500D01*
X990783D01*
X991367Y65667D01*
X991867Y65917D01*
X992283Y66250D01*
G01X995800Y70500D02*
Y65500D01*
G01X993883Y70500D02*
X997717D01*
G01X999317Y65500D02*
X1001400Y70500D01*
X1003483Y65500D01*
G01X1002733Y67250D02*
X1000067D01*
G01X1005083Y65500D02*
Y70500D01*
X1008917Y65500D01*
Y70500D01*
G01X1013100Y68000D02*
X1014767D01*
Y66500D01*
X1014267Y66000D01*
X1013683Y65667D01*
X1012850Y65500D01*
X1012017Y65667D01*
X1011433Y66000D01*
X1010933Y66500D01*
X1010600Y67083D01*
X1010433Y67750D01*
Y68333D01*
X1010600Y68833D01*
X1010933Y69417D01*
X1011433Y69917D01*
X1011933Y70250D01*
X1012600Y70500D01*
X1013183D01*
X1013850Y70333D01*
X1014350Y70000D01*
G01X1016533Y70500D02*
Y65500D01*
X1019867D01*
G01X1025467D02*
X1022133D01*
Y70500D01*
X1025467D01*
G01X1024133Y68083D02*
X1022133D01*
G01X1033167Y65500D02*
Y70500D01*
X1034833D01*
X1035500Y70250D01*
X1036000Y69917D01*
X1036417Y69417D01*
X1036750Y68833D01*
X1036833Y68000D01*
X1036750Y67167D01*
X1036417Y66583D01*
X1036000Y66083D01*
X1035500Y65750D01*
X1034833Y65500D01*
X1033167D01*
G01X1038933D02*
Y70500D01*
X1041017D01*
X1041683Y70250D01*
X1042100Y69917D01*
X1042267Y69250D01*
X1042100Y68583D01*
X1041600Y68167D01*
X1041017Y67917D01*
X1038933D01*
G01X1041017D02*
X1042267Y65500D01*
G01X1045200Y70500D02*
X1047200D01*
G01X1046200D02*
Y65500D01*
G01X1045200D02*
X1047200D01*
G01X1050133Y70500D02*
Y65500D01*
X1053467D01*
G01X1055733Y70500D02*
Y65500D01*
X1059067D01*
G01X1066850D02*
Y70500D01*
G01X1070350D02*
Y65500D01*
G01Y68000D02*
X1066850D01*
G01X1074200Y65500D02*
X1073533Y65583D01*
X1072950Y65917D01*
X1072450Y66417D01*
X1072117Y67000D01*
X1071950Y67667D01*
Y68333D01*
X1072117Y69000D01*
X1072450Y69583D01*
X1072950Y70083D01*
X1073533Y70417D01*
X1074200Y70500D01*
X1074867Y70417D01*
X1075450Y70083D01*
X1075950Y69583D01*
X1076283Y69000D01*
X1076450Y68333D01*
Y67667D01*
X1076283Y67000D01*
X1075950Y66417D01*
X1075450Y65917D01*
X1074867Y65583D01*
X1074200Y65500D01*
G01X1078133Y70500D02*
Y65500D01*
X1081467D01*
G01X1087067D02*
X1083733D01*
Y70500D01*
X1087067D01*
G01X1085733Y68083D02*
X1083733D01*
G01X1094767Y65500D02*
Y70500D01*
X1096433D01*
X1097100Y70250D01*
X1097600Y69917D01*
X1098017Y69417D01*
X1098350Y68833D01*
X1098433Y68000D01*
X1098350Y67167D01*
X1098017Y66583D01*
X1097600Y66083D01*
X1097100Y65750D01*
X1096433Y65500D01*
X1094767D01*
G01X1103867D02*
X1100533D01*
Y70500D01*
X1103867D01*
G01X1102533Y68083D02*
X1100533D01*
G01X1106217Y65500D02*
Y70500D01*
X1109383D01*
G01X1108217Y68083D02*
X1106217D01*
G01X1112400Y70500D02*
X1114400D01*
G01X1113400D02*
Y65500D01*
G01X1112400D02*
X1114400D01*
G01X1117083D02*
Y70500D01*
X1120917Y65500D01*
Y70500D01*
G01X1126267Y65500D02*
X1122933D01*
Y70500D01*
X1126267D01*
G01X1124933Y68083D02*
X1122933D01*
G01X1026000Y336000D02*
Y86000D01*
G01X1021417Y383667D02*
X1021917Y384167D01*
X1022500Y384417D01*
X1023167Y384500D01*
X1024000Y384333D01*
X1024583Y383917D01*
X1024750Y383417D01*
X1024667Y382917D01*
X1024333Y382500D01*
X1022667Y381667D01*
X1021917Y381083D01*
X1021417Y380250D01*
X1021250Y379500D01*
X1024750D01*
G01X1028600Y379333D02*
X1028433Y379417D01*
Y379583D01*
X1028600Y379667D01*
X1028767Y379583D01*
Y379417D01*
X1028600Y379333D01*
G01X1032117Y384500D02*
X1034200Y379500D01*
X1036283Y384500D01*
G01X1039800Y382833D02*
Y379500D01*
G01Y384167D02*
X1039633Y384250D01*
Y384417D01*
X1039800Y384500D01*
X1039967Y384417D01*
Y384250D01*
X1039800Y384167D01*
G01X1046900Y379500D02*
Y382833D01*
G01Y382250D02*
X1046567Y382583D01*
X1046067Y382750D01*
X1045483Y382833D01*
X1044900Y382667D01*
X1044400Y382333D01*
X1044067Y381833D01*
X1043900Y381167D01*
X1044067Y380500D01*
X1044400Y380000D01*
X1044900Y379667D01*
X1045483Y379500D01*
X1046067Y379583D01*
X1046567Y379833D01*
X1046900Y380167D01*
G01X1055350Y380083D02*
X1055767Y379750D01*
X1056350Y379500D01*
X1056850D01*
X1057350Y379667D01*
X1057683Y379917D01*
X1057850Y380250D01*
X1057767Y380750D01*
X1057433Y381000D01*
X1055933Y381500D01*
X1055600Y382083D01*
X1055767Y382500D01*
X1056100Y382750D01*
X1056600Y382833D01*
X1057100Y382750D01*
X1057600Y382500D01*
G01X1060783Y379500D02*
Y384500D01*
G01Y382083D02*
X1061200Y382500D01*
X1061617Y382750D01*
X1062283Y382833D01*
X1062783Y382750D01*
X1063367Y382417D01*
X1063617Y381917D01*
Y379500D01*
G01X1067800D02*
X1067300Y379583D01*
X1066800Y379917D01*
X1066467Y380500D01*
X1066300Y381167D01*
X1066467Y381833D01*
X1066800Y382417D01*
X1067300Y382750D01*
X1067800Y382833D01*
X1068300Y382750D01*
X1068800Y382417D01*
X1069133Y381833D01*
X1069217Y381167D01*
X1069133Y380500D01*
X1068800Y379917D01*
X1068300Y379583D01*
X1067800Y379500D01*
G01X1071983Y382833D02*
Y380500D01*
X1072317Y379917D01*
X1072817Y379583D01*
X1073400Y379500D01*
X1073983Y379583D01*
X1074483Y379917D01*
X1074817Y380500D01*
G01Y379500D02*
Y382833D01*
G01X1079000Y379500D02*
Y384500D01*
G01X1086100D02*
Y379500D01*
G01Y380250D02*
X1085767Y379833D01*
X1085267Y379583D01*
X1084683Y379500D01*
X1084017Y379667D01*
X1083517Y380083D01*
X1083183Y380583D01*
X1083100Y381167D01*
X1083183Y381750D01*
X1083517Y382250D01*
X1084017Y382667D01*
X1084683Y382833D01*
X1085267Y382750D01*
X1085683Y382583D01*
X1086100Y382250D01*
G01X1094300Y379500D02*
Y384500D01*
G01Y382000D02*
X1094717Y382500D01*
X1095217Y382750D01*
X1095717Y382833D01*
X1096467Y382667D01*
X1096967Y382333D01*
X1097300Y381750D01*
Y381083D01*
X1097133Y380417D01*
X1096800Y379917D01*
X1096217Y379583D01*
X1095717Y379500D01*
X1095217Y379583D01*
X1094717Y379833D01*
X1094300Y380250D01*
G01X1100150Y381750D02*
X1102817D01*
X1102567Y382333D01*
X1102150Y382667D01*
X1101567Y382833D01*
X1100983Y382750D01*
X1100483Y382500D01*
X1100150Y381917D01*
X1099983Y381417D01*
Y380917D01*
X1100150Y380417D01*
X1100567Y379917D01*
X1101067Y379583D01*
X1101650Y379500D01*
X1102233Y379667D01*
X1102817Y380167D01*
G01X1111100Y377833D02*
Y382833D01*
G01Y382083D02*
X1111517Y382500D01*
X1111933Y382750D01*
X1112600Y382833D01*
X1113183Y382750D01*
X1113767Y382333D01*
X1114017Y381750D01*
X1114100Y381167D01*
X1114017Y380583D01*
X1113767Y380000D01*
X1113267Y379667D01*
X1112600Y379500D01*
X1112017Y379583D01*
X1111433Y379833D01*
X1111100Y380167D01*
G01X1118200Y379500D02*
Y384500D01*
G01X1122383Y382833D02*
Y380500D01*
X1122717Y379917D01*
X1123217Y379583D01*
X1123800Y379500D01*
X1124383Y379583D01*
X1124883Y379917D01*
X1125217Y380500D01*
G01Y379500D02*
Y382833D01*
G01X1128233Y378250D02*
X1128817Y377917D01*
X1129483Y377833D01*
X1130067Y377917D01*
X1130567Y378333D01*
X1130900Y378917D01*
Y382833D01*
G01Y382167D02*
X1130567Y382500D01*
X1130067Y382750D01*
X1129483Y382833D01*
X1128817Y382667D01*
X1128400Y382333D01*
X1128067Y381750D01*
X1127900Y381167D01*
X1127983Y380667D01*
X1128317Y380083D01*
X1128817Y379667D01*
X1129483Y379500D01*
X1129983Y379583D01*
X1130567Y379917D01*
X1130900Y380250D01*
G01X1133833Y378250D02*
X1134417Y377917D01*
X1135083Y377833D01*
X1135667Y377917D01*
X1136167Y378333D01*
X1136500Y378917D01*
Y382833D01*
G01Y382167D02*
X1136167Y382500D01*
X1135667Y382750D01*
X1135083Y382833D01*
X1134417Y382667D01*
X1134000Y382333D01*
X1133667Y381750D01*
X1133500Y381167D01*
X1133583Y380667D01*
X1133917Y380083D01*
X1134417Y379667D01*
X1135083Y379500D01*
X1135583Y379583D01*
X1136167Y379917D01*
X1136500Y380250D01*
G01X1139350Y381750D02*
X1142017D01*
X1141767Y382333D01*
X1141350Y382667D01*
X1140767Y382833D01*
X1140183Y382750D01*
X1139683Y382500D01*
X1139350Y381917D01*
X1139183Y381417D01*
Y380917D01*
X1139350Y380417D01*
X1139767Y379917D01*
X1140267Y379583D01*
X1140850Y379500D01*
X1141433Y379667D01*
X1142017Y380167D01*
G01X1147700Y384500D02*
Y379500D01*
G01Y380250D02*
X1147367Y379833D01*
X1146867Y379583D01*
X1146283Y379500D01*
X1145617Y379667D01*
X1145117Y380083D01*
X1144783Y380583D01*
X1144700Y381167D01*
X1144783Y381750D01*
X1145117Y382250D01*
X1145617Y382667D01*
X1146283Y382833D01*
X1146867Y382750D01*
X1147283Y382583D01*
X1147700Y382250D01*
G01X1155317Y382833D02*
X1156317Y379500D01*
X1157400Y382833D01*
X1158483Y379500D01*
X1159483Y382833D01*
G01X1163000D02*
Y379500D01*
G01Y384167D02*
X1162833Y384250D01*
Y384417D01*
X1163000Y384500D01*
X1163167Y384417D01*
Y384250D01*
X1163000Y384167D01*
G01X1168600Y384500D02*
Y379500D01*
G01X1167433Y382833D02*
X1169767D01*
G01X1172783Y379500D02*
Y384500D01*
G01Y382083D02*
X1173200Y382500D01*
X1173617Y382750D01*
X1174283Y382833D01*
X1174783Y382750D01*
X1175367Y382417D01*
X1175617Y381917D01*
Y379500D01*
G01X1183733D02*
X1187067Y381167D01*
X1183733Y382833D01*
G01X1189583Y380083D02*
X1190167Y379667D01*
X1190833Y379500D01*
X1191500Y379667D01*
X1192083Y380167D01*
X1192500Y380917D01*
X1192667Y381667D01*
Y382583D01*
X1192500Y383333D01*
X1192083Y384000D01*
X1191583Y384333D01*
X1191000Y384500D01*
X1190333Y384333D01*
X1189833Y384000D01*
X1189500Y383500D01*
X1189333Y382833D01*
X1189500Y382250D01*
X1189917Y381667D01*
X1190417Y381333D01*
X1191000Y381250D01*
X1191667Y381417D01*
X1192167Y381833D01*
X1192667Y382583D01*
G01X1196600Y384500D02*
X1195933Y384333D01*
X1195433Y383917D01*
X1195100Y383417D01*
X1194850Y382750D01*
X1194767Y382000D01*
X1194850Y381250D01*
X1195100Y380583D01*
X1195433Y380083D01*
X1195933Y379667D01*
X1196600Y379500D01*
X1197267Y379667D01*
X1197767Y380083D01*
X1198100Y380583D01*
X1198350Y381250D01*
X1198433Y382000D01*
X1198350Y382750D01*
X1198100Y383417D01*
X1197767Y383917D01*
X1197267Y384333D01*
X1196600Y384500D01*
G01X1200700Y379333D02*
X1203700Y384500D01*
G01X1200700D02*
X1200200Y384333D01*
X1199950Y384083D01*
X1199783Y383583D01*
X1199950Y383083D01*
X1200200Y382833D01*
X1200700Y382667D01*
X1201200Y382833D01*
X1201450Y383083D01*
X1201617Y383583D01*
X1201450Y384083D01*
X1201200Y384333D01*
X1200700Y384500D01*
G01X1203700Y381167D02*
X1203200Y381000D01*
X1202950Y380750D01*
X1202783Y380250D01*
X1202950Y379750D01*
X1203200Y379500D01*
X1203700Y379333D01*
X1204200Y379500D01*
X1204450Y379750D01*
X1204617Y380250D01*
X1204450Y380750D01*
X1204200Y381000D01*
X1203700Y381167D01*
G01X1212233Y379500D02*
Y382833D01*
G01Y382167D02*
X1212650Y382500D01*
X1213067Y382750D01*
X1213650Y382833D01*
X1214067Y382750D01*
X1214567Y382500D01*
G01X1217750Y381750D02*
X1220417D01*
X1220167Y382333D01*
X1219750Y382667D01*
X1219167Y382833D01*
X1218583Y382750D01*
X1218083Y382500D01*
X1217750Y381917D01*
X1217583Y381417D01*
Y380917D01*
X1217750Y380417D01*
X1218167Y379917D01*
X1218667Y379583D01*
X1219250Y379500D01*
X1219833Y379667D01*
X1220417Y380167D01*
G01X1223350Y380083D02*
X1223767Y379750D01*
X1224350Y379500D01*
X1224850D01*
X1225350Y379667D01*
X1225683Y379917D01*
X1225850Y380250D01*
X1225767Y380750D01*
X1225433Y381000D01*
X1223933Y381500D01*
X1223600Y382083D01*
X1223767Y382500D01*
X1224100Y382750D01*
X1224600Y382833D01*
X1225100Y382750D01*
X1225600Y382500D01*
G01X1230200Y382833D02*
Y379500D01*
G01Y384167D02*
X1230033Y384250D01*
Y384417D01*
X1230200Y384500D01*
X1230367Y384417D01*
Y384250D01*
X1230200Y384167D01*
G01X1234383Y379500D02*
Y382833D01*
G01Y382000D02*
X1234717Y382417D01*
X1235217Y382750D01*
X1235883Y382833D01*
X1236467Y382750D01*
X1236967Y382417D01*
X1237217Y381833D01*
Y379500D01*
G01X1246417Y378000D02*
X1247583Y379167D01*
Y380333D01*
X1246417D01*
Y379167D01*
X1247583D01*
G01Y381167D02*
Y382333D01*
X1246417D01*
Y381167D01*
X1247583D01*
G01X1250767Y379500D02*
Y384500D01*
X1252433D01*
X1253100Y384250D01*
X1253600Y383917D01*
X1254017Y383417D01*
X1254350Y382833D01*
X1254433Y382000D01*
X1254350Y381167D01*
X1254017Y380583D01*
X1253600Y380083D01*
X1253100Y379750D01*
X1252433Y379500D01*
X1250767D01*
G01X1258200D02*
X1257700Y379583D01*
X1257200Y379917D01*
X1256867Y380500D01*
X1256700Y381167D01*
X1256867Y381833D01*
X1257200Y382417D01*
X1257700Y382750D01*
X1258200Y382833D01*
X1258700Y382750D01*
X1259200Y382417D01*
X1259533Y381833D01*
X1259617Y381167D01*
X1259533Y380500D01*
X1259200Y379917D01*
X1258700Y379583D01*
X1258200Y379500D01*
G01X1267983D02*
Y382833D01*
G01Y382000D02*
X1268317Y382417D01*
X1268817Y382750D01*
X1269483Y382833D01*
X1270067Y382750D01*
X1270567Y382417D01*
X1270817Y381833D01*
Y379500D01*
G01X1275000D02*
X1274500Y379583D01*
X1274000Y379917D01*
X1273667Y380500D01*
X1273500Y381167D01*
X1273667Y381833D01*
X1274000Y382417D01*
X1274500Y382750D01*
X1275000Y382833D01*
X1275500Y382750D01*
X1276000Y382417D01*
X1276333Y381833D01*
X1276417Y381167D01*
X1276333Y380500D01*
X1276000Y379917D01*
X1275500Y379583D01*
X1275000Y379500D01*
G01X1280600Y384500D02*
Y379500D01*
G01X1279433Y382833D02*
X1281767D01*
G01X1293300Y379500D02*
Y382833D01*
G01Y382250D02*
X1292967Y382583D01*
X1292467Y382750D01*
X1291883Y382833D01*
X1291300Y382667D01*
X1290800Y382333D01*
X1290467Y381833D01*
X1290300Y381167D01*
X1290467Y380500D01*
X1290800Y380000D01*
X1291300Y379667D01*
X1291883Y379500D01*
X1292467Y379583D01*
X1292967Y379833D01*
X1293300Y380167D01*
G01X1297400Y379500D02*
Y384500D01*
G01X1303000Y379500D02*
Y384500D01*
G01X1308600Y379500D02*
X1308100Y379583D01*
X1307600Y379917D01*
X1307267Y380500D01*
X1307100Y381167D01*
X1307267Y381833D01*
X1307600Y382417D01*
X1308100Y382750D01*
X1308600Y382833D01*
X1309100Y382750D01*
X1309600Y382417D01*
X1309933Y381833D01*
X1310017Y381167D01*
X1309933Y380500D01*
X1309600Y379917D01*
X1309100Y379583D01*
X1308600Y379500D01*
G01X1312117Y382833D02*
X1313117Y379500D01*
X1314200Y382833D01*
X1315283Y379500D01*
X1316283Y382833D01*
G01X1023000Y390000D02*
Y395000D01*
X1022000Y394000D01*
G01Y390000D02*
X1024000D01*
G01X1028600Y389833D02*
X1028433Y389917D01*
Y390083D01*
X1028600Y390167D01*
X1028767Y390083D01*
Y389917D01*
X1028600Y389833D01*
G01X1032367Y390000D02*
Y395000D01*
X1034033D01*
X1034700Y394750D01*
X1035200Y394417D01*
X1035617Y393917D01*
X1035950Y393333D01*
X1036033Y392500D01*
X1035950Y391667D01*
X1035617Y391083D01*
X1035200Y390583D01*
X1034700Y390250D01*
X1034033Y390000D01*
X1032367D01*
G01X1039800Y393333D02*
Y390000D01*
G01Y394667D02*
X1039633Y394750D01*
Y394917D01*
X1039800Y395000D01*
X1039967Y394917D01*
Y394750D01*
X1039800Y394667D01*
G01X1042900Y390000D02*
Y393333D01*
G01Y392417D02*
X1043150Y392833D01*
X1043567Y393167D01*
X1044150Y393333D01*
X1044733Y393167D01*
X1045150Y392833D01*
X1045400Y392417D01*
Y390000D01*
G01Y392417D02*
X1045650Y392833D01*
X1046067Y393167D01*
X1046650Y393333D01*
X1047233Y393167D01*
X1047650Y392833D01*
X1047900Y392333D01*
Y390000D01*
G01X1049500Y388333D02*
Y393333D01*
G01Y392583D02*
X1049917Y393000D01*
X1050333Y393250D01*
X1051000Y393333D01*
X1051583Y393250D01*
X1052167Y392833D01*
X1052417Y392250D01*
X1052500Y391667D01*
X1052417Y391083D01*
X1052167Y390500D01*
X1051667Y390167D01*
X1051000Y390000D01*
X1050417Y390083D01*
X1049833Y390333D01*
X1049500Y390667D01*
G01X1056600Y390000D02*
Y395000D01*
G01X1060950Y392250D02*
X1063617D01*
X1063367Y392833D01*
X1062950Y393167D01*
X1062367Y393333D01*
X1061783Y393250D01*
X1061283Y393000D01*
X1060950Y392417D01*
X1060783Y391917D01*
Y391417D01*
X1060950Y390917D01*
X1061367Y390417D01*
X1061867Y390083D01*
X1062450Y390000D01*
X1063033Y390167D01*
X1063617Y390667D01*
G01X1075067Y390000D02*
X1071733Y391667D01*
X1075067Y393333D01*
G01X1084600Y390000D02*
Y395000D01*
X1083600Y394000D01*
G01Y390000D02*
X1085600D01*
G01X1093300D02*
Y393333D01*
G01Y392417D02*
X1093550Y392833D01*
X1093967Y393167D01*
X1094550Y393333D01*
X1095133Y393167D01*
X1095550Y392833D01*
X1095800Y392417D01*
Y390000D01*
G01Y392417D02*
X1096050Y392833D01*
X1096467Y393167D01*
X1097050Y393333D01*
X1097633Y393167D01*
X1098050Y392833D01*
X1098300Y392333D01*
Y390000D01*
G01X1101400Y393333D02*
Y390000D01*
G01Y394667D02*
X1101233Y394750D01*
Y394917D01*
X1101400Y395000D01*
X1101567Y394917D01*
Y394750D01*
X1101400Y394667D01*
G01X1107000Y390000D02*
Y395000D01*
G01X1117617Y388500D02*
X1118783Y389667D01*
Y390833D01*
X1117617D01*
Y389667D01*
X1118783D01*
G01Y391667D02*
Y392833D01*
X1117617D01*
Y391667D01*
X1118783D01*
G01X1023000Y424000D02*
Y429000D01*
X1022000Y428000D01*
G01Y424000D02*
X1024000D01*
G01X1028600Y423833D02*
X1028433Y423917D01*
Y424083D01*
X1028600Y424167D01*
X1028767Y424083D01*
Y423917D01*
X1028600Y423833D01*
G01X1032117Y429000D02*
X1034200Y424000D01*
X1036283Y429000D01*
G01X1039800Y427333D02*
Y424000D01*
G01Y428667D02*
X1039633Y428750D01*
Y428917D01*
X1039800Y429000D01*
X1039967Y428917D01*
Y428750D01*
X1039800Y428667D01*
G01X1046900Y424000D02*
Y427333D01*
G01Y426750D02*
X1046567Y427083D01*
X1046067Y427250D01*
X1045483Y427333D01*
X1044900Y427167D01*
X1044400Y426833D01*
X1044067Y426333D01*
X1043900Y425667D01*
X1044067Y425000D01*
X1044400Y424500D01*
X1044900Y424167D01*
X1045483Y424000D01*
X1046067Y424083D01*
X1046567Y424333D01*
X1046900Y424667D01*
G01X1055350Y424583D02*
X1055767Y424250D01*
X1056350Y424000D01*
X1056850D01*
X1057350Y424167D01*
X1057683Y424417D01*
X1057850Y424750D01*
X1057767Y425250D01*
X1057433Y425500D01*
X1055933Y426000D01*
X1055600Y426583D01*
X1055767Y427000D01*
X1056100Y427250D01*
X1056600Y427333D01*
X1057100Y427250D01*
X1057600Y427000D01*
G01X1060783Y424000D02*
Y429000D01*
G01Y426583D02*
X1061200Y427000D01*
X1061617Y427250D01*
X1062283Y427333D01*
X1062783Y427250D01*
X1063367Y426917D01*
X1063617Y426417D01*
Y424000D01*
G01X1067800D02*
X1067300Y424083D01*
X1066800Y424417D01*
X1066467Y425000D01*
X1066300Y425667D01*
X1066467Y426333D01*
X1066800Y426917D01*
X1067300Y427250D01*
X1067800Y427333D01*
X1068300Y427250D01*
X1068800Y426917D01*
X1069133Y426333D01*
X1069217Y425667D01*
X1069133Y425000D01*
X1068800Y424417D01*
X1068300Y424083D01*
X1067800Y424000D01*
G01X1071983Y427333D02*
Y425000D01*
X1072317Y424417D01*
X1072817Y424083D01*
X1073400Y424000D01*
X1073983Y424083D01*
X1074483Y424417D01*
X1074817Y425000D01*
G01Y424000D02*
Y427333D01*
G01X1079000Y424000D02*
Y429000D01*
G01X1086100D02*
Y424000D01*
G01Y424750D02*
X1085767Y424333D01*
X1085267Y424083D01*
X1084683Y424000D01*
X1084017Y424167D01*
X1083517Y424583D01*
X1083183Y425083D01*
X1083100Y425667D01*
X1083183Y426250D01*
X1083517Y426750D01*
X1084017Y427167D01*
X1084683Y427333D01*
X1085267Y427250D01*
X1085683Y427083D01*
X1086100Y426750D01*
G01X1094300Y424000D02*
Y429000D01*
G01Y426500D02*
X1094717Y427000D01*
X1095217Y427250D01*
X1095717Y427333D01*
X1096467Y427167D01*
X1096967Y426833D01*
X1097300Y426250D01*
Y425583D01*
X1097133Y424917D01*
X1096800Y424417D01*
X1096217Y424083D01*
X1095717Y424000D01*
X1095217Y424083D01*
X1094717Y424333D01*
X1094300Y424750D01*
G01X1100150Y426250D02*
X1102817D01*
X1102567Y426833D01*
X1102150Y427167D01*
X1101567Y427333D01*
X1100983Y427250D01*
X1100483Y427000D01*
X1100150Y426417D01*
X1099983Y425917D01*
Y425417D01*
X1100150Y424917D01*
X1100567Y424417D01*
X1101067Y424083D01*
X1101650Y424000D01*
X1102233Y424167D01*
X1102817Y424667D01*
G01X1111100Y422333D02*
Y427333D01*
G01Y426583D02*
X1111517Y427000D01*
X1111933Y427250D01*
X1112600Y427333D01*
X1113183Y427250D01*
X1113767Y426833D01*
X1114017Y426250D01*
X1114100Y425667D01*
X1114017Y425083D01*
X1113767Y424500D01*
X1113267Y424167D01*
X1112600Y424000D01*
X1112017Y424083D01*
X1111433Y424333D01*
X1111100Y424667D01*
G01X1118200Y424000D02*
Y429000D01*
G01X1122383Y427333D02*
Y425000D01*
X1122717Y424417D01*
X1123217Y424083D01*
X1123800Y424000D01*
X1124383Y424083D01*
X1124883Y424417D01*
X1125217Y425000D01*
G01Y424000D02*
Y427333D01*
G01X1128233Y422750D02*
X1128817Y422417D01*
X1129483Y422333D01*
X1130067Y422417D01*
X1130567Y422833D01*
X1130900Y423417D01*
Y427333D01*
G01Y426667D02*
X1130567Y427000D01*
X1130067Y427250D01*
X1129483Y427333D01*
X1128817Y427167D01*
X1128400Y426833D01*
X1128067Y426250D01*
X1127900Y425667D01*
X1127983Y425167D01*
X1128317Y424583D01*
X1128817Y424167D01*
X1129483Y424000D01*
X1129983Y424083D01*
X1130567Y424417D01*
X1130900Y424750D01*
G01X1133833Y422750D02*
X1134417Y422417D01*
X1135083Y422333D01*
X1135667Y422417D01*
X1136167Y422833D01*
X1136500Y423417D01*
Y427333D01*
G01Y426667D02*
X1136167Y427000D01*
X1135667Y427250D01*
X1135083Y427333D01*
X1134417Y427167D01*
X1134000Y426833D01*
X1133667Y426250D01*
X1133500Y425667D01*
X1133583Y425167D01*
X1133917Y424583D01*
X1134417Y424167D01*
X1135083Y424000D01*
X1135583Y424083D01*
X1136167Y424417D01*
X1136500Y424750D01*
G01X1139350Y426250D02*
X1142017D01*
X1141767Y426833D01*
X1141350Y427167D01*
X1140767Y427333D01*
X1140183Y427250D01*
X1139683Y427000D01*
X1139350Y426417D01*
X1139183Y425917D01*
Y425417D01*
X1139350Y424917D01*
X1139767Y424417D01*
X1140267Y424083D01*
X1140850Y424000D01*
X1141433Y424167D01*
X1142017Y424667D01*
G01X1147700Y429000D02*
Y424000D01*
G01Y424750D02*
X1147367Y424333D01*
X1146867Y424083D01*
X1146283Y424000D01*
X1145617Y424167D01*
X1145117Y424583D01*
X1144783Y425083D01*
X1144700Y425667D01*
X1144783Y426250D01*
X1145117Y426750D01*
X1145617Y427167D01*
X1146283Y427333D01*
X1146867Y427250D01*
X1147283Y427083D01*
X1147700Y426750D01*
G01X1155317Y427333D02*
X1156317Y424000D01*
X1157400Y427333D01*
X1158483Y424000D01*
X1159483Y427333D01*
G01X1163000D02*
Y424000D01*
G01Y428667D02*
X1162833Y428750D01*
Y428917D01*
X1163000Y429000D01*
X1163167Y428917D01*
Y428750D01*
X1163000Y428667D01*
G01X1168600Y429000D02*
Y424000D01*
G01X1167433Y427333D02*
X1169767D01*
G01X1172783Y424000D02*
Y429000D01*
G01Y426583D02*
X1173200Y427000D01*
X1173617Y427250D01*
X1174283Y427333D01*
X1174783Y427250D01*
X1175367Y426917D01*
X1175617Y426417D01*
Y424000D01*
G01X1183733D02*
X1187067Y425667D01*
X1183733Y427333D01*
G01X1189583Y424583D02*
X1190167Y424167D01*
X1190833Y424000D01*
X1191500Y424167D01*
X1192083Y424667D01*
X1192500Y425417D01*
X1192667Y426167D01*
Y427083D01*
X1192500Y427833D01*
X1192083Y428500D01*
X1191583Y428833D01*
X1191000Y429000D01*
X1190333Y428833D01*
X1189833Y428500D01*
X1189500Y428000D01*
X1189333Y427333D01*
X1189500Y426750D01*
X1189917Y426167D01*
X1190417Y425833D01*
X1191000Y425750D01*
X1191667Y425917D01*
X1192167Y426333D01*
X1192667Y427083D01*
G01X1196600Y429000D02*
X1195933Y428833D01*
X1195433Y428417D01*
X1195100Y427917D01*
X1194850Y427250D01*
X1194767Y426500D01*
X1194850Y425750D01*
X1195100Y425083D01*
X1195433Y424583D01*
X1195933Y424167D01*
X1196600Y424000D01*
X1197267Y424167D01*
X1197767Y424583D01*
X1198100Y425083D01*
X1198350Y425750D01*
X1198433Y426500D01*
X1198350Y427250D01*
X1198100Y427917D01*
X1197767Y428417D01*
X1197267Y428833D01*
X1196600Y429000D01*
G01X1200700Y423833D02*
X1203700Y429000D01*
G01X1200700D02*
X1200200Y428833D01*
X1199950Y428583D01*
X1199783Y428083D01*
X1199950Y427583D01*
X1200200Y427333D01*
X1200700Y427167D01*
X1201200Y427333D01*
X1201450Y427583D01*
X1201617Y428083D01*
X1201450Y428583D01*
X1201200Y428833D01*
X1200700Y429000D01*
G01X1203700Y425667D02*
X1203200Y425500D01*
X1202950Y425250D01*
X1202783Y424750D01*
X1202950Y424250D01*
X1203200Y424000D01*
X1203700Y423833D01*
X1204200Y424000D01*
X1204450Y424250D01*
X1204617Y424750D01*
X1204450Y425250D01*
X1204200Y425500D01*
X1203700Y425667D01*
G01X1212233Y424000D02*
Y427333D01*
G01Y426667D02*
X1212650Y427000D01*
X1213067Y427250D01*
X1213650Y427333D01*
X1214067Y427250D01*
X1214567Y427000D01*
G01X1217750Y426250D02*
X1220417D01*
X1220167Y426833D01*
X1219750Y427167D01*
X1219167Y427333D01*
X1218583Y427250D01*
X1218083Y427000D01*
X1217750Y426417D01*
X1217583Y425917D01*
Y425417D01*
X1217750Y424917D01*
X1218167Y424417D01*
X1218667Y424083D01*
X1219250Y424000D01*
X1219833Y424167D01*
X1220417Y424667D01*
G01X1223350Y424583D02*
X1223767Y424250D01*
X1224350Y424000D01*
X1224850D01*
X1225350Y424167D01*
X1225683Y424417D01*
X1225850Y424750D01*
X1225767Y425250D01*
X1225433Y425500D01*
X1223933Y426000D01*
X1223600Y426583D01*
X1223767Y427000D01*
X1224100Y427250D01*
X1224600Y427333D01*
X1225100Y427250D01*
X1225600Y427000D01*
G01X1230200Y427333D02*
Y424000D01*
G01Y428667D02*
X1230033Y428750D01*
Y428917D01*
X1230200Y429000D01*
X1230367Y428917D01*
Y428750D01*
X1230200Y428667D01*
G01X1234383Y424000D02*
Y427333D01*
G01Y426500D02*
X1234717Y426917D01*
X1235217Y427250D01*
X1235883Y427333D01*
X1236467Y427250D01*
X1236967Y426917D01*
X1237217Y426333D01*
Y424000D01*
G01X1246417Y422500D02*
X1247583Y423667D01*
Y424833D01*
X1246417D01*
Y423667D01*
X1247583D01*
G01Y425667D02*
Y426833D01*
X1246417D01*
Y425667D01*
X1247583D01*
G01X1250767Y424000D02*
Y429000D01*
X1252433D01*
X1253100Y428750D01*
X1253600Y428417D01*
X1254017Y427917D01*
X1254350Y427333D01*
X1254433Y426500D01*
X1254350Y425667D01*
X1254017Y425083D01*
X1253600Y424583D01*
X1253100Y424250D01*
X1252433Y424000D01*
X1250767D01*
G01X1258200D02*
X1257700Y424083D01*
X1257200Y424417D01*
X1256867Y425000D01*
X1256700Y425667D01*
X1256867Y426333D01*
X1257200Y426917D01*
X1257700Y427250D01*
X1258200Y427333D01*
X1258700Y427250D01*
X1259200Y426917D01*
X1259533Y426333D01*
X1259617Y425667D01*
X1259533Y425000D01*
X1259200Y424417D01*
X1258700Y424083D01*
X1258200Y424000D01*
G01X1267983D02*
Y427333D01*
G01Y426500D02*
X1268317Y426917D01*
X1268817Y427250D01*
X1269483Y427333D01*
X1270067Y427250D01*
X1270567Y426917D01*
X1270817Y426333D01*
Y424000D01*
G01X1275000D02*
X1274500Y424083D01*
X1274000Y424417D01*
X1273667Y425000D01*
X1273500Y425667D01*
X1273667Y426333D01*
X1274000Y426917D01*
X1274500Y427250D01*
X1275000Y427333D01*
X1275500Y427250D01*
X1276000Y426917D01*
X1276333Y426333D01*
X1276417Y425667D01*
X1276333Y425000D01*
X1276000Y424417D01*
X1275500Y424083D01*
X1275000Y424000D01*
G01X1280600Y429000D02*
Y424000D01*
G01X1279433Y427333D02*
X1281767D01*
G01X1293300Y424000D02*
Y427333D01*
G01Y426750D02*
X1292967Y427083D01*
X1292467Y427250D01*
X1291883Y427333D01*
X1291300Y427167D01*
X1290800Y426833D01*
X1290467Y426333D01*
X1290300Y425667D01*
X1290467Y425000D01*
X1290800Y424500D01*
X1291300Y424167D01*
X1291883Y424000D01*
X1292467Y424083D01*
X1292967Y424333D01*
X1293300Y424667D01*
G01X1297400Y424000D02*
Y429000D01*
G01X1303000Y424000D02*
Y429000D01*
G01X1308600Y424000D02*
X1308100Y424083D01*
X1307600Y424417D01*
X1307267Y425000D01*
X1307100Y425667D01*
X1307267Y426333D01*
X1307600Y426917D01*
X1308100Y427250D01*
X1308600Y427333D01*
X1309100Y427250D01*
X1309600Y426917D01*
X1309933Y426333D01*
X1310017Y425667D01*
X1309933Y425000D01*
X1309600Y424417D01*
X1309100Y424083D01*
X1308600Y424000D01*
G01X1312117Y427333D02*
X1313117Y424000D01*
X1314200Y427333D01*
X1315283Y424000D01*
X1316283Y427333D01*
G01X1025417Y445500D02*
X1027500Y440500D01*
X1029583Y445500D01*
G01X1033100Y443833D02*
Y440500D01*
G01Y445167D02*
X1032933Y445250D01*
Y445417D01*
X1033100Y445500D01*
X1033267Y445417D01*
Y445250D01*
X1033100Y445167D01*
G01X1040200Y440500D02*
Y443833D01*
G01Y443250D02*
X1039867Y443583D01*
X1039367Y443750D01*
X1038783Y443833D01*
X1038200Y443667D01*
X1037700Y443333D01*
X1037367Y442833D01*
X1037200Y442167D01*
X1037367Y441500D01*
X1037700Y441000D01*
X1038200Y440667D01*
X1038783Y440500D01*
X1039367Y440583D01*
X1039867Y440833D01*
X1040200Y441167D01*
G01X1048650Y441083D02*
X1049067Y440750D01*
X1049650Y440500D01*
X1050150D01*
X1050650Y440667D01*
X1050983Y440917D01*
X1051150Y441250D01*
X1051067Y441750D01*
X1050733Y442000D01*
X1049233Y442500D01*
X1048900Y443083D01*
X1049067Y443500D01*
X1049400Y443750D01*
X1049900Y443833D01*
X1050400Y443750D01*
X1050900Y443500D01*
G01X1054083Y440500D02*
Y445500D01*
G01Y443083D02*
X1054500Y443500D01*
X1054917Y443750D01*
X1055583Y443833D01*
X1056083Y443750D01*
X1056667Y443417D01*
X1056917Y442917D01*
Y440500D01*
G01X1061100D02*
X1060600Y440583D01*
X1060100Y440917D01*
X1059767Y441500D01*
X1059600Y442167D01*
X1059767Y442833D01*
X1060100Y443417D01*
X1060600Y443750D01*
X1061100Y443833D01*
X1061600Y443750D01*
X1062100Y443417D01*
X1062433Y442833D01*
X1062517Y442167D01*
X1062433Y441500D01*
X1062100Y440917D01*
X1061600Y440583D01*
X1061100Y440500D01*
G01X1065283Y443833D02*
Y441500D01*
X1065617Y440917D01*
X1066117Y440583D01*
X1066700Y440500D01*
X1067283Y440583D01*
X1067783Y440917D01*
X1068117Y441500D01*
G01Y440500D02*
Y443833D01*
G01X1072300Y440500D02*
Y445500D01*
G01X1079400D02*
Y440500D01*
G01Y441250D02*
X1079067Y440833D01*
X1078567Y440583D01*
X1077983Y440500D01*
X1077317Y440667D01*
X1076817Y441083D01*
X1076483Y441583D01*
X1076400Y442167D01*
X1076483Y442750D01*
X1076817Y443250D01*
X1077317Y443667D01*
X1077983Y443833D01*
X1078567Y443750D01*
X1078983Y443583D01*
X1079400Y443250D01*
G01X1087600Y440500D02*
Y445500D01*
G01Y443000D02*
X1088017Y443500D01*
X1088517Y443750D01*
X1089017Y443833D01*
X1089767Y443667D01*
X1090267Y443333D01*
X1090600Y442750D01*
Y442083D01*
X1090433Y441417D01*
X1090100Y440917D01*
X1089517Y440583D01*
X1089017Y440500D01*
X1088517Y440583D01*
X1088017Y440833D01*
X1087600Y441250D01*
G01X1093450Y442750D02*
X1096117D01*
X1095867Y443333D01*
X1095450Y443667D01*
X1094867Y443833D01*
X1094283Y443750D01*
X1093783Y443500D01*
X1093450Y442917D01*
X1093283Y442417D01*
Y441917D01*
X1093450Y441417D01*
X1093867Y440917D01*
X1094367Y440583D01*
X1094950Y440500D01*
X1095533Y440667D01*
X1096117Y441167D01*
G01X1104400Y438833D02*
Y443833D01*
G01Y443083D02*
X1104817Y443500D01*
X1105233Y443750D01*
X1105900Y443833D01*
X1106483Y443750D01*
X1107067Y443333D01*
X1107317Y442750D01*
X1107400Y442167D01*
X1107317Y441583D01*
X1107067Y441000D01*
X1106567Y440667D01*
X1105900Y440500D01*
X1105317Y440583D01*
X1104733Y440833D01*
X1104400Y441167D01*
G01X1111500Y440500D02*
Y445500D01*
G01X1115683Y443833D02*
Y441500D01*
X1116017Y440917D01*
X1116517Y440583D01*
X1117100Y440500D01*
X1117683Y440583D01*
X1118183Y440917D01*
X1118517Y441500D01*
G01Y440500D02*
Y443833D01*
G01X1121533Y439250D02*
X1122117Y438917D01*
X1122783Y438833D01*
X1123367Y438917D01*
X1123867Y439333D01*
X1124200Y439917D01*
Y443833D01*
G01Y443167D02*
X1123867Y443500D01*
X1123367Y443750D01*
X1122783Y443833D01*
X1122117Y443667D01*
X1121700Y443333D01*
X1121367Y442750D01*
X1121200Y442167D01*
X1121283Y441667D01*
X1121617Y441083D01*
X1122117Y440667D01*
X1122783Y440500D01*
X1123283Y440583D01*
X1123867Y440917D01*
X1124200Y441250D01*
G01X1127133Y439250D02*
X1127717Y438917D01*
X1128383Y438833D01*
X1128967Y438917D01*
X1129467Y439333D01*
X1129800Y439917D01*
Y443833D01*
G01Y443167D02*
X1129467Y443500D01*
X1128967Y443750D01*
X1128383Y443833D01*
X1127717Y443667D01*
X1127300Y443333D01*
X1126967Y442750D01*
X1126800Y442167D01*
X1126883Y441667D01*
X1127217Y441083D01*
X1127717Y440667D01*
X1128383Y440500D01*
X1128883Y440583D01*
X1129467Y440917D01*
X1129800Y441250D01*
G01X1132650Y442750D02*
X1135317D01*
X1135067Y443333D01*
X1134650Y443667D01*
X1134067Y443833D01*
X1133483Y443750D01*
X1132983Y443500D01*
X1132650Y442917D01*
X1132483Y442417D01*
Y441917D01*
X1132650Y441417D01*
X1133067Y440917D01*
X1133567Y440583D01*
X1134150Y440500D01*
X1134733Y440667D01*
X1135317Y441167D01*
G01X1141000Y445500D02*
Y440500D01*
G01Y441250D02*
X1140667Y440833D01*
X1140167Y440583D01*
X1139583Y440500D01*
X1138917Y440667D01*
X1138417Y441083D01*
X1138083Y441583D01*
X1138000Y442167D01*
X1138083Y442750D01*
X1138417Y443250D01*
X1138917Y443667D01*
X1139583Y443833D01*
X1140167Y443750D01*
X1140583Y443583D01*
X1141000Y443250D01*
G01X1148617Y443833D02*
X1149617Y440500D01*
X1150700Y443833D01*
X1151783Y440500D01*
X1152783Y443833D01*
G01X1156300D02*
Y440500D01*
G01Y445167D02*
X1156133Y445250D01*
Y445417D01*
X1156300Y445500D01*
X1156467Y445417D01*
Y445250D01*
X1156300Y445167D01*
G01X1161900Y445500D02*
Y440500D01*
G01X1160733Y443833D02*
X1163067D01*
G01X1166083Y440500D02*
Y445500D01*
G01Y443083D02*
X1166500Y443500D01*
X1166917Y443750D01*
X1167583Y443833D01*
X1168083Y443750D01*
X1168667Y443417D01*
X1168917Y442917D01*
Y440500D01*
G01X1177033D02*
X1180367Y442167D01*
X1177033Y443833D01*
G01X1182883Y441083D02*
X1183467Y440667D01*
X1184133Y440500D01*
X1184800Y440667D01*
X1185383Y441167D01*
X1185800Y441917D01*
X1185967Y442667D01*
Y443583D01*
X1185800Y444333D01*
X1185383Y445000D01*
X1184883Y445333D01*
X1184300Y445500D01*
X1183633Y445333D01*
X1183133Y445000D01*
X1182800Y444500D01*
X1182633Y443833D01*
X1182800Y443250D01*
X1183217Y442667D01*
X1183717Y442333D01*
X1184300Y442250D01*
X1184967Y442417D01*
X1185467Y442833D01*
X1185967Y443583D01*
G01X1189900Y445500D02*
X1189233Y445333D01*
X1188733Y444917D01*
X1188400Y444417D01*
X1188150Y443750D01*
X1188067Y443000D01*
X1188150Y442250D01*
X1188400Y441583D01*
X1188733Y441083D01*
X1189233Y440667D01*
X1189900Y440500D01*
X1190567Y440667D01*
X1191067Y441083D01*
X1191400Y441583D01*
X1191650Y442250D01*
X1191733Y443000D01*
X1191650Y443750D01*
X1191400Y444417D01*
X1191067Y444917D01*
X1190567Y445333D01*
X1189900Y445500D01*
G01X1194000Y440333D02*
X1197000Y445500D01*
G01X1194000D02*
X1193500Y445333D01*
X1193250Y445083D01*
X1193083Y444583D01*
X1193250Y444083D01*
X1193500Y443833D01*
X1194000Y443667D01*
X1194500Y443833D01*
X1194750Y444083D01*
X1194917Y444583D01*
X1194750Y445083D01*
X1194500Y445333D01*
X1194000Y445500D01*
G01X1197000Y442167D02*
X1196500Y442000D01*
X1196250Y441750D01*
X1196083Y441250D01*
X1196250Y440750D01*
X1196500Y440500D01*
X1197000Y440333D01*
X1197500Y440500D01*
X1197750Y440750D01*
X1197917Y441250D01*
X1197750Y441750D01*
X1197500Y442000D01*
X1197000Y442167D01*
G01X1205533Y440500D02*
Y443833D01*
G01Y443167D02*
X1205950Y443500D01*
X1206367Y443750D01*
X1206950Y443833D01*
X1207367Y443750D01*
X1207867Y443500D01*
G01X1211050Y442750D02*
X1213717D01*
X1213467Y443333D01*
X1213050Y443667D01*
X1212467Y443833D01*
X1211883Y443750D01*
X1211383Y443500D01*
X1211050Y442917D01*
X1210883Y442417D01*
Y441917D01*
X1211050Y441417D01*
X1211467Y440917D01*
X1211967Y440583D01*
X1212550Y440500D01*
X1213133Y440667D01*
X1213717Y441167D01*
G01X1216650Y441083D02*
X1217067Y440750D01*
X1217650Y440500D01*
X1218150D01*
X1218650Y440667D01*
X1218983Y440917D01*
X1219150Y441250D01*
X1219067Y441750D01*
X1218733Y442000D01*
X1217233Y442500D01*
X1216900Y443083D01*
X1217067Y443500D01*
X1217400Y443750D01*
X1217900Y443833D01*
X1218400Y443750D01*
X1218900Y443500D01*
G01X1223500Y443833D02*
Y440500D01*
G01Y445167D02*
X1223333Y445250D01*
Y445417D01*
X1223500Y445500D01*
X1223667Y445417D01*
Y445250D01*
X1223500Y445167D01*
G01X1227683Y440500D02*
Y443833D01*
G01Y443000D02*
X1228017Y443417D01*
X1228517Y443750D01*
X1229183Y443833D01*
X1229767Y443750D01*
X1230267Y443417D01*
X1230517Y442833D01*
Y440500D01*
G01X1016000Y604500D02*
Y366000D01*
G01X1023917Y466500D02*
X1026000Y461500D01*
X1028083Y466500D01*
G01X1031600Y464833D02*
Y461500D01*
G01Y466167D02*
X1031433Y466250D01*
Y466417D01*
X1031600Y466500D01*
X1031767Y466417D01*
Y466250D01*
X1031600Y466167D01*
G01X1038700Y461500D02*
Y464833D01*
G01Y464250D02*
X1038367Y464583D01*
X1037867Y464750D01*
X1037283Y464833D01*
X1036700Y464667D01*
X1036200Y464333D01*
X1035867Y463833D01*
X1035700Y463167D01*
X1035867Y462500D01*
X1036200Y462000D01*
X1036700Y461667D01*
X1037283Y461500D01*
X1037867Y461583D01*
X1038367Y461833D01*
X1038700Y462167D01*
G01X1047150Y462083D02*
X1047567Y461750D01*
X1048150Y461500D01*
X1048650D01*
X1049150Y461667D01*
X1049483Y461917D01*
X1049650Y462250D01*
X1049567Y462750D01*
X1049233Y463000D01*
X1047733Y463500D01*
X1047400Y464083D01*
X1047567Y464500D01*
X1047900Y464750D01*
X1048400Y464833D01*
X1048900Y464750D01*
X1049400Y464500D01*
G01X1052583Y461500D02*
Y466500D01*
G01Y464083D02*
X1053000Y464500D01*
X1053417Y464750D01*
X1054083Y464833D01*
X1054583Y464750D01*
X1055167Y464417D01*
X1055417Y463917D01*
Y461500D01*
G01X1059600D02*
X1059100Y461583D01*
X1058600Y461917D01*
X1058267Y462500D01*
X1058100Y463167D01*
X1058267Y463833D01*
X1058600Y464417D01*
X1059100Y464750D01*
X1059600Y464833D01*
X1060100Y464750D01*
X1060600Y464417D01*
X1060933Y463833D01*
X1061017Y463167D01*
X1060933Y462500D01*
X1060600Y461917D01*
X1060100Y461583D01*
X1059600Y461500D01*
G01X1063783Y464833D02*
Y462500D01*
X1064117Y461917D01*
X1064617Y461583D01*
X1065200Y461500D01*
X1065783Y461583D01*
X1066283Y461917D01*
X1066617Y462500D01*
G01Y461500D02*
Y464833D01*
G01X1070800Y461500D02*
Y466500D01*
G01X1077900D02*
Y461500D01*
G01Y462250D02*
X1077567Y461833D01*
X1077067Y461583D01*
X1076483Y461500D01*
X1075817Y461667D01*
X1075317Y462083D01*
X1074983Y462583D01*
X1074900Y463167D01*
X1074983Y463750D01*
X1075317Y464250D01*
X1075817Y464667D01*
X1076483Y464833D01*
X1077067Y464750D01*
X1077483Y464583D01*
X1077900Y464250D01*
G01X1086100Y461500D02*
Y466500D01*
G01Y464000D02*
X1086517Y464500D01*
X1087017Y464750D01*
X1087517Y464833D01*
X1088267Y464667D01*
X1088767Y464333D01*
X1089100Y463750D01*
Y463083D01*
X1088933Y462417D01*
X1088600Y461917D01*
X1088017Y461583D01*
X1087517Y461500D01*
X1087017Y461583D01*
X1086517Y461833D01*
X1086100Y462250D01*
G01X1091950Y463750D02*
X1094617D01*
X1094367Y464333D01*
X1093950Y464667D01*
X1093367Y464833D01*
X1092783Y464750D01*
X1092283Y464500D01*
X1091950Y463917D01*
X1091783Y463417D01*
Y462917D01*
X1091950Y462417D01*
X1092367Y461917D01*
X1092867Y461583D01*
X1093450Y461500D01*
X1094033Y461667D01*
X1094617Y462167D01*
G01X1102900Y459833D02*
Y464833D01*
G01Y464083D02*
X1103317Y464500D01*
X1103733Y464750D01*
X1104400Y464833D01*
X1104983Y464750D01*
X1105567Y464333D01*
X1105817Y463750D01*
X1105900Y463167D01*
X1105817Y462583D01*
X1105567Y462000D01*
X1105067Y461667D01*
X1104400Y461500D01*
X1103817Y461583D01*
X1103233Y461833D01*
X1102900Y462167D01*
G01X1110000Y461500D02*
Y466500D01*
G01X1114183Y464833D02*
Y462500D01*
X1114517Y461917D01*
X1115017Y461583D01*
X1115600Y461500D01*
X1116183Y461583D01*
X1116683Y461917D01*
X1117017Y462500D01*
G01Y461500D02*
Y464833D01*
G01X1120033Y460250D02*
X1120617Y459917D01*
X1121283Y459833D01*
X1121867Y459917D01*
X1122367Y460333D01*
X1122700Y460917D01*
Y464833D01*
G01Y464167D02*
X1122367Y464500D01*
X1121867Y464750D01*
X1121283Y464833D01*
X1120617Y464667D01*
X1120200Y464333D01*
X1119867Y463750D01*
X1119700Y463167D01*
X1119783Y462667D01*
X1120117Y462083D01*
X1120617Y461667D01*
X1121283Y461500D01*
X1121783Y461583D01*
X1122367Y461917D01*
X1122700Y462250D01*
G01X1125633Y460250D02*
X1126217Y459917D01*
X1126883Y459833D01*
X1127467Y459917D01*
X1127967Y460333D01*
X1128300Y460917D01*
Y464833D01*
G01Y464167D02*
X1127967Y464500D01*
X1127467Y464750D01*
X1126883Y464833D01*
X1126217Y464667D01*
X1125800Y464333D01*
X1125467Y463750D01*
X1125300Y463167D01*
X1125383Y462667D01*
X1125717Y462083D01*
X1126217Y461667D01*
X1126883Y461500D01*
X1127383Y461583D01*
X1127967Y461917D01*
X1128300Y462250D01*
G01X1131150Y463750D02*
X1133817D01*
X1133567Y464333D01*
X1133150Y464667D01*
X1132567Y464833D01*
X1131983Y464750D01*
X1131483Y464500D01*
X1131150Y463917D01*
X1130983Y463417D01*
Y462917D01*
X1131150Y462417D01*
X1131567Y461917D01*
X1132067Y461583D01*
X1132650Y461500D01*
X1133233Y461667D01*
X1133817Y462167D01*
G01X1139500Y466500D02*
Y461500D01*
G01Y462250D02*
X1139167Y461833D01*
X1138667Y461583D01*
X1138083Y461500D01*
X1137417Y461667D01*
X1136917Y462083D01*
X1136583Y462583D01*
X1136500Y463167D01*
X1136583Y463750D01*
X1136917Y464250D01*
X1137417Y464667D01*
X1138083Y464833D01*
X1138667Y464750D01*
X1139083Y464583D01*
X1139500Y464250D01*
G01X1150200Y461500D02*
Y466500D01*
X1147117Y462917D01*
X1151283D01*
G01X1154800Y466500D02*
X1154133Y466333D01*
X1153633Y465917D01*
X1153300Y465417D01*
X1153050Y464750D01*
X1152967Y464000D01*
X1153050Y463250D01*
X1153300Y462583D01*
X1153633Y462083D01*
X1154133Y461667D01*
X1154800Y461500D01*
X1155467Y461667D01*
X1155967Y462083D01*
X1156300Y462583D01*
X1156550Y463250D01*
X1156633Y464000D01*
X1156550Y464750D01*
X1156300Y465417D01*
X1155967Y465917D01*
X1155467Y466333D01*
X1154800Y466500D01*
G01X1158900Y461333D02*
X1161900Y466500D01*
G01X1158900D02*
X1158400Y466333D01*
X1158150Y466083D01*
X1157983Y465583D01*
X1158150Y465083D01*
X1158400Y464833D01*
X1158900Y464667D01*
X1159400Y464833D01*
X1159650Y465083D01*
X1159817Y465583D01*
X1159650Y466083D01*
X1159400Y466333D01*
X1158900Y466500D01*
G01X1161900Y463167D02*
X1161400Y463000D01*
X1161150Y462750D01*
X1160983Y462250D01*
X1161150Y461750D01*
X1161400Y461500D01*
X1161900Y461333D01*
X1162400Y461500D01*
X1162650Y461750D01*
X1162817Y462250D01*
X1162650Y462750D01*
X1162400Y463000D01*
X1161900Y463167D01*
G01X1169100D02*
X1169933Y464833D01*
X1170767D01*
X1172433Y461500D01*
X1173267D01*
X1174100Y463167D01*
G01X1182800Y461500D02*
Y466500D01*
X1181800Y465500D01*
G01Y461500D02*
X1183800D01*
G01X1188400Y466500D02*
X1187733Y466333D01*
X1187233Y465917D01*
X1186900Y465417D01*
X1186650Y464750D01*
X1186567Y464000D01*
X1186650Y463250D01*
X1186900Y462583D01*
X1187233Y462083D01*
X1187733Y461667D01*
X1188400Y461500D01*
X1189067Y461667D01*
X1189567Y462083D01*
X1189900Y462583D01*
X1190150Y463250D01*
X1190233Y464000D01*
X1190150Y464750D01*
X1189900Y465417D01*
X1189567Y465917D01*
X1189067Y466333D01*
X1188400Y466500D01*
G01X1194000D02*
X1193333Y466333D01*
X1192833Y465917D01*
X1192500Y465417D01*
X1192250Y464750D01*
X1192167Y464000D01*
X1192250Y463250D01*
X1192500Y462583D01*
X1192833Y462083D01*
X1193333Y461667D01*
X1194000Y461500D01*
X1194667Y461667D01*
X1195167Y462083D01*
X1195500Y462583D01*
X1195750Y463250D01*
X1195833Y464000D01*
X1195750Y464750D01*
X1195500Y465417D01*
X1195167Y465917D01*
X1194667Y466333D01*
X1194000Y466500D01*
G01X1198100Y461333D02*
X1201100Y466500D01*
G01X1198100D02*
X1197600Y466333D01*
X1197350Y466083D01*
X1197183Y465583D01*
X1197350Y465083D01*
X1197600Y464833D01*
X1198100Y464667D01*
X1198600Y464833D01*
X1198850Y465083D01*
X1199017Y465583D01*
X1198850Y466083D01*
X1198600Y466333D01*
X1198100Y466500D01*
G01X1201100Y463167D02*
X1200600Y463000D01*
X1200350Y462750D01*
X1200183Y462250D01*
X1200350Y461750D01*
X1200600Y461500D01*
X1201100Y461333D01*
X1201600Y461500D01*
X1201850Y461750D01*
X1202017Y462250D01*
X1201850Y462750D01*
X1201600Y463000D01*
X1201100Y463167D01*
G01X1209550Y462083D02*
X1209967Y461750D01*
X1210550Y461500D01*
X1211050D01*
X1211550Y461667D01*
X1211883Y461917D01*
X1212050Y462250D01*
X1211967Y462750D01*
X1211633Y463000D01*
X1210133Y463500D01*
X1209800Y464083D01*
X1209967Y464500D01*
X1210300Y464750D01*
X1210800Y464833D01*
X1211300Y464750D01*
X1211800Y464500D01*
G01X1216400Y461500D02*
X1215900Y461583D01*
X1215400Y461917D01*
X1215067Y462500D01*
X1214900Y463167D01*
X1215067Y463833D01*
X1215400Y464417D01*
X1215900Y464750D01*
X1216400Y464833D01*
X1216900Y464750D01*
X1217400Y464417D01*
X1217733Y463833D01*
X1217817Y463167D01*
X1217733Y462500D01*
X1217400Y461917D01*
X1216900Y461583D01*
X1216400Y461500D01*
G01X1222000D02*
Y466500D01*
G01X1229100D02*
Y461500D01*
G01Y462250D02*
X1228767Y461833D01*
X1228267Y461583D01*
X1227683Y461500D01*
X1227017Y461667D01*
X1226517Y462083D01*
X1226183Y462583D01*
X1226100Y463167D01*
X1226183Y463750D01*
X1226517Y464250D01*
X1227017Y464667D01*
X1227683Y464833D01*
X1228267Y464750D01*
X1228683Y464583D01*
X1229100Y464250D01*
G01X1231950Y463750D02*
X1234617D01*
X1234367Y464333D01*
X1233950Y464667D01*
X1233367Y464833D01*
X1232783Y464750D01*
X1232283Y464500D01*
X1231950Y463917D01*
X1231783Y463417D01*
Y462917D01*
X1231950Y462417D01*
X1232367Y461917D01*
X1232867Y461583D01*
X1233450Y461500D01*
X1234033Y461667D01*
X1234617Y462167D01*
G01X1237633Y461500D02*
Y464833D01*
G01Y464167D02*
X1238050Y464500D01*
X1238467Y464750D01*
X1239050Y464833D01*
X1239467Y464750D01*
X1239967Y464500D01*
G01X1247500Y461500D02*
Y464833D01*
G01Y463917D02*
X1247750Y464333D01*
X1248167Y464667D01*
X1248750Y464833D01*
X1249333Y464667D01*
X1249750Y464333D01*
X1250000Y463917D01*
Y461500D01*
G01Y463917D02*
X1250250Y464333D01*
X1250667Y464667D01*
X1251250Y464833D01*
X1251833Y464667D01*
X1252250Y464333D01*
X1252500Y463833D01*
Y461500D01*
G01X1257100D02*
Y464833D01*
G01Y464250D02*
X1256767Y464583D01*
X1256267Y464750D01*
X1255683Y464833D01*
X1255100Y464667D01*
X1254600Y464333D01*
X1254267Y463833D01*
X1254100Y463167D01*
X1254267Y462500D01*
X1254600Y462000D01*
X1255100Y461667D01*
X1255683Y461500D01*
X1256267Y461583D01*
X1256767Y461833D01*
X1257100Y462167D01*
G01X1259950Y462083D02*
X1260367Y461750D01*
X1260950Y461500D01*
X1261450D01*
X1261950Y461667D01*
X1262283Y461917D01*
X1262450Y462250D01*
X1262367Y462750D01*
X1262033Y463000D01*
X1260533Y463500D01*
X1260200Y464083D01*
X1260367Y464500D01*
X1260700Y464750D01*
X1261200Y464833D01*
X1261700Y464750D01*
X1262200Y464500D01*
G01X1265383Y461500D02*
Y466500D01*
G01X1268050Y464833D02*
X1265383Y462917D01*
G01X1266467Y463667D02*
X1268217Y461500D01*
G01X1020417Y542667D02*
X1020917Y543167D01*
X1021500Y543417D01*
X1022167Y543500D01*
X1023000Y543333D01*
X1023583Y542917D01*
X1023750Y542417D01*
X1023667Y541917D01*
X1023333Y541500D01*
X1021667Y540667D01*
X1020917Y540083D01*
X1020417Y539250D01*
X1020250Y538500D01*
X1023750D01*
G01X1027600Y538333D02*
X1027433Y538417D01*
Y538583D01*
X1027600Y538667D01*
X1027767Y538583D01*
Y538417D01*
X1027600Y538333D01*
G01X1033200Y543500D02*
Y538500D01*
G01X1031283Y543500D02*
X1035117D01*
G01X1037383Y538500D02*
Y543500D01*
G01Y541083D02*
X1037800Y541500D01*
X1038217Y541750D01*
X1038883Y541833D01*
X1039383Y541750D01*
X1039967Y541417D01*
X1040217Y540917D01*
Y538500D01*
G01X1043150Y540750D02*
X1045817D01*
X1045567Y541333D01*
X1045150Y541667D01*
X1044567Y541833D01*
X1043983Y541750D01*
X1043483Y541500D01*
X1043150Y540917D01*
X1042983Y540417D01*
Y539917D01*
X1043150Y539417D01*
X1043567Y538917D01*
X1044067Y538583D01*
X1044650Y538500D01*
X1045233Y538667D01*
X1045817Y539167D01*
G01X1054350Y539083D02*
X1054767Y538750D01*
X1055350Y538500D01*
X1055850D01*
X1056350Y538667D01*
X1056683Y538917D01*
X1056850Y539250D01*
X1056767Y539750D01*
X1056433Y540000D01*
X1054933Y540500D01*
X1054600Y541083D01*
X1054767Y541500D01*
X1055100Y541750D01*
X1055600Y541833D01*
X1056100Y541750D01*
X1056600Y541500D01*
G01X1061200Y541833D02*
Y538500D01*
G01Y543167D02*
X1061033Y543250D01*
Y543417D01*
X1061200Y543500D01*
X1061367Y543417D01*
Y543250D01*
X1061200Y543167D01*
G01X1068300Y543500D02*
Y538500D01*
G01Y539250D02*
X1067967Y538833D01*
X1067467Y538583D01*
X1066883Y538500D01*
X1066217Y538667D01*
X1065717Y539083D01*
X1065383Y539583D01*
X1065300Y540167D01*
X1065383Y540750D01*
X1065717Y541250D01*
X1066217Y541667D01*
X1066883Y541833D01*
X1067467Y541750D01*
X1067883Y541583D01*
X1068300Y541250D01*
G01X1071150Y540750D02*
X1073817D01*
X1073567Y541333D01*
X1073150Y541667D01*
X1072567Y541833D01*
X1071983Y541750D01*
X1071483Y541500D01*
X1071150Y540917D01*
X1070983Y540417D01*
Y539917D01*
X1071150Y539417D01*
X1071567Y538917D01*
X1072067Y538583D01*
X1072650Y538500D01*
X1073233Y538667D01*
X1073817Y539167D01*
G01X1081517Y541833D02*
X1082517Y538500D01*
X1083600Y541833D01*
X1084683Y538500D01*
X1085683Y541833D01*
G01X1089200D02*
Y538500D01*
G01Y543167D02*
X1089033Y543250D01*
Y543417D01*
X1089200Y543500D01*
X1089367Y543417D01*
Y543250D01*
X1089200Y543167D01*
G01X1094800Y543500D02*
Y538500D01*
G01X1093633Y541833D02*
X1095967D01*
G01X1098983Y538500D02*
Y543500D01*
G01Y541083D02*
X1099400Y541500D01*
X1099817Y541750D01*
X1100483Y541833D01*
X1100983Y541750D01*
X1101567Y541417D01*
X1101817Y540917D01*
Y538500D01*
G01X1110350Y539083D02*
X1110767Y538750D01*
X1111350Y538500D01*
X1111850D01*
X1112350Y538667D01*
X1112683Y538917D01*
X1112850Y539250D01*
X1112767Y539750D01*
X1112433Y540000D01*
X1110933Y540500D01*
X1110600Y541083D01*
X1110767Y541500D01*
X1111100Y541750D01*
X1111600Y541833D01*
X1112100Y541750D01*
X1112600Y541500D01*
G01X1117200Y538500D02*
X1116700Y538583D01*
X1116200Y538917D01*
X1115867Y539500D01*
X1115700Y540167D01*
X1115867Y540833D01*
X1116200Y541417D01*
X1116700Y541750D01*
X1117200Y541833D01*
X1117700Y541750D01*
X1118200Y541417D01*
X1118533Y540833D01*
X1118617Y540167D01*
X1118533Y539500D01*
X1118200Y538917D01*
X1117700Y538583D01*
X1117200Y538500D01*
G01X1122800D02*
Y543500D01*
G01X1129900D02*
Y538500D01*
G01Y539250D02*
X1129567Y538833D01*
X1129067Y538583D01*
X1128483Y538500D01*
X1127817Y538667D01*
X1127317Y539083D01*
X1126983Y539583D01*
X1126900Y540167D01*
X1126983Y540750D01*
X1127317Y541250D01*
X1127817Y541667D01*
X1128483Y541833D01*
X1129067Y541750D01*
X1129483Y541583D01*
X1129900Y541250D01*
G01X1132750Y540750D02*
X1135417D01*
X1135167Y541333D01*
X1134750Y541667D01*
X1134167Y541833D01*
X1133583Y541750D01*
X1133083Y541500D01*
X1132750Y540917D01*
X1132583Y540417D01*
Y539917D01*
X1132750Y539417D01*
X1133167Y538917D01*
X1133667Y538583D01*
X1134250Y538500D01*
X1134833Y538667D01*
X1135417Y539167D01*
G01X1138433Y538500D02*
Y541833D01*
G01Y541167D02*
X1138850Y541500D01*
X1139267Y541750D01*
X1139850Y541833D01*
X1140267Y541750D01*
X1140767Y541500D01*
G01X1148300Y538500D02*
Y541833D01*
G01Y540917D02*
X1148550Y541333D01*
X1148967Y541667D01*
X1149550Y541833D01*
X1150133Y541667D01*
X1150550Y541333D01*
X1150800Y540917D01*
Y538500D01*
G01Y540917D02*
X1151050Y541333D01*
X1151467Y541667D01*
X1152050Y541833D01*
X1152633Y541667D01*
X1153050Y541333D01*
X1153300Y540833D01*
Y538500D01*
G01X1157900D02*
Y541833D01*
G01Y541250D02*
X1157567Y541583D01*
X1157067Y541750D01*
X1156483Y541833D01*
X1155900Y541667D01*
X1155400Y541333D01*
X1155067Y540833D01*
X1154900Y540167D01*
X1155067Y539500D01*
X1155400Y539000D01*
X1155900Y538667D01*
X1156483Y538500D01*
X1157067Y538583D01*
X1157567Y538833D01*
X1157900Y539167D01*
G01X1160750Y539083D02*
X1161167Y538750D01*
X1161750Y538500D01*
X1162250D01*
X1162750Y538667D01*
X1163083Y538917D01*
X1163250Y539250D01*
X1163167Y539750D01*
X1162833Y540000D01*
X1161333Y540500D01*
X1161000Y541083D01*
X1161167Y541500D01*
X1161500Y541750D01*
X1162000Y541833D01*
X1162500Y541750D01*
X1163000Y541500D01*
G01X1166183Y538500D02*
Y543500D01*
G01X1168850Y541833D02*
X1166183Y539917D01*
G01X1167267Y540667D02*
X1169017Y538500D01*
G01X1177300Y536833D02*
Y541833D01*
G01Y541083D02*
X1177717Y541500D01*
X1178133Y541750D01*
X1178800Y541833D01*
X1179383Y541750D01*
X1179967Y541333D01*
X1180217Y540750D01*
X1180300Y540167D01*
X1180217Y539583D01*
X1179967Y539000D01*
X1179467Y538667D01*
X1178800Y538500D01*
X1178217Y538583D01*
X1177633Y538833D01*
X1177300Y539167D01*
G01X1185900Y538500D02*
Y541833D01*
G01Y541250D02*
X1185567Y541583D01*
X1185067Y541750D01*
X1184483Y541833D01*
X1183900Y541667D01*
X1183400Y541333D01*
X1183067Y540833D01*
X1182900Y540167D01*
X1183067Y539500D01*
X1183400Y539000D01*
X1183900Y538667D01*
X1184483Y538500D01*
X1185067Y538583D01*
X1185567Y538833D01*
X1185900Y539167D01*
G01X1191500Y543500D02*
Y538500D01*
G01Y539250D02*
X1191167Y538833D01*
X1190667Y538583D01*
X1190083Y538500D01*
X1189417Y538667D01*
X1188917Y539083D01*
X1188583Y539583D01*
X1188500Y540167D01*
X1188583Y540750D01*
X1188917Y541250D01*
X1189417Y541667D01*
X1190083Y541833D01*
X1190667Y541750D01*
X1191083Y541583D01*
X1191500Y541250D01*
G01X1195433Y537583D02*
X1195767Y538667D01*
G01X1206800Y543500D02*
Y538500D01*
G01X1205633Y541833D02*
X1207967D01*
G01X1210983Y538500D02*
Y543500D01*
G01Y541083D02*
X1211400Y541500D01*
X1211817Y541750D01*
X1212483Y541833D01*
X1212983Y541750D01*
X1213567Y541417D01*
X1213817Y540917D01*
Y538500D01*
G01X1216750Y540750D02*
X1219417D01*
X1219167Y541333D01*
X1218750Y541667D01*
X1218167Y541833D01*
X1217583Y541750D01*
X1217083Y541500D01*
X1216750Y540917D01*
X1216583Y540417D01*
Y539917D01*
X1216750Y539417D01*
X1217167Y538917D01*
X1217667Y538583D01*
X1218250Y538500D01*
X1218833Y538667D01*
X1219417Y539167D01*
G01X1230700Y538500D02*
Y541833D01*
G01Y541250D02*
X1230367Y541583D01*
X1229867Y541750D01*
X1229283Y541833D01*
X1228700Y541667D01*
X1228200Y541333D01*
X1227867Y540833D01*
X1227700Y540167D01*
X1227867Y539500D01*
X1228200Y539000D01*
X1228700Y538667D01*
X1229283Y538500D01*
X1229867Y538583D01*
X1230367Y538833D01*
X1230700Y539167D01*
G01X1233383Y538500D02*
Y541833D01*
G01Y541000D02*
X1233717Y541417D01*
X1234217Y541750D01*
X1234883Y541833D01*
X1235467Y541750D01*
X1235967Y541417D01*
X1236217Y540833D01*
Y538500D01*
G01X1238983D02*
Y541833D01*
G01Y541000D02*
X1239317Y541417D01*
X1239817Y541750D01*
X1240483Y541833D01*
X1241067Y541750D01*
X1241567Y541417D01*
X1241817Y540833D01*
Y538500D01*
G01X1244583Y541833D02*
Y539500D01*
X1244917Y538917D01*
X1245417Y538583D01*
X1246000Y538500D01*
X1246583Y538583D01*
X1247083Y538917D01*
X1247417Y539500D01*
G01Y538500D02*
Y541833D01*
G01X1253100Y538500D02*
Y541833D01*
G01Y541250D02*
X1252767Y541583D01*
X1252267Y541750D01*
X1251683Y541833D01*
X1251100Y541667D01*
X1250600Y541333D01*
X1250267Y540833D01*
X1250100Y540167D01*
X1250267Y539500D01*
X1250600Y539000D01*
X1251100Y538667D01*
X1251683Y538500D01*
X1252267Y538583D01*
X1252767Y538833D01*
X1253100Y539167D01*
G01X1257200Y538500D02*
Y543500D01*
G01X1267233Y538500D02*
Y541833D01*
G01Y541167D02*
X1267650Y541500D01*
X1268067Y541750D01*
X1268650Y541833D01*
X1269067Y541750D01*
X1269567Y541500D01*
G01X1274000Y541833D02*
Y538500D01*
G01Y543167D02*
X1273833Y543250D01*
Y543417D01*
X1274000Y543500D01*
X1274167Y543417D01*
Y543250D01*
X1274000Y543167D01*
G01X1278183Y538500D02*
Y541833D01*
G01Y541000D02*
X1278517Y541417D01*
X1279017Y541750D01*
X1279683Y541833D01*
X1280267Y541750D01*
X1280767Y541417D01*
X1281017Y540833D01*
Y538500D01*
G01X1284033Y537250D02*
X1284617Y536917D01*
X1285283Y536833D01*
X1285867Y536917D01*
X1286367Y537333D01*
X1286700Y537917D01*
Y541833D01*
G01Y541167D02*
X1286367Y541500D01*
X1285867Y541750D01*
X1285283Y541833D01*
X1284617Y541667D01*
X1284200Y541333D01*
X1283867Y540750D01*
X1283700Y540167D01*
X1283783Y539667D01*
X1284117Y539083D01*
X1284617Y538667D01*
X1285283Y538500D01*
X1285783Y538583D01*
X1286367Y538917D01*
X1286700Y539250D01*
G01X1295150Y539083D02*
X1295567Y538750D01*
X1296150Y538500D01*
X1296650D01*
X1297150Y538667D01*
X1297483Y538917D01*
X1297650Y539250D01*
X1297567Y539750D01*
X1297233Y540000D01*
X1295733Y540500D01*
X1295400Y541083D01*
X1295567Y541500D01*
X1295900Y541750D01*
X1296400Y541833D01*
X1296900Y541750D01*
X1297400Y541500D01*
G01X1300583Y538500D02*
Y543500D01*
G01Y541083D02*
X1301000Y541500D01*
X1301417Y541750D01*
X1302083Y541833D01*
X1302583Y541750D01*
X1303167Y541417D01*
X1303417Y540917D01*
Y538500D01*
G01X1307600D02*
X1307100Y538583D01*
X1306600Y538917D01*
X1306267Y539500D01*
X1306100Y540167D01*
X1306267Y540833D01*
X1306600Y541417D01*
X1307100Y541750D01*
X1307600Y541833D01*
X1308100Y541750D01*
X1308600Y541417D01*
X1308933Y540833D01*
X1309017Y540167D01*
X1308933Y539500D01*
X1308600Y538917D01*
X1308100Y538583D01*
X1307600Y538500D01*
G01X1311783Y541833D02*
Y539500D01*
X1312117Y538917D01*
X1312617Y538583D01*
X1313200Y538500D01*
X1313783Y538583D01*
X1314283Y538917D01*
X1314617Y539500D01*
G01Y538500D02*
Y541833D01*
G01X1318800Y538500D02*
Y543500D01*
G01X1325900D02*
Y538500D01*
G01Y539250D02*
X1325567Y538833D01*
X1325067Y538583D01*
X1324483Y538500D01*
X1323817Y538667D01*
X1323317Y539083D01*
X1322983Y539583D01*
X1322900Y540167D01*
X1322983Y540750D01*
X1323317Y541250D01*
X1323817Y541667D01*
X1324483Y541833D01*
X1325067Y541750D01*
X1325483Y541583D01*
X1325900Y541250D01*
G01X1022000Y569500D02*
Y574500D01*
X1021000Y573500D01*
G01Y569500D02*
X1023000D01*
G01X1027600Y569333D02*
X1027433Y569417D01*
Y569583D01*
X1027600Y569667D01*
X1027767Y569583D01*
Y569417D01*
X1027600Y569333D01*
G01X1033200Y574500D02*
Y569500D01*
G01X1031283Y574500D02*
X1035117D01*
G01X1037383Y569500D02*
Y574500D01*
G01Y572083D02*
X1037800Y572500D01*
X1038217Y572750D01*
X1038883Y572833D01*
X1039383Y572750D01*
X1039967Y572417D01*
X1040217Y571917D01*
Y569500D01*
G01X1043150Y571750D02*
X1045817D01*
X1045567Y572333D01*
X1045150Y572667D01*
X1044567Y572833D01*
X1043983Y572750D01*
X1043483Y572500D01*
X1043150Y571917D01*
X1042983Y571417D01*
Y570917D01*
X1043150Y570417D01*
X1043567Y569917D01*
X1044067Y569583D01*
X1044650Y569500D01*
X1045233Y569667D01*
X1045817Y570167D01*
G01X1054350Y570083D02*
X1054767Y569750D01*
X1055350Y569500D01*
X1055850D01*
X1056350Y569667D01*
X1056683Y569917D01*
X1056850Y570250D01*
X1056767Y570750D01*
X1056433Y571000D01*
X1054933Y571500D01*
X1054600Y572083D01*
X1054767Y572500D01*
X1055100Y572750D01*
X1055600Y572833D01*
X1056100Y572750D01*
X1056600Y572500D01*
G01X1061200Y572833D02*
Y569500D01*
G01Y574167D02*
X1061033Y574250D01*
Y574417D01*
X1061200Y574500D01*
X1061367Y574417D01*
Y574250D01*
X1061200Y574167D01*
G01X1068300Y574500D02*
Y569500D01*
G01Y570250D02*
X1067967Y569833D01*
X1067467Y569583D01*
X1066883Y569500D01*
X1066217Y569667D01*
X1065717Y570083D01*
X1065383Y570583D01*
X1065300Y571167D01*
X1065383Y571750D01*
X1065717Y572250D01*
X1066217Y572667D01*
X1066883Y572833D01*
X1067467Y572750D01*
X1067883Y572583D01*
X1068300Y572250D01*
G01X1071150Y571750D02*
X1073817D01*
X1073567Y572333D01*
X1073150Y572667D01*
X1072567Y572833D01*
X1071983Y572750D01*
X1071483Y572500D01*
X1071150Y571917D01*
X1070983Y571417D01*
Y570917D01*
X1071150Y570417D01*
X1071567Y569917D01*
X1072067Y569583D01*
X1072650Y569500D01*
X1073233Y569667D01*
X1073817Y570167D01*
G01X1081517Y572833D02*
X1082517Y569500D01*
X1083600Y572833D01*
X1084683Y569500D01*
X1085683Y572833D01*
G01X1089200D02*
Y569500D01*
G01Y574167D02*
X1089033Y574250D01*
Y574417D01*
X1089200Y574500D01*
X1089367Y574417D01*
Y574250D01*
X1089200Y574167D01*
G01X1094800Y574500D02*
Y569500D01*
G01X1093633Y572833D02*
X1095967D01*
G01X1098983Y569500D02*
Y574500D01*
G01Y572083D02*
X1099400Y572500D01*
X1099817Y572750D01*
X1100483Y572833D01*
X1100983Y572750D01*
X1101567Y572417D01*
X1101817Y571917D01*
Y569500D01*
G01X1106000D02*
X1105500Y569583D01*
X1105000Y569917D01*
X1104667Y570500D01*
X1104500Y571167D01*
X1104667Y571833D01*
X1105000Y572417D01*
X1105500Y572750D01*
X1106000Y572833D01*
X1106500Y572750D01*
X1107000Y572417D01*
X1107333Y571833D01*
X1107417Y571167D01*
X1107333Y570500D01*
X1107000Y569917D01*
X1106500Y569583D01*
X1106000Y569500D01*
G01X1110183Y572833D02*
Y570500D01*
X1110517Y569917D01*
X1111017Y569583D01*
X1111600Y569500D01*
X1112183Y569583D01*
X1112683Y569917D01*
X1113017Y570500D01*
G01Y569500D02*
Y572833D01*
G01X1117200Y574500D02*
Y569500D01*
G01X1116033Y572833D02*
X1118367D01*
G01X1127150Y570083D02*
X1127567Y569750D01*
X1128150Y569500D01*
X1128650D01*
X1129150Y569667D01*
X1129483Y569917D01*
X1129650Y570250D01*
X1129567Y570750D01*
X1129233Y571000D01*
X1127733Y571500D01*
X1127400Y572083D01*
X1127567Y572500D01*
X1127900Y572750D01*
X1128400Y572833D01*
X1128900Y572750D01*
X1129400Y572500D01*
G01X1134000Y569500D02*
X1133500Y569583D01*
X1133000Y569917D01*
X1132667Y570500D01*
X1132500Y571167D01*
X1132667Y571833D01*
X1133000Y572417D01*
X1133500Y572750D01*
X1134000Y572833D01*
X1134500Y572750D01*
X1135000Y572417D01*
X1135333Y571833D01*
X1135417Y571167D01*
X1135333Y570500D01*
X1135000Y569917D01*
X1134500Y569583D01*
X1134000Y569500D01*
G01X1139600D02*
Y574500D01*
G01X1146700D02*
Y569500D01*
G01Y570250D02*
X1146367Y569833D01*
X1145867Y569583D01*
X1145283Y569500D01*
X1144617Y569667D01*
X1144117Y570083D01*
X1143783Y570583D01*
X1143700Y571167D01*
X1143783Y571750D01*
X1144117Y572250D01*
X1144617Y572667D01*
X1145283Y572833D01*
X1145867Y572750D01*
X1146283Y572583D01*
X1146700Y572250D01*
G01X1149550Y571750D02*
X1152217D01*
X1151967Y572333D01*
X1151550Y572667D01*
X1150967Y572833D01*
X1150383Y572750D01*
X1149883Y572500D01*
X1149550Y571917D01*
X1149383Y571417D01*
Y570917D01*
X1149550Y570417D01*
X1149967Y569917D01*
X1150467Y569583D01*
X1151050Y569500D01*
X1151633Y569667D01*
X1152217Y570167D01*
G01X1155233Y569500D02*
Y572833D01*
G01Y572167D02*
X1155650Y572500D01*
X1156067Y572750D01*
X1156650Y572833D01*
X1157067Y572750D01*
X1157567Y572500D01*
G01X1165100Y569500D02*
Y572833D01*
G01Y571917D02*
X1165350Y572333D01*
X1165767Y572667D01*
X1166350Y572833D01*
X1166933Y572667D01*
X1167350Y572333D01*
X1167600Y571917D01*
Y569500D01*
G01Y571917D02*
X1167850Y572333D01*
X1168267Y572667D01*
X1168850Y572833D01*
X1169433Y572667D01*
X1169850Y572333D01*
X1170100Y571833D01*
Y569500D01*
G01X1174700D02*
Y572833D01*
G01Y572250D02*
X1174367Y572583D01*
X1173867Y572750D01*
X1173283Y572833D01*
X1172700Y572667D01*
X1172200Y572333D01*
X1171867Y571833D01*
X1171700Y571167D01*
X1171867Y570500D01*
X1172200Y570000D01*
X1172700Y569667D01*
X1173283Y569500D01*
X1173867Y569583D01*
X1174367Y569833D01*
X1174700Y570167D01*
G01X1177550Y570083D02*
X1177967Y569750D01*
X1178550Y569500D01*
X1179050D01*
X1179550Y569667D01*
X1179883Y569917D01*
X1180050Y570250D01*
X1179967Y570750D01*
X1179633Y571000D01*
X1178133Y571500D01*
X1177800Y572083D01*
X1177967Y572500D01*
X1178300Y572750D01*
X1178800Y572833D01*
X1179300Y572750D01*
X1179800Y572500D01*
G01X1182983Y569500D02*
Y574500D01*
G01X1185650Y572833D02*
X1182983Y570917D01*
G01X1184067Y571667D02*
X1185817Y569500D01*
G01X1194100Y567833D02*
Y572833D01*
G01Y572083D02*
X1194517Y572500D01*
X1194933Y572750D01*
X1195600Y572833D01*
X1196183Y572750D01*
X1196767Y572333D01*
X1197017Y571750D01*
X1197100Y571167D01*
X1197017Y570583D01*
X1196767Y570000D01*
X1196267Y569667D01*
X1195600Y569500D01*
X1195017Y569583D01*
X1194433Y569833D01*
X1194100Y570167D01*
G01X1202700Y569500D02*
Y572833D01*
G01Y572250D02*
X1202367Y572583D01*
X1201867Y572750D01*
X1201283Y572833D01*
X1200700Y572667D01*
X1200200Y572333D01*
X1199867Y571833D01*
X1199700Y571167D01*
X1199867Y570500D01*
X1200200Y570000D01*
X1200700Y569667D01*
X1201283Y569500D01*
X1201867Y569583D01*
X1202367Y569833D01*
X1202700Y570167D01*
G01X1208300Y574500D02*
Y569500D01*
G01Y570250D02*
X1207967Y569833D01*
X1207467Y569583D01*
X1206883Y569500D01*
X1206217Y569667D01*
X1205717Y570083D01*
X1205383Y570583D01*
X1205300Y571167D01*
X1205383Y571750D01*
X1205717Y572250D01*
X1206217Y572667D01*
X1206883Y572833D01*
X1207467Y572750D01*
X1207883Y572583D01*
X1208300Y572250D01*
G01X1217833Y568583D02*
X1218167Y569667D01*
G01X1230700Y569500D02*
Y572833D01*
G01Y572250D02*
X1230367Y572583D01*
X1229867Y572750D01*
X1229283Y572833D01*
X1228700Y572667D01*
X1228200Y572333D01*
X1227867Y571833D01*
X1227700Y571167D01*
X1227867Y570500D01*
X1228200Y570000D01*
X1228700Y569667D01*
X1229283Y569500D01*
X1229867Y569583D01*
X1230367Y569833D01*
X1230700Y570167D01*
G01X1233383Y569500D02*
Y572833D01*
G01Y572000D02*
X1233717Y572417D01*
X1234217Y572750D01*
X1234883Y572833D01*
X1235467Y572750D01*
X1235967Y572417D01*
X1236217Y571833D01*
Y569500D01*
G01X1238983D02*
Y572833D01*
G01Y572000D02*
X1239317Y572417D01*
X1239817Y572750D01*
X1240483Y572833D01*
X1241067Y572750D01*
X1241567Y572417D01*
X1241817Y571833D01*
Y569500D01*
G01X1244583Y572833D02*
Y570500D01*
X1244917Y569917D01*
X1245417Y569583D01*
X1246000Y569500D01*
X1246583Y569583D01*
X1247083Y569917D01*
X1247417Y570500D01*
G01Y569500D02*
Y572833D01*
G01X1253100Y569500D02*
Y572833D01*
G01Y572250D02*
X1252767Y572583D01*
X1252267Y572750D01*
X1251683Y572833D01*
X1251100Y572667D01*
X1250600Y572333D01*
X1250267Y571833D01*
X1250100Y571167D01*
X1250267Y570500D01*
X1250600Y570000D01*
X1251100Y569667D01*
X1251683Y569500D01*
X1252267Y569583D01*
X1252767Y569833D01*
X1253100Y570167D01*
G01X1257200Y569500D02*
Y574500D01*
G01X1267233Y569500D02*
Y572833D01*
G01Y572167D02*
X1267650Y572500D01*
X1268067Y572750D01*
X1268650Y572833D01*
X1269067Y572750D01*
X1269567Y572500D01*
G01X1274000Y572833D02*
Y569500D01*
G01Y574167D02*
X1273833Y574250D01*
Y574417D01*
X1274000Y574500D01*
X1274167Y574417D01*
Y574250D01*
X1274000Y574167D01*
G01X1278183Y569500D02*
Y572833D01*
G01Y572000D02*
X1278517Y572417D01*
X1279017Y572750D01*
X1279683Y572833D01*
X1280267Y572750D01*
X1280767Y572417D01*
X1281017Y571833D01*
Y569500D01*
G01X1284033Y568250D02*
X1284617Y567917D01*
X1285283Y567833D01*
X1285867Y567917D01*
X1286367Y568333D01*
X1286700Y568917D01*
Y572833D01*
G01Y572167D02*
X1286367Y572500D01*
X1285867Y572750D01*
X1285283Y572833D01*
X1284617Y572667D01*
X1284200Y572333D01*
X1283867Y571750D01*
X1283700Y571167D01*
X1283783Y570667D01*
X1284117Y570083D01*
X1284617Y569667D01*
X1285283Y569500D01*
X1285783Y569583D01*
X1286367Y569917D01*
X1286700Y570250D01*
G01X1294983Y569500D02*
Y572833D01*
G01Y572000D02*
X1295317Y572417D01*
X1295817Y572750D01*
X1296483Y572833D01*
X1297067Y572750D01*
X1297567Y572417D01*
X1297817Y571833D01*
Y569500D01*
G01X1300750Y571750D02*
X1303417D01*
X1303167Y572333D01*
X1302750Y572667D01*
X1302167Y572833D01*
X1301583Y572750D01*
X1301083Y572500D01*
X1300750Y571917D01*
X1300583Y571417D01*
Y570917D01*
X1300750Y570417D01*
X1301167Y569917D01*
X1301667Y569583D01*
X1302250Y569500D01*
X1302833Y569667D01*
X1303417Y570167D01*
G01X1306350Y571750D02*
X1309017D01*
X1308767Y572333D01*
X1308350Y572667D01*
X1307767Y572833D01*
X1307183Y572750D01*
X1306683Y572500D01*
X1306350Y571917D01*
X1306183Y571417D01*
Y570917D01*
X1306350Y570417D01*
X1306767Y569917D01*
X1307267Y569583D01*
X1307850Y569500D01*
X1308433Y569667D01*
X1309017Y570167D01*
G01X1314700Y574500D02*
Y569500D01*
G01Y570250D02*
X1314367Y569833D01*
X1313867Y569583D01*
X1313283Y569500D01*
X1312617Y569667D01*
X1312117Y570083D01*
X1311783Y570583D01*
X1311700Y571167D01*
X1311783Y571750D01*
X1312117Y572250D01*
X1312617Y572667D01*
X1313283Y572833D01*
X1313867Y572750D01*
X1314283Y572583D01*
X1314700Y572250D01*
G01X1012083Y730500D02*
Y733833D01*
G01Y733000D02*
X1012417Y733417D01*
X1012917Y733750D01*
X1013583Y733833D01*
X1014167Y733750D01*
X1014667Y733417D01*
X1014917Y732833D01*
Y730500D01*
G01X1019100D02*
X1018600Y730583D01*
X1018100Y730917D01*
X1017767Y731500D01*
X1017600Y732167D01*
X1017767Y732833D01*
X1018100Y733417D01*
X1018600Y733750D01*
X1019100Y733833D01*
X1019600Y733750D01*
X1020100Y733417D01*
X1020433Y732833D01*
X1020517Y732167D01*
X1020433Y731500D01*
X1020100Y730917D01*
X1019600Y730583D01*
X1019100Y730500D01*
G01X1028800Y728833D02*
Y733833D01*
G01Y733083D02*
X1029217Y733500D01*
X1029633Y733750D01*
X1030300Y733833D01*
X1030883Y733750D01*
X1031467Y733333D01*
X1031717Y732750D01*
X1031800Y732167D01*
X1031717Y731583D01*
X1031467Y731000D01*
X1030967Y730667D01*
X1030300Y730500D01*
X1029717Y730583D01*
X1029133Y730833D01*
X1028800Y731167D01*
G01X1035900Y730500D02*
Y735500D01*
G01X1040083Y733833D02*
Y731500D01*
X1040417Y730917D01*
X1040917Y730583D01*
X1041500Y730500D01*
X1042083Y730583D01*
X1042583Y730917D01*
X1042917Y731500D01*
G01Y730500D02*
Y733833D01*
G01X1045933Y729250D02*
X1046517Y728917D01*
X1047183Y728833D01*
X1047767Y728917D01*
X1048267Y729333D01*
X1048600Y729917D01*
Y733833D01*
G01Y733167D02*
X1048267Y733500D01*
X1047767Y733750D01*
X1047183Y733833D01*
X1046517Y733667D01*
X1046100Y733333D01*
X1045767Y732750D01*
X1045600Y732167D01*
X1045683Y731667D01*
X1046017Y731083D01*
X1046517Y730667D01*
X1047183Y730500D01*
X1047683Y730583D01*
X1048267Y730917D01*
X1048600Y731250D01*
G01X1051533Y729250D02*
X1052117Y728917D01*
X1052783Y728833D01*
X1053367Y728917D01*
X1053867Y729333D01*
X1054200Y729917D01*
Y733833D01*
G01Y733167D02*
X1053867Y733500D01*
X1053367Y733750D01*
X1052783Y733833D01*
X1052117Y733667D01*
X1051700Y733333D01*
X1051367Y732750D01*
X1051200Y732167D01*
X1051283Y731667D01*
X1051617Y731083D01*
X1052117Y730667D01*
X1052783Y730500D01*
X1053283Y730583D01*
X1053867Y730917D01*
X1054200Y731250D01*
G01X1058300Y733833D02*
Y730500D01*
G01Y735167D02*
X1058133Y735250D01*
Y735417D01*
X1058300Y735500D01*
X1058467Y735417D01*
Y735250D01*
X1058300Y735167D01*
G01X1062483Y730500D02*
Y733833D01*
G01Y733000D02*
X1062817Y733417D01*
X1063317Y733750D01*
X1063983Y733833D01*
X1064567Y733750D01*
X1065067Y733417D01*
X1065317Y732833D01*
Y730500D01*
G01X1068333Y729250D02*
X1068917Y728917D01*
X1069583Y728833D01*
X1070167Y728917D01*
X1070667Y729333D01*
X1071000Y729917D01*
Y733833D01*
G01Y733167D02*
X1070667Y733500D01*
X1070167Y733750D01*
X1069583Y733833D01*
X1068917Y733667D01*
X1068500Y733333D01*
X1068167Y732750D01*
X1068000Y732167D01*
X1068083Y731667D01*
X1068417Y731083D01*
X1068917Y730667D01*
X1069583Y730500D01*
X1070083Y730583D01*
X1070667Y730917D01*
X1071000Y731250D01*
G01X956000Y795980D02*
Y790980D01*
G01X954083Y795980D02*
X957917D01*
G01X959517Y794313D02*
X960517Y790980D01*
X961600Y794313D01*
X962683Y790980D01*
X963683Y794313D01*
G01X967200D02*
Y790980D01*
G01Y795647D02*
X967033Y795730D01*
Y795897D01*
X967200Y795980D01*
X967367Y795897D01*
Y795730D01*
X967200Y795647D01*
G01X971550Y791563D02*
X971967Y791230D01*
X972550Y790980D01*
X973050D01*
X973550Y791147D01*
X973883Y791397D01*
X974050Y791730D01*
X973967Y792230D01*
X973633Y792480D01*
X972133Y792980D01*
X971800Y793563D01*
X971967Y793980D01*
X972300Y794230D01*
X972800Y794313D01*
X973300Y794230D01*
X973800Y793980D01*
G01X978400Y795980D02*
Y790980D01*
G01X977233Y794313D02*
X979567D01*
G01X991100Y790980D02*
Y794313D01*
G01Y793730D02*
X990767Y794063D01*
X990267Y794230D01*
X989683Y794313D01*
X989100Y794147D01*
X988600Y793813D01*
X988267Y793313D01*
X988100Y792647D01*
X988267Y791980D01*
X988600Y791480D01*
X989100Y791147D01*
X989683Y790980D01*
X990267Y791063D01*
X990767Y791313D01*
X991100Y791647D01*
G01X993783Y790980D02*
Y794313D01*
G01Y793480D02*
X994117Y793897D01*
X994617Y794230D01*
X995283Y794313D01*
X995867Y794230D01*
X996367Y793897D01*
X996617Y793313D01*
Y790980D01*
G01X1002300Y795980D02*
Y790980D01*
G01Y791730D02*
X1001967Y791313D01*
X1001467Y791063D01*
X1000883Y790980D01*
X1000217Y791147D01*
X999717Y791563D01*
X999383Y792063D01*
X999300Y792647D01*
X999383Y793230D01*
X999717Y793730D01*
X1000217Y794147D01*
X1000883Y794313D01*
X1001467Y794230D01*
X1001883Y794063D01*
X1002300Y793730D01*
G01X1010500Y790980D02*
Y795980D01*
G01Y793480D02*
X1010917Y793980D01*
X1011417Y794230D01*
X1011917Y794313D01*
X1012667Y794147D01*
X1013167Y793813D01*
X1013500Y793230D01*
Y792563D01*
X1013333Y791897D01*
X1013000Y791397D01*
X1012417Y791063D01*
X1011917Y790980D01*
X1011417Y791063D01*
X1010917Y791313D01*
X1010500Y791730D01*
G01X1017600Y790980D02*
X1017100Y791063D01*
X1016600Y791397D01*
X1016267Y791980D01*
X1016100Y792647D01*
X1016267Y793313D01*
X1016600Y793897D01*
X1017100Y794230D01*
X1017600Y794313D01*
X1018100Y794230D01*
X1018600Y793897D01*
X1018933Y793313D01*
X1019017Y792647D01*
X1018933Y791980D01*
X1018600Y791397D01*
X1018100Y791063D01*
X1017600Y790980D01*
G01X1021117Y794313D02*
X1022117Y790980D01*
X1023200Y794313D01*
X1024283Y790980D01*
X1025283Y794313D01*
G01X957500Y811500D02*
X959167D01*
Y810000D01*
X958667Y809500D01*
X958083Y809167D01*
X957250Y809000D01*
X956417Y809167D01*
X955833Y809500D01*
X955333Y810000D01*
X955000Y810583D01*
X954833Y811250D01*
Y811833D01*
X955000Y812333D01*
X955333Y812917D01*
X955833Y813417D01*
X956333Y813750D01*
X957000Y814000D01*
X957583D01*
X958250Y813833D01*
X958750Y813500D01*
G01X961100Y808833D02*
X964100Y814000D01*
G01X966617Y809000D02*
Y814000D01*
X969783D01*
G01X968617Y811583D02*
X966617D01*
G01X977650Y809667D02*
X978317Y809250D01*
X979067Y809000D01*
X979733D01*
X980400Y809250D01*
X980900Y809667D01*
X981150Y810250D01*
X980983Y810833D01*
X980567Y811333D01*
X979817Y811667D01*
X978817Y811833D01*
X978233Y812167D01*
X977983Y812750D01*
X978150Y813333D01*
X978567Y813750D01*
X979150Y814000D01*
X979733D01*
X980317Y813833D01*
X980817Y813417D01*
G01X985000Y809000D02*
Y814000D01*
G01X990600Y809000D02*
X990100Y809083D01*
X989600Y809417D01*
X989267Y810000D01*
X989100Y810667D01*
X989267Y811333D01*
X989600Y811917D01*
X990100Y812250D01*
X990600Y812333D01*
X991100Y812250D01*
X991600Y811917D01*
X991933Y811333D01*
X992017Y810667D01*
X991933Y810000D01*
X991600Y809417D01*
X991100Y809083D01*
X990600Y809000D01*
G01X996200Y814000D02*
Y809000D01*
G01X995033Y812333D02*
X997367D01*
G01X955750Y826250D02*
X958417D01*
X958167Y826833D01*
X957750Y827167D01*
X957167Y827333D01*
X956583Y827250D01*
X956083Y827000D01*
X955750Y826417D01*
X955583Y825917D01*
Y825417D01*
X955750Y824917D01*
X956167Y824417D01*
X956667Y824083D01*
X957250Y824000D01*
X957833Y824167D01*
X958417Y824667D01*
G01X964100Y829000D02*
Y824000D01*
G01Y824750D02*
X963767Y824333D01*
X963267Y824083D01*
X962683Y824000D01*
X962017Y824167D01*
X961517Y824583D01*
X961183Y825083D01*
X961100Y825667D01*
X961183Y826250D01*
X961517Y826750D01*
X962017Y827167D01*
X962683Y827333D01*
X963267Y827250D01*
X963683Y827083D01*
X964100Y826750D01*
G01X967033Y822750D02*
X967617Y822417D01*
X968283Y822333D01*
X968867Y822417D01*
X969367Y822833D01*
X969700Y823417D01*
Y827333D01*
G01Y826667D02*
X969367Y827000D01*
X968867Y827250D01*
X968283Y827333D01*
X967617Y827167D01*
X967200Y826833D01*
X966867Y826250D01*
X966700Y825667D01*
X966783Y825167D01*
X967117Y824583D01*
X967617Y824167D01*
X968283Y824000D01*
X968783Y824083D01*
X969367Y824417D01*
X969700Y824750D01*
G01X972550Y826250D02*
X975217D01*
X974967Y826833D01*
X974550Y827167D01*
X973967Y827333D01*
X973383Y827250D01*
X972883Y827000D01*
X972550Y826417D01*
X972383Y825917D01*
Y825417D01*
X972550Y824917D01*
X972967Y824417D01*
X973467Y824083D01*
X974050Y824000D01*
X974633Y824167D01*
X975217Y824667D01*
G01X985000Y829000D02*
Y824000D01*
G01X983833Y827333D02*
X986167D01*
G01X990600Y824000D02*
X990100Y824083D01*
X989600Y824417D01*
X989267Y825000D01*
X989100Y825667D01*
X989267Y826333D01*
X989600Y826917D01*
X990100Y827250D01*
X990600Y827333D01*
X991100Y827250D01*
X991600Y826917D01*
X991933Y826333D01*
X992017Y825667D01*
X991933Y825000D01*
X991600Y824417D01*
X991100Y824083D01*
X990600Y824000D01*
G01X1000383D02*
Y829000D01*
G01Y826583D02*
X1000800Y827000D01*
X1001217Y827250D01*
X1001883Y827333D01*
X1002383Y827250D01*
X1002967Y826917D01*
X1003217Y826417D01*
Y824000D01*
G01X1007400D02*
X1006900Y824083D01*
X1006400Y824417D01*
X1006067Y825000D01*
X1005900Y825667D01*
X1006067Y826333D01*
X1006400Y826917D01*
X1006900Y827250D01*
X1007400Y827333D01*
X1007900Y827250D01*
X1008400Y826917D01*
X1008733Y826333D01*
X1008817Y825667D01*
X1008733Y825000D01*
X1008400Y824417D01*
X1007900Y824083D01*
X1007400Y824000D01*
G01X1013000D02*
Y829000D01*
G01X1017350Y826250D02*
X1020017D01*
X1019767Y826833D01*
X1019350Y827167D01*
X1018767Y827333D01*
X1018183Y827250D01*
X1017683Y827000D01*
X1017350Y826417D01*
X1017183Y825917D01*
Y825417D01*
X1017350Y824917D01*
X1017767Y824417D01*
X1018267Y824083D01*
X1018850Y824000D01*
X1019433Y824167D01*
X1020017Y824667D01*
G01X955750Y842750D02*
X958417D01*
X958167Y843333D01*
X957750Y843667D01*
X957167Y843833D01*
X956583Y843750D01*
X956083Y843500D01*
X955750Y842917D01*
X955583Y842417D01*
Y841917D01*
X955750Y841417D01*
X956167Y840917D01*
X956667Y840583D01*
X957250Y840500D01*
X957833Y840667D01*
X958417Y841167D01*
G01X964100Y845500D02*
Y840500D01*
G01Y841250D02*
X963767Y840833D01*
X963267Y840583D01*
X962683Y840500D01*
X962017Y840667D01*
X961517Y841083D01*
X961183Y841583D01*
X961100Y842167D01*
X961183Y842750D01*
X961517Y843250D01*
X962017Y843667D01*
X962683Y843833D01*
X963267Y843750D01*
X963683Y843583D01*
X964100Y843250D01*
G01X967033Y839250D02*
X967617Y838917D01*
X968283Y838833D01*
X968867Y838917D01*
X969367Y839333D01*
X969700Y839917D01*
Y843833D01*
G01Y843167D02*
X969367Y843500D01*
X968867Y843750D01*
X968283Y843833D01*
X967617Y843667D01*
X967200Y843333D01*
X966867Y842750D01*
X966700Y842167D01*
X966783Y841667D01*
X967117Y841083D01*
X967617Y840667D01*
X968283Y840500D01*
X968783Y840583D01*
X969367Y840917D01*
X969700Y841250D01*
G01X972550Y842750D02*
X975217D01*
X974967Y843333D01*
X974550Y843667D01*
X973967Y843833D01*
X973383Y843750D01*
X972883Y843500D01*
X972550Y842917D01*
X972383Y842417D01*
Y841917D01*
X972550Y841417D01*
X972967Y840917D01*
X973467Y840583D01*
X974050Y840500D01*
X974633Y840667D01*
X975217Y841167D01*
G01X985000Y845500D02*
Y840500D01*
G01X983833Y843833D02*
X986167D01*
G01X990600Y840500D02*
X990100Y840583D01*
X989600Y840917D01*
X989267Y841500D01*
X989100Y842167D01*
X989267Y842833D01*
X989600Y843417D01*
X990100Y843750D01*
X990600Y843833D01*
X991100Y843750D01*
X991600Y843417D01*
X991933Y842833D01*
X992017Y842167D01*
X991933Y841500D01*
X991600Y840917D01*
X991100Y840583D01*
X990600Y840500D01*
G01X1000550Y842750D02*
X1003217D01*
X1002967Y843333D01*
X1002550Y843667D01*
X1001967Y843833D01*
X1001383Y843750D01*
X1000883Y843500D01*
X1000550Y842917D01*
X1000383Y842417D01*
Y841917D01*
X1000550Y841417D01*
X1000967Y840917D01*
X1001467Y840583D01*
X1002050Y840500D01*
X1002633Y840667D01*
X1003217Y841167D01*
G01X1008900Y845500D02*
Y840500D01*
G01Y841250D02*
X1008567Y840833D01*
X1008067Y840583D01*
X1007483Y840500D01*
X1006817Y840667D01*
X1006317Y841083D01*
X1005983Y841583D01*
X1005900Y842167D01*
X1005983Y842750D01*
X1006317Y843250D01*
X1006817Y843667D01*
X1007483Y843833D01*
X1008067Y843750D01*
X1008483Y843583D01*
X1008900Y843250D01*
G01X1011833Y839250D02*
X1012417Y838917D01*
X1013083Y838833D01*
X1013667Y838917D01*
X1014167Y839333D01*
X1014500Y839917D01*
Y843833D01*
G01Y843167D02*
X1014167Y843500D01*
X1013667Y843750D01*
X1013083Y843833D01*
X1012417Y843667D01*
X1012000Y843333D01*
X1011667Y842750D01*
X1011500Y842167D01*
X1011583Y841667D01*
X1011917Y841083D01*
X1012417Y840667D01*
X1013083Y840500D01*
X1013583Y840583D01*
X1014167Y840917D01*
X1014500Y841250D01*
G01X1017350Y842750D02*
X1020017D01*
X1019767Y843333D01*
X1019350Y843667D01*
X1018767Y843833D01*
X1018183Y843750D01*
X1017683Y843500D01*
X1017350Y842917D01*
X1017183Y842417D01*
Y841917D01*
X1017350Y841417D01*
X1017767Y840917D01*
X1018267Y840583D01*
X1018850Y840500D01*
X1019433Y840667D01*
X1020017Y841167D01*
G01X948000Y850610D02*
Y782110D01*
G01X948500Y819500D02*
X1343000D01*
G01X948500Y834500D02*
X1343000D01*
G01X1089493Y104700D02*
Y99700D01*
X1092827D01*
G01X1095510Y103033D02*
X1098010Y99700D01*
G01Y103033D02*
X1095510Y99700D01*
G01X1102360Y99533D02*
X1102193Y99617D01*
Y99783D01*
X1102360Y99867D01*
X1102527Y99783D01*
Y99617D01*
X1102360Y99533D01*
G01Y101783D02*
X1102193Y101867D01*
Y102033D01*
X1102360Y102117D01*
X1102527Y102033D01*
Y101867D01*
X1102360Y101783D01*
G01X1111060Y99700D02*
Y103033D01*
G01Y102117D02*
X1111310Y102533D01*
X1111727Y102867D01*
X1112310Y103033D01*
X1112893Y102867D01*
X1113310Y102533D01*
X1113560Y102117D01*
Y99700D01*
G01Y102117D02*
X1113810Y102533D01*
X1114227Y102867D01*
X1114810Y103033D01*
X1115393Y102867D01*
X1115810Y102533D01*
X1116060Y102033D01*
Y99700D01*
G01X1117743Y103033D02*
Y100700D01*
X1118077Y100117D01*
X1118577Y99783D01*
X1119160Y99700D01*
X1119743Y99783D01*
X1120243Y100117D01*
X1120577Y100700D01*
G01Y99700D02*
Y103033D01*
G01X1123510Y100283D02*
X1123927Y99950D01*
X1124510Y99700D01*
X1125010D01*
X1125510Y99867D01*
X1125843Y100117D01*
X1126010Y100450D01*
X1125927Y100950D01*
X1125593Y101200D01*
X1124093Y101700D01*
X1123760Y102283D01*
X1123927Y102700D01*
X1124260Y102950D01*
X1124760Y103033D01*
X1125260Y102950D01*
X1125760Y102700D01*
G01X1130360Y104700D02*
Y99700D01*
G01X1129193Y103033D02*
X1131527D01*
G01X1140060Y99700D02*
Y104700D01*
G01Y102200D02*
X1140477Y102700D01*
X1140977Y102950D01*
X1141477Y103033D01*
X1142227Y102867D01*
X1142727Y102533D01*
X1143060Y101950D01*
Y101283D01*
X1142893Y100617D01*
X1142560Y100117D01*
X1141977Y99783D01*
X1141477Y99700D01*
X1140977Y99783D01*
X1140477Y100033D01*
X1140060Y100450D01*
G01X1145910Y101950D02*
X1148577D01*
X1148327Y102533D01*
X1147910Y102867D01*
X1147327Y103033D01*
X1146743Y102950D01*
X1146243Y102700D01*
X1145910Y102117D01*
X1145743Y101617D01*
Y101117D01*
X1145910Y100617D01*
X1146327Y100117D01*
X1146827Y99783D01*
X1147410Y99700D01*
X1147993Y99867D01*
X1148577Y100367D01*
G01X1156860Y99700D02*
Y104700D01*
G01Y102200D02*
X1157277Y102700D01*
X1157777Y102950D01*
X1158277Y103033D01*
X1159027Y102867D01*
X1159527Y102533D01*
X1159860Y101950D01*
Y101283D01*
X1159693Y100617D01*
X1159360Y100117D01*
X1158777Y99783D01*
X1158277Y99700D01*
X1157777Y99783D01*
X1157277Y100033D01*
X1156860Y100450D01*
G01X1162793Y99700D02*
Y103033D01*
G01Y102367D02*
X1163210Y102700D01*
X1163627Y102950D01*
X1164210Y103033D01*
X1164627Y102950D01*
X1165127Y102700D01*
G01X1169560Y99700D02*
X1169060Y99783D01*
X1168560Y100117D01*
X1168227Y100700D01*
X1168060Y101367D01*
X1168227Y102033D01*
X1168560Y102617D01*
X1169060Y102950D01*
X1169560Y103033D01*
X1170060Y102950D01*
X1170560Y102617D01*
X1170893Y102033D01*
X1170977Y101367D01*
X1170893Y100700D01*
X1170560Y100117D01*
X1170060Y99783D01*
X1169560Y99700D01*
G01X1173743D02*
Y104700D01*
G01X1176410Y103033D02*
X1173743Y101117D01*
G01X1174827Y101867D02*
X1176577Y99700D01*
G01X1179510Y101950D02*
X1182177D01*
X1181927Y102533D01*
X1181510Y102867D01*
X1180927Y103033D01*
X1180343Y102950D01*
X1179843Y102700D01*
X1179510Y102117D01*
X1179343Y101617D01*
Y101117D01*
X1179510Y100617D01*
X1179927Y100117D01*
X1180427Y99783D01*
X1181010Y99700D01*
X1181593Y99867D01*
X1182177Y100367D01*
G01X1184943Y99700D02*
Y103033D01*
G01Y102200D02*
X1185277Y102617D01*
X1185777Y102950D01*
X1186443Y103033D01*
X1187027Y102950D01*
X1187527Y102617D01*
X1187777Y102033D01*
Y99700D01*
G01X1197560D02*
Y104700D01*
G01X1204660Y99700D02*
Y103033D01*
G01Y102450D02*
X1204327Y102783D01*
X1203827Y102950D01*
X1203243Y103033D01*
X1202660Y102867D01*
X1202160Y102533D01*
X1201827Y102033D01*
X1201660Y101367D01*
X1201827Y100700D01*
X1202160Y100200D01*
X1202660Y99867D01*
X1203243Y99700D01*
X1203827Y99783D01*
X1204327Y100033D01*
X1204660Y100367D01*
G01X1207010Y98200D02*
X1207510Y98033D01*
X1208177Y98200D01*
X1208593Y98533D01*
X1208927Y98950D01*
X1209427Y100283D01*
X1210510Y103033D01*
G01X1207843D02*
X1209427Y100283D01*
G01X1213110Y101950D02*
X1215777D01*
X1215527Y102533D01*
X1215110Y102867D01*
X1214527Y103033D01*
X1213943Y102950D01*
X1213443Y102700D01*
X1213110Y102117D01*
X1212943Y101617D01*
Y101117D01*
X1213110Y100617D01*
X1213527Y100117D01*
X1214027Y99783D01*
X1214610Y99700D01*
X1215193Y99867D01*
X1215777Y100367D01*
G01X1218793Y99700D02*
Y103033D01*
G01Y102367D02*
X1219210Y102700D01*
X1219627Y102950D01*
X1220210Y103033D01*
X1220627Y102950D01*
X1221127Y102700D01*
G01X1088893Y117200D02*
Y112200D01*
X1092227D01*
G01X1094743D02*
Y115533D01*
G01Y114700D02*
X1095077Y115117D01*
X1095577Y115450D01*
X1096243Y115533D01*
X1096827Y115450D01*
X1097327Y115117D01*
X1097577Y114533D01*
Y112200D01*
G01X1101760Y112033D02*
X1101593Y112117D01*
Y112283D01*
X1101760Y112367D01*
X1101927Y112283D01*
Y112117D01*
X1101760Y112033D01*
G01Y114283D02*
X1101593Y114367D01*
Y114533D01*
X1101760Y114617D01*
X1101927Y114533D01*
Y114367D01*
X1101760Y114283D01*
G01X1114293Y115117D02*
X1113710Y115450D01*
X1113210Y115533D01*
X1112543Y115367D01*
X1112043Y115033D01*
X1111710Y114450D01*
X1111627Y113867D01*
X1111710Y113283D01*
X1112043Y112783D01*
X1112543Y112367D01*
X1113210Y112200D01*
X1113793Y112367D01*
X1114293Y112700D01*
G01X1120060Y112200D02*
Y115533D01*
G01Y114950D02*
X1119727Y115283D01*
X1119227Y115450D01*
X1118643Y115533D01*
X1118060Y115367D01*
X1117560Y115033D01*
X1117227Y114533D01*
X1117060Y113867D01*
X1117227Y113200D01*
X1117560Y112700D01*
X1118060Y112367D01*
X1118643Y112200D01*
X1119227Y112283D01*
X1119727Y112533D01*
X1120060Y112867D01*
G01X1122743Y112200D02*
Y115533D01*
G01Y114700D02*
X1123077Y115117D01*
X1123577Y115450D01*
X1124243Y115533D01*
X1124827Y115450D01*
X1125327Y115117D01*
X1125577Y114533D01*
Y112200D01*
G01X1129760Y115533D02*
X1130593Y116575D01*
Y117200D01*
X1129968D01*
Y116575D01*
X1130593D01*
G01X1135360Y117200D02*
Y112200D01*
G01X1134193Y115533D02*
X1136527D01*
G01X1145060Y112200D02*
Y117200D01*
G01Y114700D02*
X1145477Y115200D01*
X1145977Y115450D01*
X1146477Y115533D01*
X1147227Y115367D01*
X1147727Y115033D01*
X1148060Y114450D01*
Y113783D01*
X1147893Y113117D01*
X1147560Y112617D01*
X1146977Y112283D01*
X1146477Y112200D01*
X1145977Y112283D01*
X1145477Y112533D01*
X1145060Y112950D01*
G01X1150910Y114450D02*
X1153577D01*
X1153327Y115033D01*
X1152910Y115367D01*
X1152327Y115533D01*
X1151743Y115450D01*
X1151243Y115200D01*
X1150910Y114617D01*
X1150743Y114117D01*
Y113617D01*
X1150910Y113117D01*
X1151327Y112617D01*
X1151827Y112283D01*
X1152410Y112200D01*
X1152993Y112367D01*
X1153577Y112867D01*
G01X1161860Y112200D02*
Y117200D01*
G01Y114700D02*
X1162277Y115200D01*
X1162777Y115450D01*
X1163277Y115533D01*
X1164027Y115367D01*
X1164527Y115033D01*
X1164860Y114450D01*
Y113783D01*
X1164693Y113117D01*
X1164360Y112617D01*
X1163777Y112283D01*
X1163277Y112200D01*
X1162777Y112283D01*
X1162277Y112533D01*
X1161860Y112950D01*
G01X1167793Y112200D02*
Y115533D01*
G01Y114867D02*
X1168210Y115200D01*
X1168627Y115450D01*
X1169210Y115533D01*
X1169627Y115450D01*
X1170127Y115200D01*
G01X1174560Y112200D02*
X1174060Y112283D01*
X1173560Y112617D01*
X1173227Y113200D01*
X1173060Y113867D01*
X1173227Y114533D01*
X1173560Y115117D01*
X1174060Y115450D01*
X1174560Y115533D01*
X1175060Y115450D01*
X1175560Y115117D01*
X1175893Y114533D01*
X1175977Y113867D01*
X1175893Y113200D01*
X1175560Y112617D01*
X1175060Y112283D01*
X1174560Y112200D01*
G01X1178743D02*
Y117200D01*
G01X1181410Y115533D02*
X1178743Y113617D01*
G01X1179827Y114367D02*
X1181577Y112200D01*
G01X1184510Y114450D02*
X1187177D01*
X1186927Y115033D01*
X1186510Y115367D01*
X1185927Y115533D01*
X1185343Y115450D01*
X1184843Y115200D01*
X1184510Y114617D01*
X1184343Y114117D01*
Y113617D01*
X1184510Y113117D01*
X1184927Y112617D01*
X1185427Y112283D01*
X1186010Y112200D01*
X1186593Y112367D01*
X1187177Y112867D01*
G01X1189943Y112200D02*
Y115533D01*
G01Y114700D02*
X1190277Y115117D01*
X1190777Y115450D01*
X1191443Y115533D01*
X1192027Y115450D01*
X1192527Y115117D01*
X1192777Y114533D01*
Y112200D01*
G01X1202560D02*
Y117200D01*
G01X1209660Y112200D02*
Y115533D01*
G01Y114950D02*
X1209327Y115283D01*
X1208827Y115450D01*
X1208243Y115533D01*
X1207660Y115367D01*
X1207160Y115033D01*
X1206827Y114533D01*
X1206660Y113867D01*
X1206827Y113200D01*
X1207160Y112700D01*
X1207660Y112367D01*
X1208243Y112200D01*
X1208827Y112283D01*
X1209327Y112533D01*
X1209660Y112867D01*
G01X1212010Y110700D02*
X1212510Y110533D01*
X1213177Y110700D01*
X1213593Y111033D01*
X1213927Y111450D01*
X1214427Y112783D01*
X1215510Y115533D01*
G01X1212843D02*
X1214427Y112783D01*
G01X1218110Y114450D02*
X1220777D01*
X1220527Y115033D01*
X1220110Y115367D01*
X1219527Y115533D01*
X1218943Y115450D01*
X1218443Y115200D01*
X1218110Y114617D01*
X1217943Y114117D01*
Y113617D01*
X1218110Y113117D01*
X1218527Y112617D01*
X1219027Y112283D01*
X1219610Y112200D01*
X1220193Y112367D01*
X1220777Y112867D01*
G01X1223793Y112200D02*
Y115533D01*
G01Y114867D02*
X1224210Y115200D01*
X1224627Y115450D01*
X1225210Y115533D01*
X1225627Y115450D01*
X1226127Y115200D01*
G01X1087667Y124000D02*
Y129000D01*
X1089333D01*
X1090000Y128750D01*
X1090500Y128417D01*
X1090917Y127917D01*
X1091250Y127333D01*
X1091333Y126500D01*
X1091250Y125667D01*
X1090917Y125083D01*
X1090500Y124583D01*
X1090000Y124250D01*
X1089333Y124000D01*
X1087667D01*
G01X1093933D02*
Y127333D01*
G01Y126667D02*
X1094350Y127000D01*
X1094767Y127250D01*
X1095350Y127333D01*
X1095767Y127250D01*
X1096267Y127000D01*
G01X1100700Y127333D02*
Y124000D01*
G01Y128667D02*
X1100533Y128750D01*
Y128917D01*
X1100700Y129000D01*
X1100867Y128917D01*
Y128750D01*
X1100700Y128667D01*
G01X1106300Y124000D02*
Y129000D01*
G01X1111900Y124000D02*
Y129000D01*
G01X1121517Y124000D02*
Y129000D01*
X1124683D01*
G01X1123517Y126583D02*
X1121517D01*
G01X1127533Y124000D02*
Y127333D01*
G01Y126667D02*
X1127950Y127000D01*
X1128367Y127250D01*
X1128950Y127333D01*
X1129367Y127250D01*
X1129867Y127000D01*
G01X1134300Y124000D02*
X1133800Y124083D01*
X1133300Y124417D01*
X1132967Y125000D01*
X1132800Y125667D01*
X1132967Y126333D01*
X1133300Y126917D01*
X1133800Y127250D01*
X1134300Y127333D01*
X1134800Y127250D01*
X1135300Y126917D01*
X1135633Y126333D01*
X1135717Y125667D01*
X1135633Y125000D01*
X1135300Y124417D01*
X1134800Y124083D01*
X1134300Y124000D01*
G01X1137400D02*
Y127333D01*
G01Y126417D02*
X1137650Y126833D01*
X1138067Y127167D01*
X1138650Y127333D01*
X1139233Y127167D01*
X1139650Y126833D01*
X1139900Y126417D01*
Y124000D01*
G01Y126417D02*
X1140150Y126833D01*
X1140567Y127167D01*
X1141150Y127333D01*
X1141733Y127167D01*
X1142150Y126833D01*
X1142400Y126333D01*
Y124000D01*
G01X1167483Y122333D02*
X1166650Y123167D01*
X1166233Y124000D01*
Y127333D01*
X1166650Y128167D01*
X1167483Y129000D01*
G01X1174167Y126667D02*
X1174500Y126917D01*
X1174750Y127333D01*
X1174917Y127917D01*
X1174750Y128417D01*
X1174417Y128750D01*
X1173833Y129000D01*
X1171583D01*
Y124000D01*
X1174333D01*
X1174917Y124333D01*
X1175250Y124833D01*
X1175417Y125417D01*
X1175250Y126000D01*
X1174750Y126500D01*
X1174167Y126667D01*
X1171583D01*
G01X1179100Y124000D02*
X1178433Y124083D01*
X1177850Y124417D01*
X1177350Y124917D01*
X1177017Y125500D01*
X1176850Y126167D01*
Y126833D01*
X1177017Y127500D01*
X1177350Y128083D01*
X1177850Y128583D01*
X1178433Y128917D01*
X1179100Y129000D01*
X1179767Y128917D01*
X1180350Y128583D01*
X1180850Y128083D01*
X1181183Y127500D01*
X1181350Y126833D01*
Y126167D01*
X1181183Y125500D01*
X1180850Y124917D01*
X1180350Y124417D01*
X1179767Y124083D01*
X1179100Y124000D01*
G01X1184700Y129000D02*
Y124000D01*
G01X1182783Y129000D02*
X1186617D01*
G01X1190300D02*
Y124000D01*
G01X1188383Y129000D02*
X1192217D01*
G01X1195900Y124000D02*
X1195233Y124083D01*
X1194650Y124417D01*
X1194150Y124917D01*
X1193817Y125500D01*
X1193650Y126167D01*
Y126833D01*
X1193817Y127500D01*
X1194150Y128083D01*
X1194650Y128583D01*
X1195233Y128917D01*
X1195900Y129000D01*
X1196567Y128917D01*
X1197150Y128583D01*
X1197650Y128083D01*
X1197983Y127500D01*
X1198150Y126833D01*
Y126167D01*
X1197983Y125500D01*
X1197650Y124917D01*
X1197150Y124417D01*
X1196567Y124083D01*
X1195900Y124000D01*
G01X1199333D02*
Y129000D01*
X1201500Y124833D01*
X1203667Y129000D01*
Y124000D01*
G01X1207517Y122333D02*
X1208350Y123167D01*
X1208767Y124000D01*
Y127333D01*
X1208350Y128167D01*
X1207517Y129000D01*
G01X1218300D02*
Y124000D01*
G01X1217133Y127333D02*
X1219467D01*
G01X1223900Y124000D02*
X1223400Y124083D01*
X1222900Y124417D01*
X1222567Y125000D01*
X1222400Y125667D01*
X1222567Y126333D01*
X1222900Y126917D01*
X1223400Y127250D01*
X1223900Y127333D01*
X1224400Y127250D01*
X1224900Y126917D01*
X1225233Y126333D01*
X1225317Y125667D01*
X1225233Y125000D01*
X1224900Y124417D01*
X1224400Y124083D01*
X1223900Y124000D01*
G01X1233433Y129000D02*
Y124000D01*
X1236767D01*
G01X1239450Y127333D02*
X1241950Y124000D01*
G01Y127333D02*
X1239450Y124000D01*
G01X1033500Y370500D02*
Y375500D01*
G01Y373000D02*
X1033917Y373500D01*
X1034417Y373750D01*
X1034917Y373833D01*
X1035667Y373667D01*
X1036167Y373333D01*
X1036500Y372750D01*
Y372083D01*
X1036333Y371417D01*
X1036000Y370917D01*
X1035417Y370583D01*
X1034917Y370500D01*
X1034417Y370583D01*
X1033917Y370833D01*
X1033500Y371250D01*
G01X1039183Y373833D02*
Y371500D01*
X1039517Y370917D01*
X1040017Y370583D01*
X1040600Y370500D01*
X1041183Y370583D01*
X1041683Y370917D01*
X1042017Y371500D01*
G01Y370500D02*
Y373833D01*
G01X1044700Y370500D02*
Y375500D01*
G01Y373000D02*
X1045117Y373500D01*
X1045617Y373750D01*
X1046117Y373833D01*
X1046867Y373667D01*
X1047367Y373333D01*
X1047700Y372750D01*
Y372083D01*
X1047533Y371417D01*
X1047200Y370917D01*
X1046617Y370583D01*
X1046117Y370500D01*
X1045617Y370583D01*
X1045117Y370833D01*
X1044700Y371250D01*
G01X1050300Y370500D02*
Y375500D01*
G01Y373000D02*
X1050717Y373500D01*
X1051217Y373750D01*
X1051717Y373833D01*
X1052467Y373667D01*
X1052967Y373333D01*
X1053300Y372750D01*
Y372083D01*
X1053133Y371417D01*
X1052800Y370917D01*
X1052217Y370583D01*
X1051717Y370500D01*
X1051217Y370583D01*
X1050717Y370833D01*
X1050300Y371250D01*
G01X1057400Y370500D02*
Y375500D01*
G01X1061750Y372750D02*
X1064417D01*
X1064167Y373333D01*
X1063750Y373667D01*
X1063167Y373833D01*
X1062583Y373750D01*
X1062083Y373500D01*
X1061750Y372917D01*
X1061583Y372417D01*
Y371917D01*
X1061750Y371417D01*
X1062167Y370917D01*
X1062667Y370583D01*
X1063250Y370500D01*
X1063833Y370667D01*
X1064417Y371167D01*
G01X1074200Y373833D02*
Y370500D01*
G01Y375167D02*
X1074033Y375250D01*
Y375417D01*
X1074200Y375500D01*
X1074367Y375417D01*
Y375250D01*
X1074200Y375167D01*
G01X1078383Y370500D02*
Y373833D01*
G01Y373000D02*
X1078717Y373417D01*
X1079217Y373750D01*
X1079883Y373833D01*
X1080467Y373750D01*
X1080967Y373417D01*
X1081217Y372833D01*
Y370500D01*
G01X1084150Y371083D02*
X1084567Y370750D01*
X1085150Y370500D01*
X1085650D01*
X1086150Y370667D01*
X1086483Y370917D01*
X1086650Y371250D01*
X1086567Y371750D01*
X1086233Y372000D01*
X1084733Y372500D01*
X1084400Y373083D01*
X1084567Y373500D01*
X1084900Y373750D01*
X1085400Y373833D01*
X1085900Y373750D01*
X1086400Y373500D01*
G01X1091000Y373833D02*
Y370500D01*
G01Y375167D02*
X1090833Y375250D01*
Y375417D01*
X1091000Y375500D01*
X1091167Y375417D01*
Y375250D01*
X1091000Y375167D01*
G01X1098100Y375500D02*
Y370500D01*
G01Y371250D02*
X1097767Y370833D01*
X1097267Y370583D01*
X1096683Y370500D01*
X1096017Y370667D01*
X1095517Y371083D01*
X1095183Y371583D01*
X1095100Y372167D01*
X1095183Y372750D01*
X1095517Y373250D01*
X1096017Y373667D01*
X1096683Y373833D01*
X1097267Y373750D01*
X1097683Y373583D01*
X1098100Y373250D01*
G01X1100950Y372750D02*
X1103617D01*
X1103367Y373333D01*
X1102950Y373667D01*
X1102367Y373833D01*
X1101783Y373750D01*
X1101283Y373500D01*
X1100950Y372917D01*
X1100783Y372417D01*
Y371917D01*
X1100950Y371417D01*
X1101367Y370917D01*
X1101867Y370583D01*
X1102450Y370500D01*
X1103033Y370667D01*
X1103617Y371167D01*
G01X1113400Y375500D02*
Y370500D01*
G01X1112233Y373833D02*
X1114567D01*
G01X1117583Y370500D02*
Y375500D01*
G01Y373083D02*
X1118000Y373500D01*
X1118417Y373750D01*
X1119083Y373833D01*
X1119583Y373750D01*
X1120167Y373417D01*
X1120417Y372917D01*
Y370500D01*
G01X1123350Y372750D02*
X1126017D01*
X1125767Y373333D01*
X1125350Y373667D01*
X1124767Y373833D01*
X1124183Y373750D01*
X1123683Y373500D01*
X1123350Y372917D01*
X1123183Y372417D01*
Y371917D01*
X1123350Y371417D01*
X1123767Y370917D01*
X1124267Y370583D01*
X1124850Y370500D01*
X1125433Y370667D01*
X1126017Y371167D01*
G01X1134633Y370500D02*
Y373833D01*
G01Y373167D02*
X1135050Y373500D01*
X1135467Y373750D01*
X1136050Y373833D01*
X1136467Y373750D01*
X1136967Y373500D01*
G01X1140150Y372750D02*
X1142817D01*
X1142567Y373333D01*
X1142150Y373667D01*
X1141567Y373833D01*
X1140983Y373750D01*
X1140483Y373500D01*
X1140150Y372917D01*
X1139983Y372417D01*
Y371917D01*
X1140150Y371417D01*
X1140567Y370917D01*
X1141067Y370583D01*
X1141650Y370500D01*
X1142233Y370667D01*
X1142817Y371167D01*
G01X1145750Y371083D02*
X1146167Y370750D01*
X1146750Y370500D01*
X1147250D01*
X1147750Y370667D01*
X1148083Y370917D01*
X1148250Y371250D01*
X1148167Y371750D01*
X1147833Y372000D01*
X1146333Y372500D01*
X1146000Y373083D01*
X1146167Y373500D01*
X1146500Y373750D01*
X1147000Y373833D01*
X1147500Y373750D01*
X1148000Y373500D01*
G01X1152600Y373833D02*
Y370500D01*
G01Y375167D02*
X1152433Y375250D01*
Y375417D01*
X1152600Y375500D01*
X1152767Y375417D01*
Y375250D01*
X1152600Y375167D01*
G01X1156783Y370500D02*
Y373833D01*
G01Y373000D02*
X1157117Y373417D01*
X1157617Y373750D01*
X1158283Y373833D01*
X1158867Y373750D01*
X1159367Y373417D01*
X1159617Y372833D01*
Y370500D01*
G01X1163800Y370333D02*
X1163633Y370417D01*
Y370583D01*
X1163800Y370667D01*
X1163967Y370583D01*
Y370417D01*
X1163800Y370333D01*
G01X1033500Y413500D02*
Y418500D01*
G01Y416000D02*
X1033917Y416500D01*
X1034417Y416750D01*
X1034917Y416833D01*
X1035667Y416667D01*
X1036167Y416333D01*
X1036500Y415750D01*
Y415083D01*
X1036333Y414417D01*
X1036000Y413917D01*
X1035417Y413583D01*
X1034917Y413500D01*
X1034417Y413583D01*
X1033917Y413833D01*
X1033500Y414250D01*
G01X1039183Y416833D02*
Y414500D01*
X1039517Y413917D01*
X1040017Y413583D01*
X1040600Y413500D01*
X1041183Y413583D01*
X1041683Y413917D01*
X1042017Y414500D01*
G01Y413500D02*
Y416833D01*
G01X1044700Y413500D02*
Y418500D01*
G01Y416000D02*
X1045117Y416500D01*
X1045617Y416750D01*
X1046117Y416833D01*
X1046867Y416667D01*
X1047367Y416333D01*
X1047700Y415750D01*
Y415083D01*
X1047533Y414417D01*
X1047200Y413917D01*
X1046617Y413583D01*
X1046117Y413500D01*
X1045617Y413583D01*
X1045117Y413833D01*
X1044700Y414250D01*
G01X1050300Y413500D02*
Y418500D01*
G01Y416000D02*
X1050717Y416500D01*
X1051217Y416750D01*
X1051717Y416833D01*
X1052467Y416667D01*
X1052967Y416333D01*
X1053300Y415750D01*
Y415083D01*
X1053133Y414417D01*
X1052800Y413917D01*
X1052217Y413583D01*
X1051717Y413500D01*
X1051217Y413583D01*
X1050717Y413833D01*
X1050300Y414250D01*
G01X1057400Y413500D02*
Y418500D01*
G01X1061750Y415750D02*
X1064417D01*
X1064167Y416333D01*
X1063750Y416667D01*
X1063167Y416833D01*
X1062583Y416750D01*
X1062083Y416500D01*
X1061750Y415917D01*
X1061583Y415417D01*
Y414917D01*
X1061750Y414417D01*
X1062167Y413917D01*
X1062667Y413583D01*
X1063250Y413500D01*
X1063833Y413667D01*
X1064417Y414167D01*
G01X1074200Y416833D02*
Y413500D01*
G01Y418167D02*
X1074033Y418250D01*
Y418417D01*
X1074200Y418500D01*
X1074367Y418417D01*
Y418250D01*
X1074200Y418167D01*
G01X1078383Y413500D02*
Y416833D01*
G01Y416000D02*
X1078717Y416417D01*
X1079217Y416750D01*
X1079883Y416833D01*
X1080467Y416750D01*
X1080967Y416417D01*
X1081217Y415833D01*
Y413500D01*
G01X1084150Y414083D02*
X1084567Y413750D01*
X1085150Y413500D01*
X1085650D01*
X1086150Y413667D01*
X1086483Y413917D01*
X1086650Y414250D01*
X1086567Y414750D01*
X1086233Y415000D01*
X1084733Y415500D01*
X1084400Y416083D01*
X1084567Y416500D01*
X1084900Y416750D01*
X1085400Y416833D01*
X1085900Y416750D01*
X1086400Y416500D01*
G01X1091000Y416833D02*
Y413500D01*
G01Y418167D02*
X1090833Y418250D01*
Y418417D01*
X1091000Y418500D01*
X1091167Y418417D01*
Y418250D01*
X1091000Y418167D01*
G01X1098100Y418500D02*
Y413500D01*
G01Y414250D02*
X1097767Y413833D01*
X1097267Y413583D01*
X1096683Y413500D01*
X1096017Y413667D01*
X1095517Y414083D01*
X1095183Y414583D01*
X1095100Y415167D01*
X1095183Y415750D01*
X1095517Y416250D01*
X1096017Y416667D01*
X1096683Y416833D01*
X1097267Y416750D01*
X1097683Y416583D01*
X1098100Y416250D01*
G01X1100950Y415750D02*
X1103617D01*
X1103367Y416333D01*
X1102950Y416667D01*
X1102367Y416833D01*
X1101783Y416750D01*
X1101283Y416500D01*
X1100950Y415917D01*
X1100783Y415417D01*
Y414917D01*
X1100950Y414417D01*
X1101367Y413917D01*
X1101867Y413583D01*
X1102450Y413500D01*
X1103033Y413667D01*
X1103617Y414167D01*
G01X1113400Y418500D02*
Y413500D01*
G01X1112233Y416833D02*
X1114567D01*
G01X1117583Y413500D02*
Y418500D01*
G01Y416083D02*
X1118000Y416500D01*
X1118417Y416750D01*
X1119083Y416833D01*
X1119583Y416750D01*
X1120167Y416417D01*
X1120417Y415917D01*
Y413500D01*
G01X1123350Y415750D02*
X1126017D01*
X1125767Y416333D01*
X1125350Y416667D01*
X1124767Y416833D01*
X1124183Y416750D01*
X1123683Y416500D01*
X1123350Y415917D01*
X1123183Y415417D01*
Y414917D01*
X1123350Y414417D01*
X1123767Y413917D01*
X1124267Y413583D01*
X1124850Y413500D01*
X1125433Y413667D01*
X1126017Y414167D01*
G01X1134633Y413500D02*
Y416833D01*
G01Y416167D02*
X1135050Y416500D01*
X1135467Y416750D01*
X1136050Y416833D01*
X1136467Y416750D01*
X1136967Y416500D01*
G01X1140150Y415750D02*
X1142817D01*
X1142567Y416333D01*
X1142150Y416667D01*
X1141567Y416833D01*
X1140983Y416750D01*
X1140483Y416500D01*
X1140150Y415917D01*
X1139983Y415417D01*
Y414917D01*
X1140150Y414417D01*
X1140567Y413917D01*
X1141067Y413583D01*
X1141650Y413500D01*
X1142233Y413667D01*
X1142817Y414167D01*
G01X1145750Y414083D02*
X1146167Y413750D01*
X1146750Y413500D01*
X1147250D01*
X1147750Y413667D01*
X1148083Y413917D01*
X1148250Y414250D01*
X1148167Y414750D01*
X1147833Y415000D01*
X1146333Y415500D01*
X1146000Y416083D01*
X1146167Y416500D01*
X1146500Y416750D01*
X1147000Y416833D01*
X1147500Y416750D01*
X1148000Y416500D01*
G01X1152600Y416833D02*
Y413500D01*
G01Y418167D02*
X1152433Y418250D01*
Y418417D01*
X1152600Y418500D01*
X1152767Y418417D01*
Y418250D01*
X1152600Y418167D01*
G01X1156783Y413500D02*
Y416833D01*
G01Y416000D02*
X1157117Y416417D01*
X1157617Y416750D01*
X1158283Y416833D01*
X1158867Y416750D01*
X1159367Y416417D01*
X1159617Y415833D01*
Y413500D01*
G01X1163800Y413333D02*
X1163633Y413417D01*
Y413583D01*
X1163800Y413667D01*
X1163967Y413583D01*
Y413417D01*
X1163800Y413333D01*
G01X1046500Y485833D02*
X1048000Y482500D01*
X1049500Y485833D01*
G01X1053600D02*
Y482500D01*
G01Y487167D02*
X1053433Y487250D01*
Y487417D01*
X1053600Y487500D01*
X1053767Y487417D01*
Y487250D01*
X1053600Y487167D01*
G01X1060700Y482500D02*
Y485833D01*
G01Y485250D02*
X1060367Y485583D01*
X1059867Y485750D01*
X1059283Y485833D01*
X1058700Y485667D01*
X1058200Y485333D01*
X1057867Y484833D01*
X1057700Y484167D01*
X1057867Y483500D01*
X1058200Y483000D01*
X1058700Y482667D01*
X1059283Y482500D01*
X1059867Y482583D01*
X1060367Y482833D01*
X1060700Y483167D01*
G01X1069150Y483083D02*
X1069567Y482750D01*
X1070150Y482500D01*
X1070650D01*
X1071150Y482667D01*
X1071483Y482917D01*
X1071650Y483250D01*
X1071567Y483750D01*
X1071233Y484000D01*
X1069733Y484500D01*
X1069400Y485083D01*
X1069567Y485500D01*
X1069900Y485750D01*
X1070400Y485833D01*
X1070900Y485750D01*
X1071400Y485500D01*
G01X1074583Y482500D02*
Y487500D01*
G01Y485083D02*
X1075000Y485500D01*
X1075417Y485750D01*
X1076083Y485833D01*
X1076583Y485750D01*
X1077167Y485417D01*
X1077417Y484917D01*
Y482500D01*
G01X1083100D02*
Y485833D01*
G01Y485250D02*
X1082767Y485583D01*
X1082267Y485750D01*
X1081683Y485833D01*
X1081100Y485667D01*
X1080600Y485333D01*
X1080267Y484833D01*
X1080100Y484167D01*
X1080267Y483500D01*
X1080600Y483000D01*
X1081100Y482667D01*
X1081683Y482500D01*
X1082267Y482583D01*
X1082767Y482833D01*
X1083100Y483167D01*
G01X1087200Y482500D02*
Y487500D01*
G01X1092800Y482500D02*
Y487500D01*
G01X1102500Y482500D02*
Y487500D01*
G01Y485000D02*
X1102917Y485500D01*
X1103417Y485750D01*
X1103917Y485833D01*
X1104667Y485667D01*
X1105167Y485333D01*
X1105500Y484750D01*
Y484083D01*
X1105333Y483417D01*
X1105000Y482917D01*
X1104417Y482583D01*
X1103917Y482500D01*
X1103417Y482583D01*
X1102917Y482833D01*
X1102500Y483250D01*
G01X1108350Y484750D02*
X1111017D01*
X1110767Y485333D01*
X1110350Y485667D01*
X1109767Y485833D01*
X1109183Y485750D01*
X1108683Y485500D01*
X1108350Y484917D01*
X1108183Y484417D01*
Y483917D01*
X1108350Y483417D01*
X1108767Y482917D01*
X1109267Y482583D01*
X1109850Y482500D01*
X1110433Y482667D01*
X1111017Y483167D01*
G01X1118717Y485833D02*
X1119717Y482500D01*
X1120800Y485833D01*
X1121883Y482500D01*
X1122883Y485833D01*
G01X1126400D02*
Y482500D01*
G01Y487167D02*
X1126233Y487250D01*
Y487417D01*
X1126400Y487500D01*
X1126567Y487417D01*
Y487250D01*
X1126400Y487167D01*
G01X1132000Y487500D02*
Y482500D01*
G01X1130833Y485833D02*
X1133167D01*
G01X1136183Y482500D02*
Y487500D01*
G01Y485083D02*
X1136600Y485500D01*
X1137017Y485750D01*
X1137683Y485833D01*
X1138183Y485750D01*
X1138767Y485417D01*
X1139017Y484917D01*
Y482500D01*
G01X1150467D02*
X1147133Y484167D01*
X1150467Y485833D01*
G01X1160000Y482500D02*
X1160583Y482583D01*
X1161250Y482833D01*
X1161667Y483250D01*
X1161833Y483833D01*
X1161667Y484417D01*
X1161167Y484917D01*
X1160417Y485167D01*
X1159583D01*
X1159083Y485333D01*
X1158667Y485750D01*
X1158500Y486333D01*
X1158750Y486917D01*
X1159333Y487333D01*
X1160000Y487500D01*
X1160667Y487333D01*
X1161250Y486917D01*
X1161500Y486333D01*
X1161333Y485750D01*
X1160917Y485333D01*
X1160417Y485167D01*
X1159583D01*
X1158833Y484917D01*
X1158333Y484417D01*
X1158167Y483833D01*
X1158333Y483250D01*
X1158750Y482833D01*
X1159417Y482583D01*
X1160000Y482500D01*
G01X1165600Y487500D02*
X1164933Y487333D01*
X1164433Y486917D01*
X1164100Y486417D01*
X1163850Y485750D01*
X1163767Y485000D01*
X1163850Y484250D01*
X1164100Y483583D01*
X1164433Y483083D01*
X1164933Y482667D01*
X1165600Y482500D01*
X1166267Y482667D01*
X1166767Y483083D01*
X1167100Y483583D01*
X1167350Y484250D01*
X1167433Y485000D01*
X1167350Y485750D01*
X1167100Y486417D01*
X1166767Y486917D01*
X1166267Y487333D01*
X1165600Y487500D01*
G01X1175300Y482333D02*
X1178300Y487500D01*
G01X1175300D02*
X1174800Y487333D01*
X1174550Y487083D01*
X1174383Y486583D01*
X1174550Y486083D01*
X1174800Y485833D01*
X1175300Y485667D01*
X1175800Y485833D01*
X1176050Y486083D01*
X1176217Y486583D01*
X1176050Y487083D01*
X1175800Y487333D01*
X1175300Y487500D01*
G01X1178300Y484167D02*
X1177800Y484000D01*
X1177550Y483750D01*
X1177383Y483250D01*
X1177550Y482750D01*
X1177800Y482500D01*
X1178300Y482333D01*
X1178800Y482500D01*
X1179050Y482750D01*
X1179217Y483250D01*
X1179050Y483750D01*
X1178800Y484000D01*
X1178300Y484167D01*
G01X1186750Y483083D02*
X1187167Y482750D01*
X1187750Y482500D01*
X1188250D01*
X1188750Y482667D01*
X1189083Y482917D01*
X1189250Y483250D01*
X1189167Y483750D01*
X1188833Y484000D01*
X1187333Y484500D01*
X1187000Y485083D01*
X1187167Y485500D01*
X1187500Y485750D01*
X1188000Y485833D01*
X1188500Y485750D01*
X1189000Y485500D01*
G01X1193600Y482500D02*
X1193100Y482583D01*
X1192600Y482917D01*
X1192267Y483500D01*
X1192100Y484167D01*
X1192267Y484833D01*
X1192600Y485417D01*
X1193100Y485750D01*
X1193600Y485833D01*
X1194100Y485750D01*
X1194600Y485417D01*
X1194933Y484833D01*
X1195017Y484167D01*
X1194933Y483500D01*
X1194600Y482917D01*
X1194100Y482583D01*
X1193600Y482500D01*
G01X1199200D02*
Y487500D01*
G01X1206300D02*
Y482500D01*
G01Y483250D02*
X1205967Y482833D01*
X1205467Y482583D01*
X1204883Y482500D01*
X1204217Y482667D01*
X1203717Y483083D01*
X1203383Y483583D01*
X1203300Y484167D01*
X1203383Y484750D01*
X1203717Y485250D01*
X1204217Y485667D01*
X1204883Y485833D01*
X1205467Y485750D01*
X1205883Y485583D01*
X1206300Y485250D01*
G01X1209150Y484750D02*
X1211817D01*
X1211567Y485333D01*
X1211150Y485667D01*
X1210567Y485833D01*
X1209983Y485750D01*
X1209483Y485500D01*
X1209150Y484917D01*
X1208983Y484417D01*
Y483917D01*
X1209150Y483417D01*
X1209567Y482917D01*
X1210067Y482583D01*
X1210650Y482500D01*
X1211233Y482667D01*
X1211817Y483167D01*
G01X1214833Y482500D02*
Y485833D01*
G01Y485167D02*
X1215250Y485500D01*
X1215667Y485750D01*
X1216250Y485833D01*
X1216667Y485750D01*
X1217167Y485500D01*
G01X1224700Y482500D02*
Y485833D01*
G01Y484917D02*
X1224950Y485333D01*
X1225367Y485667D01*
X1225950Y485833D01*
X1226533Y485667D01*
X1226950Y485333D01*
X1227200Y484917D01*
Y482500D01*
G01Y484917D02*
X1227450Y485333D01*
X1227867Y485667D01*
X1228450Y485833D01*
X1229033Y485667D01*
X1229450Y485333D01*
X1229700Y484833D01*
Y482500D01*
G01X1234300D02*
Y485833D01*
G01Y485250D02*
X1233967Y485583D01*
X1233467Y485750D01*
X1232883Y485833D01*
X1232300Y485667D01*
X1231800Y485333D01*
X1231467Y484833D01*
X1231300Y484167D01*
X1231467Y483500D01*
X1231800Y483000D01*
X1232300Y482667D01*
X1232883Y482500D01*
X1233467Y482583D01*
X1233967Y482833D01*
X1234300Y483167D01*
G01X1237150Y483083D02*
X1237567Y482750D01*
X1238150Y482500D01*
X1238650D01*
X1239150Y482667D01*
X1239483Y482917D01*
X1239650Y483250D01*
X1239567Y483750D01*
X1239233Y484000D01*
X1237733Y484500D01*
X1237400Y485083D01*
X1237567Y485500D01*
X1237900Y485750D01*
X1238400Y485833D01*
X1238900Y485750D01*
X1239400Y485500D01*
G01X1242583Y482500D02*
Y487500D01*
G01X1245250Y485833D02*
X1242583Y483917D01*
G01X1243667Y484667D02*
X1245417Y482500D01*
G01X1035500Y491500D02*
Y496500D01*
G01Y494000D02*
X1035917Y494500D01*
X1036417Y494750D01*
X1036917Y494833D01*
X1037667Y494667D01*
X1038167Y494333D01*
X1038500Y493750D01*
Y493083D01*
X1038333Y492417D01*
X1038000Y491917D01*
X1037417Y491583D01*
X1036917Y491500D01*
X1036417Y491583D01*
X1035917Y491833D01*
X1035500Y492250D01*
G01X1042600Y491333D02*
X1042433Y491417D01*
Y491583D01*
X1042600Y491667D01*
X1042767Y491583D01*
Y491417D01*
X1042600Y491333D01*
G01X1048867Y494167D02*
X1049200Y494417D01*
X1049450Y494833D01*
X1049617Y495417D01*
X1049450Y495917D01*
X1049117Y496250D01*
X1048533Y496500D01*
X1046283D01*
Y491500D01*
X1049033D01*
X1049617Y491833D01*
X1049950Y492333D01*
X1050117Y492917D01*
X1049950Y493500D01*
X1049450Y494000D01*
X1048867Y494167D01*
X1046283D01*
G01X1053800Y491500D02*
X1053300Y491583D01*
X1052800Y491917D01*
X1052467Y492500D01*
X1052300Y493167D01*
X1052467Y493833D01*
X1052800Y494417D01*
X1053300Y494750D01*
X1053800Y494833D01*
X1054300Y494750D01*
X1054800Y494417D01*
X1055133Y493833D01*
X1055217Y493167D01*
X1055133Y492500D01*
X1054800Y491917D01*
X1054300Y491583D01*
X1053800Y491500D01*
G01X1060900D02*
Y494833D01*
G01Y494250D02*
X1060567Y494583D01*
X1060067Y494750D01*
X1059483Y494833D01*
X1058900Y494667D01*
X1058400Y494333D01*
X1058067Y493833D01*
X1057900Y493167D01*
X1058067Y492500D01*
X1058400Y492000D01*
X1058900Y491667D01*
X1059483Y491500D01*
X1060067Y491583D01*
X1060567Y491833D01*
X1060900Y492167D01*
G01X1063833Y491500D02*
Y494833D01*
G01Y494167D02*
X1064250Y494500D01*
X1064667Y494750D01*
X1065250Y494833D01*
X1065667Y494750D01*
X1066167Y494500D01*
G01X1072100Y496500D02*
Y491500D01*
G01Y492250D02*
X1071767Y491833D01*
X1071267Y491583D01*
X1070683Y491500D01*
X1070017Y491667D01*
X1069517Y492083D01*
X1069183Y492583D01*
X1069100Y493167D01*
X1069183Y493750D01*
X1069517Y494250D01*
X1070017Y494667D01*
X1070683Y494833D01*
X1071267Y494750D01*
X1071683Y494583D01*
X1072100Y494250D01*
G01X1081800Y496500D02*
Y491500D01*
G01X1080633Y494833D02*
X1082967D01*
G01X1085983Y491500D02*
Y496500D01*
G01Y494083D02*
X1086400Y494500D01*
X1086817Y494750D01*
X1087483Y494833D01*
X1087983Y494750D01*
X1088567Y494417D01*
X1088817Y493917D01*
Y491500D01*
G01X1093000Y494833D02*
Y491500D01*
G01Y496167D02*
X1092833Y496250D01*
Y496417D01*
X1093000Y496500D01*
X1093167Y496417D01*
Y496250D01*
X1093000Y496167D01*
G01X1099933Y494417D02*
X1099350Y494750D01*
X1098850Y494833D01*
X1098183Y494667D01*
X1097683Y494333D01*
X1097350Y493750D01*
X1097267Y493167D01*
X1097350Y492583D01*
X1097683Y492083D01*
X1098183Y491667D01*
X1098850Y491500D01*
X1099433Y491667D01*
X1099933Y492000D01*
G01X1102783Y491500D02*
Y496500D01*
G01X1105450Y494833D02*
X1102783Y492917D01*
G01X1103867Y493667D02*
X1105617Y491500D01*
G01X1108383D02*
Y494833D01*
G01Y494000D02*
X1108717Y494417D01*
X1109217Y494750D01*
X1109883Y494833D01*
X1110467Y494750D01*
X1110967Y494417D01*
X1111217Y493833D01*
Y491500D01*
G01X1114150Y493750D02*
X1116817D01*
X1116567Y494333D01*
X1116150Y494667D01*
X1115567Y494833D01*
X1114983Y494750D01*
X1114483Y494500D01*
X1114150Y493917D01*
X1113983Y493417D01*
Y492917D01*
X1114150Y492417D01*
X1114567Y491917D01*
X1115067Y491583D01*
X1115650Y491500D01*
X1116233Y491667D01*
X1116817Y492167D01*
G01X1119750Y492083D02*
X1120167Y491750D01*
X1120750Y491500D01*
X1121250D01*
X1121750Y491667D01*
X1122083Y491917D01*
X1122250Y492250D01*
X1122167Y492750D01*
X1121833Y493000D01*
X1120333Y493500D01*
X1120000Y494083D01*
X1120167Y494500D01*
X1120500Y494750D01*
X1121000Y494833D01*
X1121500Y494750D01*
X1122000Y494500D01*
G01X1125350Y492083D02*
X1125767Y491750D01*
X1126350Y491500D01*
X1126850D01*
X1127350Y491667D01*
X1127683Y491917D01*
X1127850Y492250D01*
X1127767Y492750D01*
X1127433Y493000D01*
X1125933Y493500D01*
X1125600Y494083D01*
X1125767Y494500D01*
X1126100Y494750D01*
X1126600Y494833D01*
X1127100Y494750D01*
X1127600Y494500D01*
G01X1139467Y491500D02*
X1136133Y493167D01*
X1139467Y494833D01*
G01X1149000Y496500D02*
X1148333Y496333D01*
X1147833Y495917D01*
X1147500Y495417D01*
X1147250Y494750D01*
X1147167Y494000D01*
X1147250Y493250D01*
X1147500Y492583D01*
X1147833Y492083D01*
X1148333Y491667D01*
X1149000Y491500D01*
X1149667Y491667D01*
X1150167Y492083D01*
X1150500Y492583D01*
X1150750Y493250D01*
X1150833Y494000D01*
X1150750Y494750D01*
X1150500Y495417D01*
X1150167Y495917D01*
X1149667Y496333D01*
X1149000Y496500D01*
G01X1154600Y491333D02*
X1154433Y491417D01*
Y491583D01*
X1154600Y491667D01*
X1154767Y491583D01*
Y491417D01*
X1154600Y491333D01*
G01X1158783Y492083D02*
X1159367Y491667D01*
X1160033Y491500D01*
X1160700Y491667D01*
X1161283Y492167D01*
X1161700Y492917D01*
X1161867Y493667D01*
Y494583D01*
X1161700Y495333D01*
X1161283Y496000D01*
X1160783Y496333D01*
X1160200Y496500D01*
X1159533Y496333D01*
X1159033Y496000D01*
X1158700Y495500D01*
X1158533Y494833D01*
X1158700Y494250D01*
X1159117Y493667D01*
X1159617Y493333D01*
X1160200Y493250D01*
X1160867Y493417D01*
X1161367Y493833D01*
X1161867Y494583D01*
G01X1163300Y491500D02*
Y494833D01*
G01Y493917D02*
X1163550Y494333D01*
X1163967Y494667D01*
X1164550Y494833D01*
X1165133Y494667D01*
X1165550Y494333D01*
X1165800Y493917D01*
Y491500D01*
G01Y493917D02*
X1166050Y494333D01*
X1166467Y494667D01*
X1167050Y494833D01*
X1167633Y494667D01*
X1168050Y494333D01*
X1168300Y493833D01*
Y491500D01*
G01X1168900D02*
Y494833D01*
G01Y493917D02*
X1169150Y494333D01*
X1169567Y494667D01*
X1170150Y494833D01*
X1170733Y494667D01*
X1171150Y494333D01*
X1171400Y493917D01*
Y491500D01*
G01Y493917D02*
X1171650Y494333D01*
X1172067Y494667D01*
X1172650Y494833D01*
X1173233Y494667D01*
X1173650Y494333D01*
X1173900Y493833D01*
Y491500D01*
G01X1177000Y491333D02*
X1176833Y491417D01*
Y491583D01*
X1177000Y491667D01*
X1177167Y491583D01*
Y491417D01*
X1177000Y491333D01*
G01Y493583D02*
X1176833Y493667D01*
Y493833D01*
X1177000Y493917D01*
X1177167Y493833D01*
Y493667D01*
X1177000Y493583D01*
G01X1045500Y504833D02*
X1047000Y501500D01*
X1048500Y504833D01*
G01X1052600D02*
Y501500D01*
G01Y506167D02*
X1052433Y506250D01*
Y506417D01*
X1052600Y506500D01*
X1052767Y506417D01*
Y506250D01*
X1052600Y506167D01*
G01X1059700Y501500D02*
Y504833D01*
G01Y504250D02*
X1059367Y504583D01*
X1058867Y504750D01*
X1058283Y504833D01*
X1057700Y504667D01*
X1057200Y504333D01*
X1056867Y503833D01*
X1056700Y503167D01*
X1056867Y502500D01*
X1057200Y502000D01*
X1057700Y501667D01*
X1058283Y501500D01*
X1058867Y501583D01*
X1059367Y501833D01*
X1059700Y502167D01*
G01X1068150Y502083D02*
X1068567Y501750D01*
X1069150Y501500D01*
X1069650D01*
X1070150Y501667D01*
X1070483Y501917D01*
X1070650Y502250D01*
X1070567Y502750D01*
X1070233Y503000D01*
X1068733Y503500D01*
X1068400Y504083D01*
X1068567Y504500D01*
X1068900Y504750D01*
X1069400Y504833D01*
X1069900Y504750D01*
X1070400Y504500D01*
G01X1073583Y501500D02*
Y506500D01*
G01Y504083D02*
X1074000Y504500D01*
X1074417Y504750D01*
X1075083Y504833D01*
X1075583Y504750D01*
X1076167Y504417D01*
X1076417Y503917D01*
Y501500D01*
G01X1082100D02*
Y504833D01*
G01Y504250D02*
X1081767Y504583D01*
X1081267Y504750D01*
X1080683Y504833D01*
X1080100Y504667D01*
X1079600Y504333D01*
X1079267Y503833D01*
X1079100Y503167D01*
X1079267Y502500D01*
X1079600Y502000D01*
X1080100Y501667D01*
X1080683Y501500D01*
X1081267Y501583D01*
X1081767Y501833D01*
X1082100Y502167D01*
G01X1086200Y501500D02*
Y506500D01*
G01X1091800Y501500D02*
Y506500D01*
G01X1101500Y501500D02*
Y506500D01*
G01Y504000D02*
X1101917Y504500D01*
X1102417Y504750D01*
X1102917Y504833D01*
X1103667Y504667D01*
X1104167Y504333D01*
X1104500Y503750D01*
Y503083D01*
X1104333Y502417D01*
X1104000Y501917D01*
X1103417Y501583D01*
X1102917Y501500D01*
X1102417Y501583D01*
X1101917Y501833D01*
X1101500Y502250D01*
G01X1107350Y503750D02*
X1110017D01*
X1109767Y504333D01*
X1109350Y504667D01*
X1108767Y504833D01*
X1108183Y504750D01*
X1107683Y504500D01*
X1107350Y503917D01*
X1107183Y503417D01*
Y502917D01*
X1107350Y502417D01*
X1107767Y501917D01*
X1108267Y501583D01*
X1108850Y501500D01*
X1109433Y501667D01*
X1110017Y502167D01*
G01X1118300Y499833D02*
Y504833D01*
G01Y504083D02*
X1118717Y504500D01*
X1119133Y504750D01*
X1119800Y504833D01*
X1120383Y504750D01*
X1120967Y504333D01*
X1121217Y503750D01*
X1121300Y503167D01*
X1121217Y502583D01*
X1120967Y502000D01*
X1120467Y501667D01*
X1119800Y501500D01*
X1119217Y501583D01*
X1118633Y501833D01*
X1118300Y502167D01*
G01X1125400Y501500D02*
Y506500D01*
G01X1129583Y504833D02*
Y502500D01*
X1129917Y501917D01*
X1130417Y501583D01*
X1131000Y501500D01*
X1131583Y501583D01*
X1132083Y501917D01*
X1132417Y502500D01*
G01Y501500D02*
Y504833D01*
G01X1135433Y500250D02*
X1136017Y499917D01*
X1136683Y499833D01*
X1137267Y499917D01*
X1137767Y500333D01*
X1138100Y500917D01*
Y504833D01*
G01Y504167D02*
X1137767Y504500D01*
X1137267Y504750D01*
X1136683Y504833D01*
X1136017Y504667D01*
X1135600Y504333D01*
X1135267Y503750D01*
X1135100Y503167D01*
X1135183Y502667D01*
X1135517Y502083D01*
X1136017Y501667D01*
X1136683Y501500D01*
X1137183Y501583D01*
X1137767Y501917D01*
X1138100Y502250D01*
G01X1141033Y500250D02*
X1141617Y499917D01*
X1142283Y499833D01*
X1142867Y499917D01*
X1143367Y500333D01*
X1143700Y500917D01*
Y504833D01*
G01Y504167D02*
X1143367Y504500D01*
X1142867Y504750D01*
X1142283Y504833D01*
X1141617Y504667D01*
X1141200Y504333D01*
X1140867Y503750D01*
X1140700Y503167D01*
X1140783Y502667D01*
X1141117Y502083D01*
X1141617Y501667D01*
X1142283Y501500D01*
X1142783Y501583D01*
X1143367Y501917D01*
X1143700Y502250D01*
G01X1146550Y503750D02*
X1149217D01*
X1148967Y504333D01*
X1148550Y504667D01*
X1147967Y504833D01*
X1147383Y504750D01*
X1146883Y504500D01*
X1146550Y503917D01*
X1146383Y503417D01*
Y502917D01*
X1146550Y502417D01*
X1146967Y501917D01*
X1147467Y501583D01*
X1148050Y501500D01*
X1148633Y501667D01*
X1149217Y502167D01*
G01X1154900Y506500D02*
Y501500D01*
G01Y502250D02*
X1154567Y501833D01*
X1154067Y501583D01*
X1153483Y501500D01*
X1152817Y501667D01*
X1152317Y502083D01*
X1151983Y502583D01*
X1151900Y503167D01*
X1151983Y503750D01*
X1152317Y504250D01*
X1152817Y504667D01*
X1153483Y504833D01*
X1154067Y504750D01*
X1154483Y504583D01*
X1154900Y504250D01*
G01X1162517Y504833D02*
X1163517Y501500D01*
X1164600Y504833D01*
X1165683Y501500D01*
X1166683Y504833D01*
G01X1170200D02*
Y501500D01*
G01Y506167D02*
X1170033Y506250D01*
Y506417D01*
X1170200Y506500D01*
X1170367Y506417D01*
Y506250D01*
X1170200Y506167D01*
G01X1175800Y506500D02*
Y501500D01*
G01X1174633Y504833D02*
X1176967D01*
G01X1179983Y501500D02*
Y506500D01*
G01Y504083D02*
X1180400Y504500D01*
X1180817Y504750D01*
X1181483Y504833D01*
X1181983Y504750D01*
X1182567Y504417D01*
X1182817Y503917D01*
Y501500D01*
G01X1194267D02*
X1190933Y503167D01*
X1194267Y504833D01*
G01X1201967Y502250D02*
X1202467Y501833D01*
X1203050Y501583D01*
X1203800Y501500D01*
X1204550Y501667D01*
X1205133Y502000D01*
X1205550Y502583D01*
X1205633Y503250D01*
X1205467Y503917D01*
X1205050Y504333D01*
X1204467Y504667D01*
X1203883Y504750D01*
X1203300Y504667D01*
X1202550Y504333D01*
X1202800Y506500D01*
X1205050D01*
G01X1209400D02*
X1208733Y506333D01*
X1208233Y505917D01*
X1207900Y505417D01*
X1207650Y504750D01*
X1207567Y504000D01*
X1207650Y503250D01*
X1207900Y502583D01*
X1208233Y502083D01*
X1208733Y501667D01*
X1209400Y501500D01*
X1210067Y501667D01*
X1210567Y502083D01*
X1210900Y502583D01*
X1211150Y503250D01*
X1211233Y504000D01*
X1211150Y504750D01*
X1210900Y505417D01*
X1210567Y505917D01*
X1210067Y506333D01*
X1209400Y506500D01*
G01X1219100Y501333D02*
X1222100Y506500D01*
G01X1219100D02*
X1218600Y506333D01*
X1218350Y506083D01*
X1218183Y505583D01*
X1218350Y505083D01*
X1218600Y504833D01*
X1219100Y504667D01*
X1219600Y504833D01*
X1219850Y505083D01*
X1220017Y505583D01*
X1219850Y506083D01*
X1219600Y506333D01*
X1219100Y506500D01*
G01X1222100Y503167D02*
X1221600Y503000D01*
X1221350Y502750D01*
X1221183Y502250D01*
X1221350Y501750D01*
X1221600Y501500D01*
X1222100Y501333D01*
X1222600Y501500D01*
X1222850Y501750D01*
X1223017Y502250D01*
X1222850Y502750D01*
X1222600Y503000D01*
X1222100Y503167D01*
G01X1230550Y502083D02*
X1230967Y501750D01*
X1231550Y501500D01*
X1232050D01*
X1232550Y501667D01*
X1232883Y501917D01*
X1233050Y502250D01*
X1232967Y502750D01*
X1232633Y503000D01*
X1231133Y503500D01*
X1230800Y504083D01*
X1230967Y504500D01*
X1231300Y504750D01*
X1231800Y504833D01*
X1232300Y504750D01*
X1232800Y504500D01*
G01X1237400Y501500D02*
X1236900Y501583D01*
X1236400Y501917D01*
X1236067Y502500D01*
X1235900Y503167D01*
X1236067Y503833D01*
X1236400Y504417D01*
X1236900Y504750D01*
X1237400Y504833D01*
X1237900Y504750D01*
X1238400Y504417D01*
X1238733Y503833D01*
X1238817Y503167D01*
X1238733Y502500D01*
X1238400Y501917D01*
X1237900Y501583D01*
X1237400Y501500D01*
G01X1243000D02*
Y506500D01*
G01X1250100D02*
Y501500D01*
G01Y502250D02*
X1249767Y501833D01*
X1249267Y501583D01*
X1248683Y501500D01*
X1248017Y501667D01*
X1247517Y502083D01*
X1247183Y502583D01*
X1247100Y503167D01*
X1247183Y503750D01*
X1247517Y504250D01*
X1248017Y504667D01*
X1248683Y504833D01*
X1249267Y504750D01*
X1249683Y504583D01*
X1250100Y504250D01*
G01X1252950Y503750D02*
X1255617D01*
X1255367Y504333D01*
X1254950Y504667D01*
X1254367Y504833D01*
X1253783Y504750D01*
X1253283Y504500D01*
X1252950Y503917D01*
X1252783Y503417D01*
Y502917D01*
X1252950Y502417D01*
X1253367Y501917D01*
X1253867Y501583D01*
X1254450Y501500D01*
X1255033Y501667D01*
X1255617Y502167D01*
G01X1258633Y501500D02*
Y504833D01*
G01Y504167D02*
X1259050Y504500D01*
X1259467Y504750D01*
X1260050Y504833D01*
X1260467Y504750D01*
X1260967Y504500D01*
G01X1268500Y501500D02*
Y504833D01*
G01Y503917D02*
X1268750Y504333D01*
X1269167Y504667D01*
X1269750Y504833D01*
X1270333Y504667D01*
X1270750Y504333D01*
X1271000Y503917D01*
Y501500D01*
G01Y503917D02*
X1271250Y504333D01*
X1271667Y504667D01*
X1272250Y504833D01*
X1272833Y504667D01*
X1273250Y504333D01*
X1273500Y503833D01*
Y501500D01*
G01X1278100D02*
Y504833D01*
G01Y504250D02*
X1277767Y504583D01*
X1277267Y504750D01*
X1276683Y504833D01*
X1276100Y504667D01*
X1275600Y504333D01*
X1275267Y503833D01*
X1275100Y503167D01*
X1275267Y502500D01*
X1275600Y502000D01*
X1276100Y501667D01*
X1276683Y501500D01*
X1277267Y501583D01*
X1277767Y501833D01*
X1278100Y502167D01*
G01X1280950Y502083D02*
X1281367Y501750D01*
X1281950Y501500D01*
X1282450D01*
X1282950Y501667D01*
X1283283Y501917D01*
X1283450Y502250D01*
X1283367Y502750D01*
X1283033Y503000D01*
X1281533Y503500D01*
X1281200Y504083D01*
X1281367Y504500D01*
X1281700Y504750D01*
X1282200Y504833D01*
X1282700Y504750D01*
X1283200Y504500D01*
G01X1286383Y501500D02*
Y506500D01*
G01X1289050Y504833D02*
X1286383Y502917D01*
G01X1287467Y503667D02*
X1289217Y501500D01*
G01X1293233Y500583D02*
X1293567Y501667D01*
G01X1038500Y510500D02*
Y513833D01*
G01Y513250D02*
X1038167Y513583D01*
X1037667Y513750D01*
X1037083Y513833D01*
X1036500Y513667D01*
X1036000Y513333D01*
X1035667Y512833D01*
X1035500Y512167D01*
X1035667Y511500D01*
X1036000Y511000D01*
X1036500Y510667D01*
X1037083Y510500D01*
X1037667Y510583D01*
X1038167Y510833D01*
X1038500Y511167D01*
G01X1042600Y510333D02*
X1042433Y510417D01*
Y510583D01*
X1042600Y510667D01*
X1042767Y510583D01*
Y510417D01*
X1042600Y510333D01*
G01X1048867Y513167D02*
X1049200Y513417D01*
X1049450Y513833D01*
X1049617Y514417D01*
X1049450Y514917D01*
X1049117Y515250D01*
X1048533Y515500D01*
X1046283D01*
Y510500D01*
X1049033D01*
X1049617Y510833D01*
X1049950Y511333D01*
X1050117Y511917D01*
X1049950Y512500D01*
X1049450Y513000D01*
X1048867Y513167D01*
X1046283D01*
G01X1053800Y510500D02*
X1053300Y510583D01*
X1052800Y510917D01*
X1052467Y511500D01*
X1052300Y512167D01*
X1052467Y512833D01*
X1052800Y513417D01*
X1053300Y513750D01*
X1053800Y513833D01*
X1054300Y513750D01*
X1054800Y513417D01*
X1055133Y512833D01*
X1055217Y512167D01*
X1055133Y511500D01*
X1054800Y510917D01*
X1054300Y510583D01*
X1053800Y510500D01*
G01X1060900D02*
Y513833D01*
G01Y513250D02*
X1060567Y513583D01*
X1060067Y513750D01*
X1059483Y513833D01*
X1058900Y513667D01*
X1058400Y513333D01*
X1058067Y512833D01*
X1057900Y512167D01*
X1058067Y511500D01*
X1058400Y511000D01*
X1058900Y510667D01*
X1059483Y510500D01*
X1060067Y510583D01*
X1060567Y510833D01*
X1060900Y511167D01*
G01X1063833Y510500D02*
Y513833D01*
G01Y513167D02*
X1064250Y513500D01*
X1064667Y513750D01*
X1065250Y513833D01*
X1065667Y513750D01*
X1066167Y513500D01*
G01X1072100Y515500D02*
Y510500D01*
G01Y511250D02*
X1071767Y510833D01*
X1071267Y510583D01*
X1070683Y510500D01*
X1070017Y510667D01*
X1069517Y511083D01*
X1069183Y511583D01*
X1069100Y512167D01*
X1069183Y512750D01*
X1069517Y513250D01*
X1070017Y513667D01*
X1070683Y513833D01*
X1071267Y513750D01*
X1071683Y513583D01*
X1072100Y513250D01*
G01X1081800Y515500D02*
Y510500D01*
G01X1080633Y513833D02*
X1082967D01*
G01X1085983Y510500D02*
Y515500D01*
G01Y513083D02*
X1086400Y513500D01*
X1086817Y513750D01*
X1087483Y513833D01*
X1087983Y513750D01*
X1088567Y513417D01*
X1088817Y512917D01*
Y510500D01*
G01X1093000Y513833D02*
Y510500D01*
G01Y515167D02*
X1092833Y515250D01*
Y515417D01*
X1093000Y515500D01*
X1093167Y515417D01*
Y515250D01*
X1093000Y515167D01*
G01X1099933Y513417D02*
X1099350Y513750D01*
X1098850Y513833D01*
X1098183Y513667D01*
X1097683Y513333D01*
X1097350Y512750D01*
X1097267Y512167D01*
X1097350Y511583D01*
X1097683Y511083D01*
X1098183Y510667D01*
X1098850Y510500D01*
X1099433Y510667D01*
X1099933Y511000D01*
G01X1102783Y510500D02*
Y515500D01*
G01X1105450Y513833D02*
X1102783Y511917D01*
G01X1103867Y512667D02*
X1105617Y510500D01*
G01X1108383D02*
Y513833D01*
G01Y513000D02*
X1108717Y513417D01*
X1109217Y513750D01*
X1109883Y513833D01*
X1110467Y513750D01*
X1110967Y513417D01*
X1111217Y512833D01*
Y510500D01*
G01X1114150Y512750D02*
X1116817D01*
X1116567Y513333D01*
X1116150Y513667D01*
X1115567Y513833D01*
X1114983Y513750D01*
X1114483Y513500D01*
X1114150Y512917D01*
X1113983Y512417D01*
Y511917D01*
X1114150Y511417D01*
X1114567Y510917D01*
X1115067Y510583D01*
X1115650Y510500D01*
X1116233Y510667D01*
X1116817Y511167D01*
G01X1119750Y511083D02*
X1120167Y510750D01*
X1120750Y510500D01*
X1121250D01*
X1121750Y510667D01*
X1122083Y510917D01*
X1122250Y511250D01*
X1122167Y511750D01*
X1121833Y512000D01*
X1120333Y512500D01*
X1120000Y513083D01*
X1120167Y513500D01*
X1120500Y513750D01*
X1121000Y513833D01*
X1121500Y513750D01*
X1122000Y513500D01*
G01X1125350Y511083D02*
X1125767Y510750D01*
X1126350Y510500D01*
X1126850D01*
X1127350Y510667D01*
X1127683Y510917D01*
X1127850Y511250D01*
X1127767Y511750D01*
X1127433Y512000D01*
X1125933Y512500D01*
X1125600Y513083D01*
X1125767Y513500D01*
X1126100Y513750D01*
X1126600Y513833D01*
X1127100Y513750D01*
X1127600Y513500D01*
G01X1130533Y510500D02*
X1133867Y512167D01*
X1130533Y513833D01*
G01X1136717Y511417D02*
X1138883D01*
G01Y512917D02*
X1136717D01*
G01X1149000Y515500D02*
X1148333Y515333D01*
X1147833Y514917D01*
X1147500Y514417D01*
X1147250Y513750D01*
X1147167Y513000D01*
X1147250Y512250D01*
X1147500Y511583D01*
X1147833Y511083D01*
X1148333Y510667D01*
X1149000Y510500D01*
X1149667Y510667D01*
X1150167Y511083D01*
X1150500Y511583D01*
X1150750Y512250D01*
X1150833Y513000D01*
X1150750Y513750D01*
X1150500Y514417D01*
X1150167Y514917D01*
X1149667Y515333D01*
X1149000Y515500D01*
G01X1154600Y510333D02*
X1154433Y510417D01*
Y510583D01*
X1154600Y510667D01*
X1154767Y510583D01*
Y510417D01*
X1154600Y510333D01*
G01X1158783Y511083D02*
X1159367Y510667D01*
X1160033Y510500D01*
X1160700Y510667D01*
X1161283Y511167D01*
X1161700Y511917D01*
X1161867Y512667D01*
Y513583D01*
X1161700Y514333D01*
X1161283Y515000D01*
X1160783Y515333D01*
X1160200Y515500D01*
X1159533Y515333D01*
X1159033Y515000D01*
X1158700Y514500D01*
X1158533Y513833D01*
X1158700Y513250D01*
X1159117Y512667D01*
X1159617Y512333D01*
X1160200Y512250D01*
X1160867Y512417D01*
X1161367Y512833D01*
X1161867Y513583D01*
G01X1163300Y510500D02*
Y513833D01*
G01Y512917D02*
X1163550Y513333D01*
X1163967Y513667D01*
X1164550Y513833D01*
X1165133Y513667D01*
X1165550Y513333D01*
X1165800Y512917D01*
Y510500D01*
G01Y512917D02*
X1166050Y513333D01*
X1166467Y513667D01*
X1167050Y513833D01*
X1167633Y513667D01*
X1168050Y513333D01*
X1168300Y512833D01*
Y510500D01*
G01X1171400Y510333D02*
X1171233Y510417D01*
Y510583D01*
X1171400Y510667D01*
X1171567Y510583D01*
Y510417D01*
X1171400Y510333D01*
G01Y512583D02*
X1171233Y512667D01*
Y512833D01*
X1171400Y512917D01*
X1171567Y512833D01*
Y512667D01*
X1171400Y512583D01*
G01X1034250Y520500D02*
Y525500D01*
G01X1037750D02*
Y520500D01*
G01Y523000D02*
X1034250D01*
G01X1043100Y520500D02*
Y523833D01*
G01Y523250D02*
X1042767Y523583D01*
X1042267Y523750D01*
X1041683Y523833D01*
X1041100Y523667D01*
X1040600Y523333D01*
X1040267Y522833D01*
X1040100Y522167D01*
X1040267Y521500D01*
X1040600Y521000D01*
X1041100Y520667D01*
X1041683Y520500D01*
X1042267Y520583D01*
X1042767Y520833D01*
X1043100Y521167D01*
G01X1047200Y520500D02*
Y525500D01*
G01X1052300Y520500D02*
Y524750D01*
X1052467Y525167D01*
X1052800Y525417D01*
X1053300Y525500D01*
X1053800Y525333D01*
X1054050Y524917D01*
G01X1053050Y523500D02*
X1051383D01*
G01X1057317Y522167D02*
X1059483D01*
G01X1062500Y518833D02*
Y523833D01*
G01Y523083D02*
X1062917Y523500D01*
X1063333Y523750D01*
X1064000Y523833D01*
X1064583Y523750D01*
X1065167Y523333D01*
X1065417Y522750D01*
X1065500Y522167D01*
X1065417Y521583D01*
X1065167Y521000D01*
X1064667Y520667D01*
X1064000Y520500D01*
X1063417Y520583D01*
X1062833Y520833D01*
X1062500Y521167D01*
G01X1069600Y520500D02*
Y525500D01*
G01X1073783Y523833D02*
Y521500D01*
X1074117Y520917D01*
X1074617Y520583D01*
X1075200Y520500D01*
X1075783Y520583D01*
X1076283Y520917D01*
X1076617Y521500D01*
G01Y520500D02*
Y523833D01*
G01X1079633Y519250D02*
X1080217Y518917D01*
X1080883Y518833D01*
X1081467Y518917D01*
X1081967Y519333D01*
X1082300Y519917D01*
Y523833D01*
G01Y523167D02*
X1081967Y523500D01*
X1081467Y523750D01*
X1080883Y523833D01*
X1080217Y523667D01*
X1079800Y523333D01*
X1079467Y522750D01*
X1079300Y522167D01*
X1079383Y521667D01*
X1079717Y521083D01*
X1080217Y520667D01*
X1080883Y520500D01*
X1081383Y520583D01*
X1081967Y520917D01*
X1082300Y521250D01*
G01X1085233Y519250D02*
X1085817Y518917D01*
X1086483Y518833D01*
X1087067Y518917D01*
X1087567Y519333D01*
X1087900Y519917D01*
Y523833D01*
G01Y523167D02*
X1087567Y523500D01*
X1087067Y523750D01*
X1086483Y523833D01*
X1085817Y523667D01*
X1085400Y523333D01*
X1085067Y522750D01*
X1084900Y522167D01*
X1084983Y521667D01*
X1085317Y521083D01*
X1085817Y520667D01*
X1086483Y520500D01*
X1086983Y520583D01*
X1087567Y520917D01*
X1087900Y521250D01*
G01X1092000Y523833D02*
Y520500D01*
G01Y525167D02*
X1091833Y525250D01*
Y525417D01*
X1092000Y525500D01*
X1092167Y525417D01*
Y525250D01*
X1092000Y525167D01*
G01X1096183Y520500D02*
Y523833D01*
G01Y523000D02*
X1096517Y523417D01*
X1097017Y523750D01*
X1097683Y523833D01*
X1098267Y523750D01*
X1098767Y523417D01*
X1099017Y522833D01*
Y520500D01*
G01X1102033Y519250D02*
X1102617Y518917D01*
X1103283Y518833D01*
X1103867Y518917D01*
X1104367Y519333D01*
X1104700Y519917D01*
Y523833D01*
G01Y523167D02*
X1104367Y523500D01*
X1103867Y523750D01*
X1103283Y523833D01*
X1102617Y523667D01*
X1102200Y523333D01*
X1101867Y522750D01*
X1101700Y522167D01*
X1101783Y521667D01*
X1102117Y521083D01*
X1102617Y520667D01*
X1103283Y520500D01*
X1103783Y520583D01*
X1104367Y520917D01*
X1104700Y521250D01*
G01X1114400Y520333D02*
X1114233Y520417D01*
Y520583D01*
X1114400Y520667D01*
X1114567Y520583D01*
Y520417D01*
X1114400Y520333D01*
G01Y522583D02*
X1114233Y522667D01*
Y522833D01*
X1114400Y522917D01*
X1114567Y522833D01*
Y522667D01*
X1114400Y522583D01*
G01X1125600Y525500D02*
Y520500D01*
G01X1124433Y523833D02*
X1126767D01*
G01X1129783Y520500D02*
Y525500D01*
G01Y523083D02*
X1130200Y523500D01*
X1130617Y523750D01*
X1131283Y523833D01*
X1131783Y523750D01*
X1132367Y523417D01*
X1132617Y522917D01*
Y520500D01*
G01X1135550Y522750D02*
X1138217D01*
X1137967Y523333D01*
X1137550Y523667D01*
X1136967Y523833D01*
X1136383Y523750D01*
X1135883Y523500D01*
X1135550Y522917D01*
X1135383Y522417D01*
Y521917D01*
X1135550Y521417D01*
X1135967Y520917D01*
X1136467Y520583D01*
X1137050Y520500D01*
X1137633Y520667D01*
X1138217Y521167D01*
G01X1146500Y518833D02*
Y523833D01*
G01Y523083D02*
X1146917Y523500D01*
X1147333Y523750D01*
X1148000Y523833D01*
X1148583Y523750D01*
X1149167Y523333D01*
X1149417Y522750D01*
X1149500Y522167D01*
X1149417Y521583D01*
X1149167Y521000D01*
X1148667Y520667D01*
X1148000Y520500D01*
X1147417Y520583D01*
X1146833Y520833D01*
X1146500Y521167D01*
G01X1153600Y520500D02*
Y525500D01*
G01X1157783Y523833D02*
Y521500D01*
X1158117Y520917D01*
X1158617Y520583D01*
X1159200Y520500D01*
X1159783Y520583D01*
X1160283Y520917D01*
X1160617Y521500D01*
G01Y520500D02*
Y523833D01*
G01X1163633Y519250D02*
X1164217Y518917D01*
X1164883Y518833D01*
X1165467Y518917D01*
X1165967Y519333D01*
X1166300Y519917D01*
Y523833D01*
G01Y523167D02*
X1165967Y523500D01*
X1165467Y523750D01*
X1164883Y523833D01*
X1164217Y523667D01*
X1163800Y523333D01*
X1163467Y522750D01*
X1163300Y522167D01*
X1163383Y521667D01*
X1163717Y521083D01*
X1164217Y520667D01*
X1164883Y520500D01*
X1165383Y520583D01*
X1165967Y520917D01*
X1166300Y521250D01*
G01X1169233Y519250D02*
X1169817Y518917D01*
X1170483Y518833D01*
X1171067Y518917D01*
X1171567Y519333D01*
X1171900Y519917D01*
Y523833D01*
G01Y523167D02*
X1171567Y523500D01*
X1171067Y523750D01*
X1170483Y523833D01*
X1169817Y523667D01*
X1169400Y523333D01*
X1169067Y522750D01*
X1168900Y522167D01*
X1168983Y521667D01*
X1169317Y521083D01*
X1169817Y520667D01*
X1170483Y520500D01*
X1170983Y520583D01*
X1171567Y520917D01*
X1171900Y521250D01*
G01X1176000Y523833D02*
Y520500D01*
G01Y525167D02*
X1175833Y525250D01*
Y525417D01*
X1176000Y525500D01*
X1176167Y525417D01*
Y525250D01*
X1176000Y525167D01*
G01X1180183Y520500D02*
Y523833D01*
G01Y523000D02*
X1180517Y523417D01*
X1181017Y523750D01*
X1181683Y523833D01*
X1182267Y523750D01*
X1182767Y523417D01*
X1183017Y522833D01*
Y520500D01*
G01X1186033Y519250D02*
X1186617Y518917D01*
X1187283Y518833D01*
X1187867Y518917D01*
X1188367Y519333D01*
X1188700Y519917D01*
Y523833D01*
G01Y523167D02*
X1188367Y523500D01*
X1187867Y523750D01*
X1187283Y523833D01*
X1186617Y523667D01*
X1186200Y523333D01*
X1185867Y522750D01*
X1185700Y522167D01*
X1185783Y521667D01*
X1186117Y521083D01*
X1186617Y520667D01*
X1187283Y520500D01*
X1187783Y520583D01*
X1188367Y520917D01*
X1188700Y521250D01*
G01X1197233Y520500D02*
Y523833D01*
G01Y523167D02*
X1197650Y523500D01*
X1198067Y523750D01*
X1198650Y523833D01*
X1199067Y523750D01*
X1199567Y523500D01*
G01X1205500Y520500D02*
Y523833D01*
G01Y523250D02*
X1205167Y523583D01*
X1204667Y523750D01*
X1204083Y523833D01*
X1203500Y523667D01*
X1203000Y523333D01*
X1202667Y522833D01*
X1202500Y522167D01*
X1202667Y521500D01*
X1203000Y521000D01*
X1203500Y520667D01*
X1204083Y520500D01*
X1204667Y520583D01*
X1205167Y520833D01*
X1205500Y521167D01*
G01X1209600Y525500D02*
Y520500D01*
G01X1208433Y523833D02*
X1210767D01*
G01X1215200D02*
Y520500D01*
G01Y525167D02*
X1215033Y525250D01*
Y525417D01*
X1215200Y525500D01*
X1215367Y525417D01*
Y525250D01*
X1215200Y525167D01*
G01X1220800Y520500D02*
X1220300Y520583D01*
X1219800Y520917D01*
X1219467Y521500D01*
X1219300Y522167D01*
X1219467Y522833D01*
X1219800Y523417D01*
X1220300Y523750D01*
X1220800Y523833D01*
X1221300Y523750D01*
X1221800Y523417D01*
X1222133Y522833D01*
X1222217Y522167D01*
X1222133Y521500D01*
X1221800Y520917D01*
X1221300Y520583D01*
X1220800Y520500D01*
G01X1230500Y518833D02*
Y523833D01*
G01Y523083D02*
X1230917Y523500D01*
X1231333Y523750D01*
X1232000Y523833D01*
X1232583Y523750D01*
X1233167Y523333D01*
X1233417Y522750D01*
X1233500Y522167D01*
X1233417Y521583D01*
X1233167Y521000D01*
X1232667Y520667D01*
X1232000Y520500D01*
X1231417Y520583D01*
X1230833Y520833D01*
X1230500Y521167D01*
G01X1236350Y522750D02*
X1239017D01*
X1238767Y523333D01*
X1238350Y523667D01*
X1237767Y523833D01*
X1237183Y523750D01*
X1236683Y523500D01*
X1236350Y522917D01*
X1236183Y522417D01*
Y521917D01*
X1236350Y521417D01*
X1236767Y520917D01*
X1237267Y520583D01*
X1237850Y520500D01*
X1238433Y520667D01*
X1239017Y521167D01*
G01X1242033Y520500D02*
Y523833D01*
G01Y523167D02*
X1242450Y523500D01*
X1242867Y523750D01*
X1243450Y523833D01*
X1243867Y523750D01*
X1244367Y523500D01*
G01X1253900Y520500D02*
Y524750D01*
X1254067Y525167D01*
X1254400Y525417D01*
X1254900Y525500D01*
X1255400Y525333D01*
X1255650Y524917D01*
G01X1254650Y523500D02*
X1252983D01*
G01X1260000Y520500D02*
X1259500Y520583D01*
X1259000Y520917D01*
X1258667Y521500D01*
X1258500Y522167D01*
X1258667Y522833D01*
X1259000Y523417D01*
X1259500Y523750D01*
X1260000Y523833D01*
X1260500Y523750D01*
X1261000Y523417D01*
X1261333Y522833D01*
X1261417Y522167D01*
X1261333Y521500D01*
X1261000Y520917D01*
X1260500Y520583D01*
X1260000Y520500D01*
G01X1265600D02*
Y525500D01*
G01X1271200Y520500D02*
Y525500D01*
G01X1276800Y520500D02*
X1276300Y520583D01*
X1275800Y520917D01*
X1275467Y521500D01*
X1275300Y522167D01*
X1275467Y522833D01*
X1275800Y523417D01*
X1276300Y523750D01*
X1276800Y523833D01*
X1277300Y523750D01*
X1277800Y523417D01*
X1278133Y522833D01*
X1278217Y522167D01*
X1278133Y521500D01*
X1277800Y520917D01*
X1277300Y520583D01*
X1276800Y520500D01*
G01X1280317Y523833D02*
X1281317Y520500D01*
X1282400Y523833D01*
X1283483Y520500D01*
X1284483Y523833D01*
G01X1288000D02*
Y520500D01*
G01Y525167D02*
X1287833Y525250D01*
Y525417D01*
X1288000Y525500D01*
X1288167Y525417D01*
Y525250D01*
X1288000Y525167D01*
G01X1292183Y520500D02*
Y523833D01*
G01Y523000D02*
X1292517Y523417D01*
X1293017Y523750D01*
X1293683Y523833D01*
X1294267Y523750D01*
X1294767Y523417D01*
X1295017Y522833D01*
Y520500D01*
G01X1298033Y519250D02*
X1298617Y518917D01*
X1299283Y518833D01*
X1299867Y518917D01*
X1300367Y519333D01*
X1300700Y519917D01*
Y523833D01*
G01Y523167D02*
X1300367Y523500D01*
X1299867Y523750D01*
X1299283Y523833D01*
X1298617Y523667D01*
X1298200Y523333D01*
X1297867Y522750D01*
X1297700Y522167D01*
X1297783Y521667D01*
X1298117Y521083D01*
X1298617Y520667D01*
X1299283Y520500D01*
X1299783Y520583D01*
X1300367Y520917D01*
X1300700Y521250D01*
G01X1304800Y520333D02*
X1304633Y520417D01*
Y520583D01*
X1304800Y520667D01*
X1304967Y520583D01*
Y520417D01*
X1304800Y520333D01*
G01Y522583D02*
X1304633Y522667D01*
Y522833D01*
X1304800Y522917D01*
X1304967Y522833D01*
Y522667D01*
X1304800Y522583D01*
G01X1033500Y529500D02*
Y534500D01*
G01Y532000D02*
X1033917Y532500D01*
X1034417Y532750D01*
X1034917Y532833D01*
X1035667Y532667D01*
X1036167Y532333D01*
X1036500Y531750D01*
Y531083D01*
X1036333Y530417D01*
X1036000Y529917D01*
X1035417Y529583D01*
X1034917Y529500D01*
X1034417Y529583D01*
X1033917Y529833D01*
X1033500Y530250D01*
G01X1039350Y531750D02*
X1042017D01*
X1041767Y532333D01*
X1041350Y532667D01*
X1040767Y532833D01*
X1040183Y532750D01*
X1039683Y532500D01*
X1039350Y531917D01*
X1039183Y531417D01*
Y530917D01*
X1039350Y530417D01*
X1039767Y529917D01*
X1040267Y529583D01*
X1040850Y529500D01*
X1041433Y529667D01*
X1042017Y530167D01*
G01X1051300Y529500D02*
Y533750D01*
X1051467Y534167D01*
X1051800Y534417D01*
X1052300Y534500D01*
X1052800Y534333D01*
X1053050Y533917D01*
G01X1052050Y532500D02*
X1050383D01*
G01X1056233Y529500D02*
Y532833D01*
G01Y532167D02*
X1056650Y532500D01*
X1057067Y532750D01*
X1057650Y532833D01*
X1058067Y532750D01*
X1058567Y532500D01*
G01X1061750Y531750D02*
X1064417D01*
X1064167Y532333D01*
X1063750Y532667D01*
X1063167Y532833D01*
X1062583Y532750D01*
X1062083Y532500D01*
X1061750Y531917D01*
X1061583Y531417D01*
Y530917D01*
X1061750Y530417D01*
X1062167Y529917D01*
X1062667Y529583D01*
X1063250Y529500D01*
X1063833Y529667D01*
X1064417Y530167D01*
G01X1067350Y531750D02*
X1070017D01*
X1069767Y532333D01*
X1069350Y532667D01*
X1068767Y532833D01*
X1068183Y532750D01*
X1067683Y532500D01*
X1067350Y531917D01*
X1067183Y531417D01*
Y530917D01*
X1067350Y530417D01*
X1067767Y529917D01*
X1068267Y529583D01*
X1068850Y529500D01*
X1069433Y529667D01*
X1070017Y530167D01*
G01X1079300Y529500D02*
Y533750D01*
X1079467Y534167D01*
X1079800Y534417D01*
X1080300Y534500D01*
X1080800Y534333D01*
X1081050Y533917D01*
G01X1080050Y532500D02*
X1078383D01*
G01X1084233Y529500D02*
Y532833D01*
G01Y532167D02*
X1084650Y532500D01*
X1085067Y532750D01*
X1085650Y532833D01*
X1086067Y532750D01*
X1086567Y532500D01*
G01X1091000Y529500D02*
X1090500Y529583D01*
X1090000Y529917D01*
X1089667Y530500D01*
X1089500Y531167D01*
X1089667Y531833D01*
X1090000Y532417D01*
X1090500Y532750D01*
X1091000Y532833D01*
X1091500Y532750D01*
X1092000Y532417D01*
X1092333Y531833D01*
X1092417Y531167D01*
X1092333Y530500D01*
X1092000Y529917D01*
X1091500Y529583D01*
X1091000Y529500D01*
G01X1094100D02*
Y532833D01*
G01Y531917D02*
X1094350Y532333D01*
X1094767Y532667D01*
X1095350Y532833D01*
X1095933Y532667D01*
X1096350Y532333D01*
X1096600Y531917D01*
Y529500D01*
G01Y531917D02*
X1096850Y532333D01*
X1097267Y532667D01*
X1097850Y532833D01*
X1098433Y532667D01*
X1098850Y532333D01*
X1099100Y531833D01*
Y529500D01*
G01X1106550Y530083D02*
X1106967Y529750D01*
X1107550Y529500D01*
X1108050D01*
X1108550Y529667D01*
X1108883Y529917D01*
X1109050Y530250D01*
X1108967Y530750D01*
X1108633Y531000D01*
X1107133Y531500D01*
X1106800Y532083D01*
X1106967Y532500D01*
X1107300Y532750D01*
X1107800Y532833D01*
X1108300Y532750D01*
X1108800Y532500D01*
G01X1113400Y529500D02*
X1112900Y529583D01*
X1112400Y529917D01*
X1112067Y530500D01*
X1111900Y531167D01*
X1112067Y531833D01*
X1112400Y532417D01*
X1112900Y532750D01*
X1113400Y532833D01*
X1113900Y532750D01*
X1114400Y532417D01*
X1114733Y531833D01*
X1114817Y531167D01*
X1114733Y530500D01*
X1114400Y529917D01*
X1113900Y529583D01*
X1113400Y529500D01*
G01X1119000D02*
Y534500D01*
G01X1126100D02*
Y529500D01*
G01Y530250D02*
X1125767Y529833D01*
X1125267Y529583D01*
X1124683Y529500D01*
X1124017Y529667D01*
X1123517Y530083D01*
X1123183Y530583D01*
X1123100Y531167D01*
X1123183Y531750D01*
X1123517Y532250D01*
X1124017Y532667D01*
X1124683Y532833D01*
X1125267Y532750D01*
X1125683Y532583D01*
X1126100Y532250D01*
G01X1128950Y531750D02*
X1131617D01*
X1131367Y532333D01*
X1130950Y532667D01*
X1130367Y532833D01*
X1129783Y532750D01*
X1129283Y532500D01*
X1128950Y531917D01*
X1128783Y531417D01*
Y530917D01*
X1128950Y530417D01*
X1129367Y529917D01*
X1129867Y529583D01*
X1130450Y529500D01*
X1131033Y529667D01*
X1131617Y530167D01*
G01X1134633Y529500D02*
Y532833D01*
G01Y532167D02*
X1135050Y532500D01*
X1135467Y532750D01*
X1136050Y532833D01*
X1136467Y532750D01*
X1136967Y532500D01*
G01X1144500Y529500D02*
Y532833D01*
G01Y531917D02*
X1144750Y532333D01*
X1145167Y532667D01*
X1145750Y532833D01*
X1146333Y532667D01*
X1146750Y532333D01*
X1147000Y531917D01*
Y529500D01*
G01Y531917D02*
X1147250Y532333D01*
X1147667Y532667D01*
X1148250Y532833D01*
X1148833Y532667D01*
X1149250Y532333D01*
X1149500Y531833D01*
Y529500D01*
G01X1154100D02*
Y532833D01*
G01Y532250D02*
X1153767Y532583D01*
X1153267Y532750D01*
X1152683Y532833D01*
X1152100Y532667D01*
X1151600Y532333D01*
X1151267Y531833D01*
X1151100Y531167D01*
X1151267Y530500D01*
X1151600Y530000D01*
X1152100Y529667D01*
X1152683Y529500D01*
X1153267Y529583D01*
X1153767Y529833D01*
X1154100Y530167D01*
G01X1156950Y530083D02*
X1157367Y529750D01*
X1157950Y529500D01*
X1158450D01*
X1158950Y529667D01*
X1159283Y529917D01*
X1159450Y530250D01*
X1159367Y530750D01*
X1159033Y531000D01*
X1157533Y531500D01*
X1157200Y532083D01*
X1157367Y532500D01*
X1157700Y532750D01*
X1158200Y532833D01*
X1158700Y532750D01*
X1159200Y532500D01*
G01X1162383Y529500D02*
Y534500D01*
G01X1165050Y532833D02*
X1162383Y530917D01*
G01X1163467Y531667D02*
X1165217Y529500D01*
G01X1169400Y529333D02*
X1169233Y529417D01*
Y529583D01*
X1169400Y529667D01*
X1169567Y529583D01*
Y529417D01*
X1169400Y529333D01*
G01X1032500Y552500D02*
Y557500D01*
G01Y555000D02*
X1032917Y555500D01*
X1033417Y555750D01*
X1033917Y555833D01*
X1034667Y555667D01*
X1035167Y555333D01*
X1035500Y554750D01*
Y554083D01*
X1035333Y553417D01*
X1035000Y552917D01*
X1034417Y552583D01*
X1033917Y552500D01*
X1033417Y552583D01*
X1032917Y552833D01*
X1032500Y553250D01*
G01X1038350Y554750D02*
X1041017D01*
X1040767Y555333D01*
X1040350Y555667D01*
X1039767Y555833D01*
X1039183Y555750D01*
X1038683Y555500D01*
X1038350Y554917D01*
X1038183Y554417D01*
Y553917D01*
X1038350Y553417D01*
X1038767Y552917D01*
X1039267Y552583D01*
X1039850Y552500D01*
X1040433Y552667D01*
X1041017Y553167D01*
G01X1050800Y557500D02*
Y552500D01*
G01X1049633Y555833D02*
X1051967D01*
G01X1055150Y554750D02*
X1057817D01*
X1057567Y555333D01*
X1057150Y555667D01*
X1056567Y555833D01*
X1055983Y555750D01*
X1055483Y555500D01*
X1055150Y554917D01*
X1054983Y554417D01*
Y553917D01*
X1055150Y553417D01*
X1055567Y552917D01*
X1056067Y552583D01*
X1056650Y552500D01*
X1057233Y552667D01*
X1057817Y553167D01*
G01X1060583Y552500D02*
Y555833D01*
G01Y555000D02*
X1060917Y555417D01*
X1061417Y555750D01*
X1062083Y555833D01*
X1062667Y555750D01*
X1063167Y555417D01*
X1063417Y554833D01*
Y552500D01*
G01X1067600Y557500D02*
Y552500D01*
G01X1066433Y555833D02*
X1068767D01*
G01X1071950Y554750D02*
X1074617D01*
X1074367Y555333D01*
X1073950Y555667D01*
X1073367Y555833D01*
X1072783Y555750D01*
X1072283Y555500D01*
X1071950Y554917D01*
X1071783Y554417D01*
Y553917D01*
X1071950Y553417D01*
X1072367Y552917D01*
X1072867Y552583D01*
X1073450Y552500D01*
X1074033Y552667D01*
X1074617Y553167D01*
G01X1080300Y557500D02*
Y552500D01*
G01Y553250D02*
X1079967Y552833D01*
X1079467Y552583D01*
X1078883Y552500D01*
X1078217Y552667D01*
X1077717Y553083D01*
X1077383Y553583D01*
X1077300Y554167D01*
X1077383Y554750D01*
X1077717Y555250D01*
X1078217Y555667D01*
X1078883Y555833D01*
X1079467Y555750D01*
X1079883Y555583D01*
X1080300Y555250D01*
G01X1087917Y555833D02*
X1088917Y552500D01*
X1090000Y555833D01*
X1091083Y552500D01*
X1092083Y555833D01*
G01X1095600D02*
Y552500D01*
G01Y557167D02*
X1095433Y557250D01*
Y557417D01*
X1095600Y557500D01*
X1095767Y557417D01*
Y557250D01*
X1095600Y557167D01*
G01X1101200Y557500D02*
Y552500D01*
G01X1100033Y555833D02*
X1102367D01*
G01X1105383Y552500D02*
Y557500D01*
G01Y555083D02*
X1105800Y555500D01*
X1106217Y555750D01*
X1106883Y555833D01*
X1107383Y555750D01*
X1107967Y555417D01*
X1108217Y554917D01*
Y552500D01*
G01X1116750Y553083D02*
X1117167Y552750D01*
X1117750Y552500D01*
X1118250D01*
X1118750Y552667D01*
X1119083Y552917D01*
X1119250Y553250D01*
X1119167Y553750D01*
X1118833Y554000D01*
X1117333Y554500D01*
X1117000Y555083D01*
X1117167Y555500D01*
X1117500Y555750D01*
X1118000Y555833D01*
X1118500Y555750D01*
X1119000Y555500D01*
G01X1123600Y552500D02*
X1123100Y552583D01*
X1122600Y552917D01*
X1122267Y553500D01*
X1122100Y554167D01*
X1122267Y554833D01*
X1122600Y555417D01*
X1123100Y555750D01*
X1123600Y555833D01*
X1124100Y555750D01*
X1124600Y555417D01*
X1124933Y554833D01*
X1125017Y554167D01*
X1124933Y553500D01*
X1124600Y552917D01*
X1124100Y552583D01*
X1123600Y552500D01*
G01X1129200D02*
Y557500D01*
G01X1136300D02*
Y552500D01*
G01Y553250D02*
X1135967Y552833D01*
X1135467Y552583D01*
X1134883Y552500D01*
X1134217Y552667D01*
X1133717Y553083D01*
X1133383Y553583D01*
X1133300Y554167D01*
X1133383Y554750D01*
X1133717Y555250D01*
X1134217Y555667D01*
X1134883Y555833D01*
X1135467Y555750D01*
X1135883Y555583D01*
X1136300Y555250D01*
G01X1139150Y554750D02*
X1141817D01*
X1141567Y555333D01*
X1141150Y555667D01*
X1140567Y555833D01*
X1139983Y555750D01*
X1139483Y555500D01*
X1139150Y554917D01*
X1138983Y554417D01*
Y553917D01*
X1139150Y553417D01*
X1139567Y552917D01*
X1140067Y552583D01*
X1140650Y552500D01*
X1141233Y552667D01*
X1141817Y553167D01*
G01X1144833Y552500D02*
Y555833D01*
G01Y555167D02*
X1145250Y555500D01*
X1145667Y555750D01*
X1146250Y555833D01*
X1146667Y555750D01*
X1147167Y555500D01*
G01X1154700Y552500D02*
Y555833D01*
G01Y554917D02*
X1154950Y555333D01*
X1155367Y555667D01*
X1155950Y555833D01*
X1156533Y555667D01*
X1156950Y555333D01*
X1157200Y554917D01*
Y552500D01*
G01Y554917D02*
X1157450Y555333D01*
X1157867Y555667D01*
X1158450Y555833D01*
X1159033Y555667D01*
X1159450Y555333D01*
X1159700Y554833D01*
Y552500D01*
G01X1164300D02*
Y555833D01*
G01Y555250D02*
X1163967Y555583D01*
X1163467Y555750D01*
X1162883Y555833D01*
X1162300Y555667D01*
X1161800Y555333D01*
X1161467Y554833D01*
X1161300Y554167D01*
X1161467Y553500D01*
X1161800Y553000D01*
X1162300Y552667D01*
X1162883Y552500D01*
X1163467Y552583D01*
X1163967Y552833D01*
X1164300Y553167D01*
G01X1167150Y553083D02*
X1167567Y552750D01*
X1168150Y552500D01*
X1168650D01*
X1169150Y552667D01*
X1169483Y552917D01*
X1169650Y553250D01*
X1169567Y553750D01*
X1169233Y554000D01*
X1167733Y554500D01*
X1167400Y555083D01*
X1167567Y555500D01*
X1167900Y555750D01*
X1168400Y555833D01*
X1168900Y555750D01*
X1169400Y555500D01*
G01X1172583Y552500D02*
Y557500D01*
G01X1175250Y555833D02*
X1172583Y553917D01*
G01X1173667Y554667D02*
X1175417Y552500D01*
G01X1179600Y552333D02*
X1179433Y552417D01*
Y552583D01*
X1179600Y552667D01*
X1179767Y552583D01*
Y552417D01*
X1179600Y552333D01*
G01X1034000Y566500D02*
Y561500D01*
G01X1032833Y564833D02*
X1035167D01*
G01X1039600Y561500D02*
X1039100Y561583D01*
X1038600Y561917D01*
X1038267Y562500D01*
X1038100Y563167D01*
X1038267Y563833D01*
X1038600Y564417D01*
X1039100Y564750D01*
X1039600Y564833D01*
X1040100Y564750D01*
X1040600Y564417D01*
X1040933Y563833D01*
X1041017Y563167D01*
X1040933Y562500D01*
X1040600Y561917D01*
X1040100Y561583D01*
X1039600Y561500D01*
G01X1049300D02*
Y566500D01*
G01Y564000D02*
X1049717Y564500D01*
X1050217Y564750D01*
X1050717Y564833D01*
X1051467Y564667D01*
X1051967Y564333D01*
X1052300Y563750D01*
Y563083D01*
X1052133Y562417D01*
X1051800Y561917D01*
X1051217Y561583D01*
X1050717Y561500D01*
X1050217Y561583D01*
X1049717Y561833D01*
X1049300Y562250D01*
G01X1055150Y563750D02*
X1057817D01*
X1057567Y564333D01*
X1057150Y564667D01*
X1056567Y564833D01*
X1055983Y564750D01*
X1055483Y564500D01*
X1055150Y563917D01*
X1054983Y563417D01*
Y562917D01*
X1055150Y562417D01*
X1055567Y561917D01*
X1056067Y561583D01*
X1056650Y561500D01*
X1057233Y561667D01*
X1057817Y562167D01*
G01X1068933Y564417D02*
X1068350Y564750D01*
X1067850Y564833D01*
X1067183Y564667D01*
X1066683Y564333D01*
X1066350Y563750D01*
X1066267Y563167D01*
X1066350Y562583D01*
X1066683Y562083D01*
X1067183Y561667D01*
X1067850Y561500D01*
X1068433Y561667D01*
X1068933Y562000D01*
G01X1073200Y561500D02*
X1072700Y561583D01*
X1072200Y561917D01*
X1071867Y562500D01*
X1071700Y563167D01*
X1071867Y563833D01*
X1072200Y564417D01*
X1072700Y564750D01*
X1073200Y564833D01*
X1073700Y564750D01*
X1074200Y564417D01*
X1074533Y563833D01*
X1074617Y563167D01*
X1074533Y562500D01*
X1074200Y561917D01*
X1073700Y561583D01*
X1073200Y561500D01*
G01X1077300Y564833D02*
X1078800Y561500D01*
X1080300Y564833D01*
G01X1083150Y563750D02*
X1085817D01*
X1085567Y564333D01*
X1085150Y564667D01*
X1084567Y564833D01*
X1083983Y564750D01*
X1083483Y564500D01*
X1083150Y563917D01*
X1082983Y563417D01*
Y562917D01*
X1083150Y562417D01*
X1083567Y561917D01*
X1084067Y561583D01*
X1084650Y561500D01*
X1085233Y561667D01*
X1085817Y562167D01*
G01X1088833Y561500D02*
Y564833D01*
G01Y564167D02*
X1089250Y564500D01*
X1089667Y564750D01*
X1090250Y564833D01*
X1090667Y564750D01*
X1091167Y564500D01*
G01X1094350Y563750D02*
X1097017D01*
X1096767Y564333D01*
X1096350Y564667D01*
X1095767Y564833D01*
X1095183Y564750D01*
X1094683Y564500D01*
X1094350Y563917D01*
X1094183Y563417D01*
Y562917D01*
X1094350Y562417D01*
X1094767Y561917D01*
X1095267Y561583D01*
X1095850Y561500D01*
X1096433Y561667D01*
X1097017Y562167D01*
G01X1102700Y566500D02*
Y561500D01*
G01Y562250D02*
X1102367Y561833D01*
X1101867Y561583D01*
X1101283Y561500D01*
X1100617Y561667D01*
X1100117Y562083D01*
X1099783Y562583D01*
X1099700Y563167D01*
X1099783Y563750D01*
X1100117Y564250D01*
X1100617Y564667D01*
X1101283Y564833D01*
X1101867Y564750D01*
X1102283Y564583D01*
X1102700Y564250D01*
G01X1110900Y561500D02*
Y566500D01*
G01Y564000D02*
X1111317Y564500D01*
X1111817Y564750D01*
X1112317Y564833D01*
X1113067Y564667D01*
X1113567Y564333D01*
X1113900Y563750D01*
Y563083D01*
X1113733Y562417D01*
X1113400Y561917D01*
X1112817Y561583D01*
X1112317Y561500D01*
X1111817Y561583D01*
X1111317Y561833D01*
X1110900Y562250D01*
G01X1116250Y560000D02*
X1116750Y559833D01*
X1117417Y560000D01*
X1117833Y560333D01*
X1118167Y560750D01*
X1118667Y562083D01*
X1119750Y564833D01*
G01X1117083D02*
X1118667Y562083D01*
G01X1127950D02*
X1128367Y561750D01*
X1128950Y561500D01*
X1129450D01*
X1129950Y561667D01*
X1130283Y561917D01*
X1130450Y562250D01*
X1130367Y562750D01*
X1130033Y563000D01*
X1128533Y563500D01*
X1128200Y564083D01*
X1128367Y564500D01*
X1128700Y564750D01*
X1129200Y564833D01*
X1129700Y564750D01*
X1130200Y564500D01*
G01X1134800Y561500D02*
X1134300Y561583D01*
X1133800Y561917D01*
X1133467Y562500D01*
X1133300Y563167D01*
X1133467Y563833D01*
X1133800Y564417D01*
X1134300Y564750D01*
X1134800Y564833D01*
X1135300Y564750D01*
X1135800Y564417D01*
X1136133Y563833D01*
X1136217Y563167D01*
X1136133Y562500D01*
X1135800Y561917D01*
X1135300Y561583D01*
X1134800Y561500D01*
G01X1140400D02*
Y566500D01*
G01X1147500D02*
Y561500D01*
G01Y562250D02*
X1147167Y561833D01*
X1146667Y561583D01*
X1146083Y561500D01*
X1145417Y561667D01*
X1144917Y562083D01*
X1144583Y562583D01*
X1144500Y563167D01*
X1144583Y563750D01*
X1144917Y564250D01*
X1145417Y564667D01*
X1146083Y564833D01*
X1146667Y564750D01*
X1147083Y564583D01*
X1147500Y564250D01*
G01X1150350Y563750D02*
X1153017D01*
X1152767Y564333D01*
X1152350Y564667D01*
X1151767Y564833D01*
X1151183Y564750D01*
X1150683Y564500D01*
X1150350Y563917D01*
X1150183Y563417D01*
Y562917D01*
X1150350Y562417D01*
X1150767Y561917D01*
X1151267Y561583D01*
X1151850Y561500D01*
X1152433Y561667D01*
X1153017Y562167D01*
G01X1156033Y561500D02*
Y564833D01*
G01Y564167D02*
X1156450Y564500D01*
X1156867Y564750D01*
X1157450Y564833D01*
X1157867Y564750D01*
X1158367Y564500D01*
G01X1165900Y561500D02*
Y564833D01*
G01Y563917D02*
X1166150Y564333D01*
X1166567Y564667D01*
X1167150Y564833D01*
X1167733Y564667D01*
X1168150Y564333D01*
X1168400Y563917D01*
Y561500D01*
G01Y563917D02*
X1168650Y564333D01*
X1169067Y564667D01*
X1169650Y564833D01*
X1170233Y564667D01*
X1170650Y564333D01*
X1170900Y563833D01*
Y561500D01*
G01X1175500D02*
Y564833D01*
G01Y564250D02*
X1175167Y564583D01*
X1174667Y564750D01*
X1174083Y564833D01*
X1173500Y564667D01*
X1173000Y564333D01*
X1172667Y563833D01*
X1172500Y563167D01*
X1172667Y562500D01*
X1173000Y562000D01*
X1173500Y561667D01*
X1174083Y561500D01*
X1174667Y561583D01*
X1175167Y561833D01*
X1175500Y562167D01*
G01X1178350Y562083D02*
X1178767Y561750D01*
X1179350Y561500D01*
X1179850D01*
X1180350Y561667D01*
X1180683Y561917D01*
X1180850Y562250D01*
X1180767Y562750D01*
X1180433Y563000D01*
X1178933Y563500D01*
X1178600Y564083D01*
X1178767Y564500D01*
X1179100Y564750D01*
X1179600Y564833D01*
X1180100Y564750D01*
X1180600Y564500D01*
G01X1183783Y561500D02*
Y566500D01*
G01X1186450Y564833D02*
X1183783Y562917D01*
G01X1184867Y563667D02*
X1186617Y561500D01*
G01X1197900D02*
Y564833D01*
G01Y564250D02*
X1197567Y564583D01*
X1197067Y564750D01*
X1196483Y564833D01*
X1195900Y564667D01*
X1195400Y564333D01*
X1195067Y563833D01*
X1194900Y563167D01*
X1195067Y562500D01*
X1195400Y562000D01*
X1195900Y561667D01*
X1196483Y561500D01*
X1197067Y561583D01*
X1197567Y561833D01*
X1197900Y562167D01*
G01X1200583Y561500D02*
Y564833D01*
G01Y564000D02*
X1200917Y564417D01*
X1201417Y564750D01*
X1202083Y564833D01*
X1202667Y564750D01*
X1203167Y564417D01*
X1203417Y563833D01*
Y561500D01*
G01X1209100Y566500D02*
Y561500D01*
G01Y562250D02*
X1208767Y561833D01*
X1208267Y561583D01*
X1207683Y561500D01*
X1207017Y561667D01*
X1206517Y562083D01*
X1206183Y562583D01*
X1206100Y563167D01*
X1206183Y563750D01*
X1206517Y564250D01*
X1207017Y564667D01*
X1207683Y564833D01*
X1208267Y564750D01*
X1208683Y564583D01*
X1209100Y564250D01*
G01X1217383Y561500D02*
Y566500D01*
G01Y564083D02*
X1217800Y564500D01*
X1218217Y564750D01*
X1218883Y564833D01*
X1219383Y564750D01*
X1219967Y564417D01*
X1220217Y563917D01*
Y561500D01*
G01X1224400D02*
X1223900Y561583D01*
X1223400Y561917D01*
X1223067Y562500D01*
X1222900Y563167D01*
X1223067Y563833D01*
X1223400Y564417D01*
X1223900Y564750D01*
X1224400Y564833D01*
X1224900Y564750D01*
X1225400Y564417D01*
X1225733Y563833D01*
X1225817Y563167D01*
X1225733Y562500D01*
X1225400Y561917D01*
X1224900Y561583D01*
X1224400Y561500D01*
G01X1230000D02*
Y566500D01*
G01X1234350Y563750D02*
X1237017D01*
X1236767Y564333D01*
X1236350Y564667D01*
X1235767Y564833D01*
X1235183Y564750D01*
X1234683Y564500D01*
X1234350Y563917D01*
X1234183Y563417D01*
Y562917D01*
X1234350Y562417D01*
X1234767Y561917D01*
X1235267Y561583D01*
X1235850Y561500D01*
X1236433Y561667D01*
X1237017Y562167D01*
G01X1248300Y561500D02*
Y564833D01*
G01Y564250D02*
X1247967Y564583D01*
X1247467Y564750D01*
X1246883Y564833D01*
X1246300Y564667D01*
X1245800Y564333D01*
X1245467Y563833D01*
X1245300Y563167D01*
X1245467Y562500D01*
X1245800Y562000D01*
X1246300Y561667D01*
X1246883Y561500D01*
X1247467Y561583D01*
X1247967Y561833D01*
X1248300Y562167D01*
G01X1252400Y561500D02*
Y566500D01*
G01X1256750Y562083D02*
X1257167Y561750D01*
X1257750Y561500D01*
X1258250D01*
X1258750Y561667D01*
X1259083Y561917D01*
X1259250Y562250D01*
X1259167Y562750D01*
X1258833Y563000D01*
X1257333Y563500D01*
X1257000Y564083D01*
X1257167Y564500D01*
X1257500Y564750D01*
X1258000Y564833D01*
X1258500Y564750D01*
X1259000Y564500D01*
G01X1263600Y561500D02*
X1263100Y561583D01*
X1262600Y561917D01*
X1262267Y562500D01*
X1262100Y563167D01*
X1262267Y563833D01*
X1262600Y564417D01*
X1263100Y564750D01*
X1263600Y564833D01*
X1264100Y564750D01*
X1264600Y564417D01*
X1264933Y563833D01*
X1265017Y563167D01*
X1264933Y562500D01*
X1264600Y561917D01*
X1264100Y561583D01*
X1263600Y561500D01*
G01X1273383D02*
Y564833D01*
G01Y564000D02*
X1273717Y564417D01*
X1274217Y564750D01*
X1274883Y564833D01*
X1275467Y564750D01*
X1275967Y564417D01*
X1276217Y563833D01*
Y561500D01*
G01X1279150Y563750D02*
X1281817D01*
X1281567Y564333D01*
X1281150Y564667D01*
X1280567Y564833D01*
X1279983Y564750D01*
X1279483Y564500D01*
X1279150Y563917D01*
X1278983Y563417D01*
Y562917D01*
X1279150Y562417D01*
X1279567Y561917D01*
X1280067Y561583D01*
X1280650Y561500D01*
X1281233Y561667D01*
X1281817Y562167D01*
G01X1284750Y563750D02*
X1287417D01*
X1287167Y564333D01*
X1286750Y564667D01*
X1286167Y564833D01*
X1285583Y564750D01*
X1285083Y564500D01*
X1284750Y563917D01*
X1284583Y563417D01*
Y562917D01*
X1284750Y562417D01*
X1285167Y561917D01*
X1285667Y561583D01*
X1286250Y561500D01*
X1286833Y561667D01*
X1287417Y562167D01*
G01X1293100Y566500D02*
Y561500D01*
G01Y562250D02*
X1292767Y561833D01*
X1292267Y561583D01*
X1291683Y561500D01*
X1291017Y561667D01*
X1290517Y562083D01*
X1290183Y562583D01*
X1290100Y563167D01*
X1290183Y563750D01*
X1290517Y564250D01*
X1291017Y564667D01*
X1291683Y564833D01*
X1292267Y564750D01*
X1292683Y564583D01*
X1293100Y564250D01*
G01X1302800Y566500D02*
Y561500D01*
G01X1301633Y564833D02*
X1303967D01*
G01X1308400Y561500D02*
X1307900Y561583D01*
X1307400Y561917D01*
X1307067Y562500D01*
X1306900Y563167D01*
X1307067Y563833D01*
X1307400Y564417D01*
X1307900Y564750D01*
X1308400Y564833D01*
X1308900Y564750D01*
X1309400Y564417D01*
X1309733Y563833D01*
X1309817Y563167D01*
X1309733Y562500D01*
X1309400Y561917D01*
X1308900Y561583D01*
X1308400Y561500D01*
G01X1109833Y590500D02*
Y595500D01*
X1111833D01*
X1112500Y595250D01*
X1113000Y594667D01*
X1113167Y594000D01*
X1113000Y593333D01*
X1112583Y592833D01*
X1111833Y592583D01*
X1109833D01*
G01X1117100Y590500D02*
Y595500D01*
G01X1121283Y593833D02*
Y591500D01*
X1121617Y590917D01*
X1122117Y590583D01*
X1122700Y590500D01*
X1123283Y590583D01*
X1123783Y590917D01*
X1124117Y591500D01*
G01Y590500D02*
Y593833D01*
G01X1127133Y589250D02*
X1127717Y588917D01*
X1128383Y588833D01*
X1128967Y588917D01*
X1129467Y589333D01*
X1129800Y589917D01*
Y593833D01*
G01Y593167D02*
X1129467Y593500D01*
X1128967Y593750D01*
X1128383Y593833D01*
X1127717Y593667D01*
X1127300Y593333D01*
X1126967Y592750D01*
X1126800Y592167D01*
X1126883Y591667D01*
X1127217Y591083D01*
X1127717Y590667D01*
X1128383Y590500D01*
X1128883Y590583D01*
X1129467Y590917D01*
X1129800Y591250D01*
G01X1132733Y589250D02*
X1133317Y588917D01*
X1133983Y588833D01*
X1134567Y588917D01*
X1135067Y589333D01*
X1135400Y589917D01*
Y593833D01*
G01Y593167D02*
X1135067Y593500D01*
X1134567Y593750D01*
X1133983Y593833D01*
X1133317Y593667D01*
X1132900Y593333D01*
X1132567Y592750D01*
X1132400Y592167D01*
X1132483Y591667D01*
X1132817Y591083D01*
X1133317Y590667D01*
X1133983Y590500D01*
X1134483Y590583D01*
X1135067Y590917D01*
X1135400Y591250D01*
G01X1139500Y593833D02*
Y590500D01*
G01Y595167D02*
X1139333Y595250D01*
Y595417D01*
X1139500Y595500D01*
X1139667Y595417D01*
Y595250D01*
X1139500Y595167D01*
G01X1143683Y590500D02*
Y593833D01*
G01Y593000D02*
X1144017Y593417D01*
X1144517Y593750D01*
X1145183Y593833D01*
X1145767Y593750D01*
X1146267Y593417D01*
X1146517Y592833D01*
Y590500D01*
G01X1149533Y589250D02*
X1150117Y588917D01*
X1150783Y588833D01*
X1151367Y588917D01*
X1151867Y589333D01*
X1152200Y589917D01*
Y593833D01*
G01Y593167D02*
X1151867Y593500D01*
X1151367Y593750D01*
X1150783Y593833D01*
X1150117Y593667D01*
X1149700Y593333D01*
X1149367Y592750D01*
X1149200Y592167D01*
X1149283Y591667D01*
X1149617Y591083D01*
X1150117Y590667D01*
X1150783Y590500D01*
X1151283Y590583D01*
X1151867Y590917D01*
X1152200Y591250D01*
G01X1163233Y593417D02*
X1162650Y593750D01*
X1162150Y593833D01*
X1161483Y593667D01*
X1160983Y593333D01*
X1160650Y592750D01*
X1160567Y592167D01*
X1160650Y591583D01*
X1160983Y591083D01*
X1161483Y590667D01*
X1162150Y590500D01*
X1162733Y590667D01*
X1163233Y591000D01*
G01X1166333Y590500D02*
Y593833D01*
G01Y593167D02*
X1166750Y593500D01*
X1167167Y593750D01*
X1167750Y593833D01*
X1168167Y593750D01*
X1168667Y593500D01*
G01X1173100Y593833D02*
Y590500D01*
G01Y595167D02*
X1172933Y595250D01*
Y595417D01*
X1173100Y595500D01*
X1173267Y595417D01*
Y595250D01*
X1173100Y595167D01*
G01X1178700Y595500D02*
Y590500D01*
G01X1177533Y593833D02*
X1179867D01*
G01X1183050Y592750D02*
X1185717D01*
X1185467Y593333D01*
X1185050Y593667D01*
X1184467Y593833D01*
X1183883Y593750D01*
X1183383Y593500D01*
X1183050Y592917D01*
X1182883Y592417D01*
Y591917D01*
X1183050Y591417D01*
X1183467Y590917D01*
X1183967Y590583D01*
X1184550Y590500D01*
X1185133Y590667D01*
X1185717Y591167D01*
G01X1188733Y590500D02*
Y593833D01*
G01Y593167D02*
X1189150Y593500D01*
X1189567Y593750D01*
X1190150Y593833D01*
X1190567Y593750D01*
X1191067Y593500D01*
G01X1195500Y593833D02*
Y590500D01*
G01Y595167D02*
X1195333Y595250D01*
Y595417D01*
X1195500Y595500D01*
X1195667Y595417D01*
Y595250D01*
X1195500Y595167D01*
G01X1202600Y590500D02*
Y593833D01*
G01Y593250D02*
X1202267Y593583D01*
X1201767Y593750D01*
X1201183Y593833D01*
X1200600Y593667D01*
X1200100Y593333D01*
X1199767Y592833D01*
X1199600Y592167D01*
X1199767Y591500D01*
X1200100Y591000D01*
X1200600Y590667D01*
X1201183Y590500D01*
X1201767Y590583D01*
X1202267Y590833D01*
X1202600Y591167D01*
G01X1106417Y735500D02*
X1108500Y730500D01*
X1110583Y735500D01*
G01X1113100D02*
X1115100D01*
G01X1114100D02*
Y730500D01*
G01X1113100D02*
X1115100D01*
G01X1118033D02*
Y735500D01*
X1120033D01*
X1120700Y735250D01*
X1121200Y734667D01*
X1121367Y734000D01*
X1121200Y733333D01*
X1120783Y732833D01*
X1120033Y732583D01*
X1118033D01*
G01X1184667Y150367D02*
X1185000Y150617D01*
X1185250Y151033D01*
X1185417Y151617D01*
X1185250Y152117D01*
X1184917Y152450D01*
X1184333Y152700D01*
X1182083D01*
Y147700D01*
X1184833D01*
X1185417Y148033D01*
X1185750Y148533D01*
X1185917Y149117D01*
X1185750Y149700D01*
X1185250Y150200D01*
X1184667Y150367D01*
X1182083D01*
G01X1187517Y147700D02*
X1189600Y152700D01*
X1191683Y147700D01*
G01X1190933Y149450D02*
X1188267D01*
G01X1197033Y152283D02*
X1196533Y152533D01*
X1195950Y152700D01*
X1195283D01*
X1194533Y152450D01*
X1193950Y152033D01*
X1193533Y151533D01*
X1193200Y150700D01*
X1193117Y149950D01*
X1193283Y149200D01*
X1193533Y148700D01*
X1194033Y148200D01*
X1194617Y147867D01*
X1195200Y147700D01*
X1195783D01*
X1196367Y147867D01*
X1196867Y148117D01*
X1197283Y148450D01*
G01X1198967Y147700D02*
Y152700D01*
G01X1202133D02*
X1198967Y149617D01*
G01X1202633Y147700D02*
X1200383Y151033D01*
G01X1210167Y147700D02*
Y152700D01*
X1211833D01*
X1212500Y152450D01*
X1213000Y152117D01*
X1213417Y151617D01*
X1213750Y151033D01*
X1213833Y150200D01*
X1213750Y149367D01*
X1213417Y148783D01*
X1213000Y148283D01*
X1212500Y147950D01*
X1211833Y147700D01*
X1210167D01*
G01X1215933D02*
Y152700D01*
X1218017D01*
X1218683Y152450D01*
X1219100Y152117D01*
X1219267Y151450D01*
X1219100Y150783D01*
X1218600Y150367D01*
X1218017Y150117D01*
X1215933D01*
G01X1218017D02*
X1219267Y147700D01*
G01X1222200Y152700D02*
X1224200D01*
G01X1223200D02*
Y147700D01*
G01X1222200D02*
X1224200D01*
G01X1227133Y152700D02*
Y147700D01*
X1230467D01*
G01X1232733Y152700D02*
Y147700D01*
X1236067D01*
G01X1259900D02*
Y151033D01*
G01Y150117D02*
X1260150Y150533D01*
X1260567Y150867D01*
X1261150Y151033D01*
X1261733Y150867D01*
X1262150Y150533D01*
X1262400Y150117D01*
Y147700D01*
G01Y150117D02*
X1262650Y150533D01*
X1263067Y150867D01*
X1263650Y151033D01*
X1264233Y150867D01*
X1264650Y150533D01*
X1264900Y150033D01*
Y147700D01*
G01X1268000Y151033D02*
Y147700D01*
G01Y152367D02*
X1267833Y152450D01*
Y152617D01*
X1268000Y152700D01*
X1268167Y152617D01*
Y152450D01*
X1268000Y152367D01*
G01X1273600Y147700D02*
Y152700D01*
G01X1277950Y148283D02*
X1278367Y147950D01*
X1278950Y147700D01*
X1279450D01*
X1279950Y147867D01*
X1280283Y148117D01*
X1280450Y148450D01*
X1280367Y148950D01*
X1280033Y149200D01*
X1278533Y149700D01*
X1278200Y150283D01*
X1278367Y150700D01*
X1278700Y150950D01*
X1279200Y151033D01*
X1279700Y150950D01*
X1280200Y150700D01*
G01X1284383Y146033D02*
X1283550Y146867D01*
X1283133Y147700D01*
Y151033D01*
X1283550Y151867D01*
X1284383Y152700D01*
G01X1288483Y147700D02*
Y152700D01*
X1292317Y147700D01*
Y152700D01*
G01X1294333Y147700D02*
Y152700D01*
X1296333D01*
X1297000Y152450D01*
X1297500Y151867D01*
X1297667Y151200D01*
X1297500Y150533D01*
X1297083Y150033D01*
X1296333Y149783D01*
X1294333D01*
G01X1301600Y152700D02*
Y147700D01*
G01X1299683Y152700D02*
X1303517D01*
G01X1305450Y147700D02*
Y152700D01*
G01X1308950D02*
Y147700D01*
G01Y150200D02*
X1305450D01*
G01X1313217Y146033D02*
X1314050Y146867D01*
X1314467Y147700D01*
Y151033D01*
X1314050Y151867D01*
X1313217Y152700D01*
G01X1136167Y157700D02*
Y162700D01*
X1137833D01*
X1138500Y162450D01*
X1139000Y162117D01*
X1139417Y161617D01*
X1139750Y161033D01*
X1139833Y160200D01*
X1139750Y159367D01*
X1139417Y158783D01*
X1139000Y158283D01*
X1138500Y157950D01*
X1137833Y157700D01*
X1136167D01*
G01X1142017Y161867D02*
X1142517Y162367D01*
X1143100Y162617D01*
X1143767Y162700D01*
X1144600Y162533D01*
X1145183Y162117D01*
X1145350Y161617D01*
X1145267Y161117D01*
X1144933Y160700D01*
X1143267Y159867D01*
X1142517Y159283D01*
X1142017Y158450D01*
X1141850Y157700D01*
X1145350D01*
G01X1178750Y315500D02*
Y320500D01*
G01X1182250D02*
Y315500D01*
G01Y318000D02*
X1178750D01*
G01X1186100Y315500D02*
X1185433Y315583D01*
X1184850Y315917D01*
X1184350Y316417D01*
X1184017Y317000D01*
X1183850Y317667D01*
Y318333D01*
X1184017Y319000D01*
X1184350Y319583D01*
X1184850Y320083D01*
X1185433Y320417D01*
X1186100Y320500D01*
X1186767Y320417D01*
X1187350Y320083D01*
X1187850Y319583D01*
X1188183Y319000D01*
X1188350Y318333D01*
Y317667D01*
X1188183Y317000D01*
X1187850Y316417D01*
X1187350Y315917D01*
X1186767Y315583D01*
X1186100Y315500D01*
G01X1190033Y320500D02*
Y315500D01*
X1193367D01*
G01X1198967D02*
X1195633D01*
Y320500D01*
X1198967D01*
G01X1197633Y318083D02*
X1195633D01*
G01X1222800Y315500D02*
Y318833D01*
G01Y317917D02*
X1223050Y318333D01*
X1223467Y318667D01*
X1224050Y318833D01*
X1224633Y318667D01*
X1225050Y318333D01*
X1225300Y317917D01*
Y315500D01*
G01Y317917D02*
X1225550Y318333D01*
X1225967Y318667D01*
X1226550Y318833D01*
X1227133Y318667D01*
X1227550Y318333D01*
X1227800Y317833D01*
Y315500D01*
G01X1230900Y318833D02*
Y315500D01*
G01Y320167D02*
X1230733Y320250D01*
Y320417D01*
X1230900Y320500D01*
X1231067Y320417D01*
Y320250D01*
X1230900Y320167D01*
G01X1236500Y315500D02*
Y320500D01*
G01X1240850Y316083D02*
X1241267Y315750D01*
X1241850Y315500D01*
X1242350D01*
X1242850Y315667D01*
X1243183Y315917D01*
X1243350Y316250D01*
X1243267Y316750D01*
X1242933Y317000D01*
X1241433Y317500D01*
X1241100Y318083D01*
X1241267Y318500D01*
X1241600Y318750D01*
X1242100Y318833D01*
X1242600Y318750D01*
X1243100Y318500D01*
G01X1247283Y313833D02*
X1246450Y314667D01*
X1246033Y315500D01*
Y318833D01*
X1246450Y319667D01*
X1247283Y320500D01*
G01X1251633Y315500D02*
Y320500D01*
X1253633D01*
X1254300Y320250D01*
X1254800Y319667D01*
X1254967Y319000D01*
X1254800Y318333D01*
X1254383Y317833D01*
X1253633Y317583D01*
X1251633D01*
G01X1258900Y320500D02*
Y315500D01*
G01X1256983Y320500D02*
X1260817D01*
G01X1262750Y315500D02*
Y320500D01*
G01X1266250D02*
Y315500D01*
G01Y318000D02*
X1262750D01*
G01X1270517Y313833D02*
X1271350Y314667D01*
X1271767Y315500D01*
Y318833D01*
X1271350Y319667D01*
X1270517Y320500D01*
G01X1135167Y315700D02*
Y320700D01*
X1136833D01*
X1137500Y320450D01*
X1138000Y320117D01*
X1138417Y319617D01*
X1138750Y319033D01*
X1138833Y318200D01*
X1138750Y317367D01*
X1138417Y316783D01*
X1138000Y316283D01*
X1137500Y315950D01*
X1136833Y315700D01*
X1135167D01*
G01X1142600D02*
Y320700D01*
X1141600Y319700D01*
G01Y315700D02*
X1143600D01*
G01X1136833Y619917D02*
X1136250Y620250D01*
X1135750Y620333D01*
X1135083Y620167D01*
X1134583Y619833D01*
X1134250Y619250D01*
X1134167Y618667D01*
X1134250Y618083D01*
X1134583Y617583D01*
X1135083Y617167D01*
X1135750Y617000D01*
X1136333Y617167D01*
X1136833Y617500D01*
G01X1141100Y617000D02*
X1140600Y617083D01*
X1140100Y617417D01*
X1139767Y618000D01*
X1139600Y618667D01*
X1139767Y619333D01*
X1140100Y619917D01*
X1140600Y620250D01*
X1141100Y620333D01*
X1141600Y620250D01*
X1142100Y619917D01*
X1142433Y619333D01*
X1142517Y618667D01*
X1142433Y618000D01*
X1142100Y617417D01*
X1141600Y617083D01*
X1141100Y617000D01*
G01X1145200Y615333D02*
Y620333D01*
G01Y619583D02*
X1145617Y620000D01*
X1146033Y620250D01*
X1146700Y620333D01*
X1147283Y620250D01*
X1147867Y619833D01*
X1148117Y619250D01*
X1148200Y618667D01*
X1148117Y618083D01*
X1147867Y617500D01*
X1147367Y617167D01*
X1146700Y617000D01*
X1146117Y617083D01*
X1145533Y617333D01*
X1145200Y617667D01*
G01X1150800Y615333D02*
Y620333D01*
G01Y619583D02*
X1151217Y620000D01*
X1151633Y620250D01*
X1152300Y620333D01*
X1152883Y620250D01*
X1153467Y619833D01*
X1153717Y619250D01*
X1153800Y618667D01*
X1153717Y618083D01*
X1153467Y617500D01*
X1152967Y617167D01*
X1152300Y617000D01*
X1151717Y617083D01*
X1151133Y617333D01*
X1150800Y617667D01*
G01X1156650Y619250D02*
X1159317D01*
X1159067Y619833D01*
X1158650Y620167D01*
X1158067Y620333D01*
X1157483Y620250D01*
X1156983Y620000D01*
X1156650Y619417D01*
X1156483Y618917D01*
Y618417D01*
X1156650Y617917D01*
X1157067Y617417D01*
X1157567Y617083D01*
X1158150Y617000D01*
X1158733Y617167D01*
X1159317Y617667D01*
G01X1162333Y617000D02*
Y620333D01*
G01Y619667D02*
X1162750Y620000D01*
X1163167Y620250D01*
X1163750Y620333D01*
X1164167Y620250D01*
X1164667Y620000D01*
G01X1180417Y734500D02*
X1182500Y729500D01*
X1184583Y734500D01*
G01X1188100Y729500D02*
X1187433Y729583D01*
X1186850Y729917D01*
X1186350Y730417D01*
X1186017Y731000D01*
X1185850Y731667D01*
Y732333D01*
X1186017Y733000D01*
X1186350Y733583D01*
X1186850Y734083D01*
X1187433Y734417D01*
X1188100Y734500D01*
X1188767Y734417D01*
X1189350Y734083D01*
X1189850Y733583D01*
X1190183Y733000D01*
X1190350Y732333D01*
Y731667D01*
X1190183Y731000D01*
X1189850Y730417D01*
X1189350Y729917D01*
X1188767Y729583D01*
X1188100Y729500D01*
G01X1192033D02*
Y734500D01*
X1194033D01*
X1194700Y734250D01*
X1195200Y733667D01*
X1195367Y733000D01*
X1195200Y732333D01*
X1194783Y731833D01*
X1194033Y731583D01*
X1192033D01*
G01X1218250Y281583D02*
X1218667Y281250D01*
X1219250Y281000D01*
X1219750D01*
X1220250Y281167D01*
X1220583Y281417D01*
X1220750Y281750D01*
X1220667Y282250D01*
X1220333Y282500D01*
X1218833Y283000D01*
X1218500Y283583D01*
X1218667Y284000D01*
X1219000Y284250D01*
X1219500Y284333D01*
X1220000Y284250D01*
X1220500Y284000D01*
G01X1225100Y286000D02*
Y281000D01*
G01X1223933Y284333D02*
X1226267D01*
G01X1229283D02*
Y282000D01*
X1229617Y281417D01*
X1230117Y281083D01*
X1230700Y281000D01*
X1231283Y281083D01*
X1231783Y281417D01*
X1232117Y282000D01*
G01Y281000D02*
Y284333D01*
G01X1234800Y281000D02*
Y286000D01*
G01Y283500D02*
X1235217Y284000D01*
X1235717Y284250D01*
X1236217Y284333D01*
X1236967Y284167D01*
X1237467Y283833D01*
X1237800Y283250D01*
Y282583D01*
X1237633Y281917D01*
X1237300Y281417D01*
X1236717Y281083D01*
X1236217Y281000D01*
X1235717Y281083D01*
X1235217Y281333D01*
X1234800Y281750D01*
G01X1247500Y281000D02*
Y286000D01*
G01X1251850Y283250D02*
X1254517D01*
X1254267Y283833D01*
X1253850Y284167D01*
X1253267Y284333D01*
X1252683Y284250D01*
X1252183Y284000D01*
X1251850Y283417D01*
X1251683Y282917D01*
Y282417D01*
X1251850Y281917D01*
X1252267Y281417D01*
X1252767Y281083D01*
X1253350Y281000D01*
X1253933Y281167D01*
X1254517Y281667D01*
G01X1257283Y281000D02*
Y284333D01*
G01Y283500D02*
X1257617Y283917D01*
X1258117Y284250D01*
X1258783Y284333D01*
X1259367Y284250D01*
X1259867Y283917D01*
X1260117Y283333D01*
Y281000D01*
G01X1263133Y279750D02*
X1263717Y279417D01*
X1264383Y279333D01*
X1264967Y279417D01*
X1265467Y279833D01*
X1265800Y280417D01*
Y284333D01*
G01Y283667D02*
X1265467Y284000D01*
X1264967Y284250D01*
X1264383Y284333D01*
X1263717Y284167D01*
X1263300Y283833D01*
X1262967Y283250D01*
X1262800Y282667D01*
X1262883Y282167D01*
X1263217Y281583D01*
X1263717Y281167D01*
X1264383Y281000D01*
X1264883Y281083D01*
X1265467Y281417D01*
X1265800Y281750D01*
G01X1269900Y286000D02*
Y281000D01*
G01X1268733Y284333D02*
X1271067D01*
G01X1274083Y281000D02*
Y286000D01*
G01Y283583D02*
X1274500Y284000D01*
X1274917Y284250D01*
X1275583Y284333D01*
X1276083Y284250D01*
X1276667Y283917D01*
X1276917Y283417D01*
Y281000D01*
G01X1280017Y281917D02*
X1282183D01*
G01Y283417D02*
X1280017D01*
G01X1285117Y283083D02*
X1285700Y283667D01*
X1286200Y284000D01*
X1286867Y284167D01*
X1287450Y284000D01*
X1287867Y283667D01*
X1288200Y283167D01*
X1288283Y282583D01*
X1288200Y282083D01*
X1287867Y281583D01*
X1287367Y281167D01*
X1286783Y281000D01*
X1286117Y281167D01*
X1285533Y281667D01*
X1285200Y282417D01*
X1285117Y283250D01*
X1285283Y284333D01*
X1285533Y284917D01*
X1285950Y285500D01*
X1286533Y285917D01*
X1287117Y286000D01*
X1287700Y285833D01*
X1288117Y285417D01*
G01X1291383Y282667D02*
X1293383D01*
G01X1292300Y283750D02*
Y281583D01*
G01X1296400Y280833D02*
X1299400Y286000D01*
G01X1302417Y282667D02*
X1304583D01*
G01X1307267Y281750D02*
X1307767Y281333D01*
X1308350Y281083D01*
X1309100Y281000D01*
X1309850Y281167D01*
X1310433Y281500D01*
X1310850Y282083D01*
X1310933Y282750D01*
X1310767Y283417D01*
X1310350Y283833D01*
X1309767Y284167D01*
X1309183Y284250D01*
X1308600Y284167D01*
X1307850Y283833D01*
X1308100Y286000D01*
X1310350D01*
G01X1312200Y281000D02*
Y284333D01*
G01Y283417D02*
X1312450Y283833D01*
X1312867Y284167D01*
X1313450Y284333D01*
X1314033Y284167D01*
X1314450Y283833D01*
X1314700Y283417D01*
Y281000D01*
G01Y283417D02*
X1314950Y283833D01*
X1315367Y284167D01*
X1315950Y284333D01*
X1316533Y284167D01*
X1316950Y283833D01*
X1317200Y283333D01*
Y281000D01*
G01X1320300Y284333D02*
Y281000D01*
G01Y285667D02*
X1320133Y285750D01*
Y285917D01*
X1320300Y286000D01*
X1320467Y285917D01*
Y285750D01*
X1320300Y285667D01*
G01X1325900Y281000D02*
Y286000D01*
G01X1210333Y218700D02*
Y213700D01*
X1213667D01*
G01X1216350Y217033D02*
X1218850Y213700D01*
G01Y217033D02*
X1216350Y213700D01*
G01X1207333Y260500D02*
Y255500D01*
X1210667D01*
G01X1213183D02*
Y258833D01*
G01Y258000D02*
X1213517Y258417D01*
X1214017Y258750D01*
X1214683Y258833D01*
X1215267Y258750D01*
X1215767Y258417D01*
X1216017Y257833D01*
Y255500D01*
G01X1241083Y841667D02*
X1243083D01*
G01X1242000Y842750D02*
Y840583D01*
G01X1246100Y839833D02*
X1249100Y845000D01*
G01X1252117Y841667D02*
X1254283D01*
G01X1256967Y840750D02*
X1257467Y840333D01*
X1258050Y840083D01*
X1258800Y840000D01*
X1259550Y840167D01*
X1260133Y840500D01*
X1260550Y841083D01*
X1260633Y841750D01*
X1260467Y842417D01*
X1260050Y842833D01*
X1259467Y843167D01*
X1258883Y843250D01*
X1258300Y843167D01*
X1257550Y842833D01*
X1257800Y845000D01*
X1260050D01*
G01X1261900Y840000D02*
Y843333D01*
G01Y842417D02*
X1262150Y842833D01*
X1262567Y843167D01*
X1263150Y843333D01*
X1263733Y843167D01*
X1264150Y842833D01*
X1264400Y842417D01*
Y840000D01*
G01Y842417D02*
X1264650Y842833D01*
X1265067Y843167D01*
X1265650Y843333D01*
X1266233Y843167D01*
X1266650Y842833D01*
X1266900Y842333D01*
Y840000D01*
G01X1270000Y843333D02*
Y840000D01*
G01Y844667D02*
X1269833Y844750D01*
Y844917D01*
X1270000Y845000D01*
X1270167Y844917D01*
Y844750D01*
X1270000Y844667D01*
G01X1275600Y840000D02*
Y845000D01*
G01X1241083Y826667D02*
X1243083D01*
G01X1242000Y827750D02*
Y825583D01*
G01X1246100Y824833D02*
X1249100Y830000D01*
G01X1252117Y826667D02*
X1254283D01*
G01X1256967Y825750D02*
X1257467Y825333D01*
X1258050Y825083D01*
X1258800Y825000D01*
X1259550Y825167D01*
X1260133Y825500D01*
X1260550Y826083D01*
X1260633Y826750D01*
X1260467Y827417D01*
X1260050Y827833D01*
X1259467Y828167D01*
X1258883Y828250D01*
X1258300Y828167D01*
X1257550Y827833D01*
X1257800Y830000D01*
X1260050D01*
G01X1261900Y825000D02*
Y828333D01*
G01Y827417D02*
X1262150Y827833D01*
X1262567Y828167D01*
X1263150Y828333D01*
X1263733Y828167D01*
X1264150Y827833D01*
X1264400Y827417D01*
Y825000D01*
G01Y827417D02*
X1264650Y827833D01*
X1265067Y828167D01*
X1265650Y828333D01*
X1266233Y828167D01*
X1266650Y827833D01*
X1266900Y827333D01*
Y825000D01*
G01X1270000Y828333D02*
Y825000D01*
G01Y829667D02*
X1269833Y829750D01*
Y829917D01*
X1270000Y830000D01*
X1270167Y829917D01*
Y829750D01*
X1270000Y829667D01*
G01X1275600Y825000D02*
Y830000D01*
G01X1241083Y811667D02*
X1243083D01*
G01X1242000Y812750D02*
Y810583D01*
G01X1246100Y809833D02*
X1249100Y815000D01*
G01X1252117Y811667D02*
X1254283D01*
G01X1257217Y814167D02*
X1257717Y814667D01*
X1258300Y814917D01*
X1258967Y815000D01*
X1259800Y814833D01*
X1260383Y814417D01*
X1260550Y813917D01*
X1260467Y813417D01*
X1260133Y813000D01*
X1258467Y812167D01*
X1257717Y811583D01*
X1257217Y810750D01*
X1257050Y810000D01*
X1260550D01*
G01X1261900D02*
Y813333D01*
G01Y812417D02*
X1262150Y812833D01*
X1262567Y813167D01*
X1263150Y813333D01*
X1263733Y813167D01*
X1264150Y812833D01*
X1264400Y812417D01*
Y810000D01*
G01Y812417D02*
X1264650Y812833D01*
X1265067Y813167D01*
X1265650Y813333D01*
X1266233Y813167D01*
X1266650Y812833D01*
X1266900Y812333D01*
Y810000D01*
G01X1270000Y813333D02*
Y810000D01*
G01Y814667D02*
X1269833Y814750D01*
Y814917D01*
X1270000Y815000D01*
X1270167Y814917D01*
Y814750D01*
X1270000Y814667D01*
G01X1275600Y810000D02*
Y815000D01*
G01X1242793Y785443D02*
X1241960Y786277D01*
X1241543Y787110D01*
Y790443D01*
X1241960Y791277D01*
X1242793Y792110D01*
G01X1248810Y787110D02*
Y792110D01*
X1247810Y791110D01*
G01Y787110D02*
X1249810D01*
G01X1254410Y786943D02*
X1254243Y787027D01*
Y787193D01*
X1254410Y787277D01*
X1254577Y787193D01*
Y787027D01*
X1254410Y786943D01*
G01X1258427Y791277D02*
X1258927Y791777D01*
X1259510Y792027D01*
X1260177Y792110D01*
X1261010Y791943D01*
X1261593Y791527D01*
X1261760Y791027D01*
X1261677Y790527D01*
X1261343Y790110D01*
X1259677Y789277D01*
X1258927Y788693D01*
X1258427Y787860D01*
X1258260Y787110D01*
X1261760D01*
G01X1263110D02*
Y790443D01*
G01Y789527D02*
X1263360Y789943D01*
X1263777Y790277D01*
X1264360Y790443D01*
X1264943Y790277D01*
X1265360Y789943D01*
X1265610Y789527D01*
Y787110D01*
G01Y789527D02*
X1265860Y789943D01*
X1266277Y790277D01*
X1266860Y790443D01*
X1267443Y790277D01*
X1267860Y789943D01*
X1268110Y789443D01*
Y787110D01*
G01X1268710D02*
Y790443D01*
G01Y789527D02*
X1268960Y789943D01*
X1269377Y790277D01*
X1269960Y790443D01*
X1270543Y790277D01*
X1270960Y789943D01*
X1271210Y789527D01*
Y787110D01*
G01Y789527D02*
X1271460Y789943D01*
X1271877Y790277D01*
X1272460Y790443D01*
X1273043Y790277D01*
X1273460Y789943D01*
X1273710Y789443D01*
Y787110D01*
G01X1280243D02*
Y792110D01*
X1282410Y787943D01*
X1284577Y792110D01*
Y787110D01*
G01X1289510D02*
Y790443D01*
G01Y789860D02*
X1289177Y790193D01*
X1288677Y790360D01*
X1288093Y790443D01*
X1287510Y790277D01*
X1287010Y789943D01*
X1286677Y789443D01*
X1286510Y788777D01*
X1286677Y788110D01*
X1287010Y787610D01*
X1287510Y787277D01*
X1288093Y787110D01*
X1288677Y787193D01*
X1289177Y787443D01*
X1289510Y787777D01*
G01X1292360Y790443D02*
X1294860Y787110D01*
G01Y790443D02*
X1292360Y787110D01*
G01X1299627Y785443D02*
X1300460Y786277D01*
X1300877Y787110D01*
Y790443D01*
X1300460Y791277D01*
X1299627Y792110D01*
G01X1244877Y797230D02*
X1241543Y798897D01*
X1244877Y800563D01*
G01X1247727Y798147D02*
X1249893D01*
G01Y799647D02*
X1247727D01*
G01X1254410Y802230D02*
X1253743Y802063D01*
X1253243Y801647D01*
X1252910Y801147D01*
X1252660Y800480D01*
X1252577Y799730D01*
X1252660Y798980D01*
X1252910Y798313D01*
X1253243Y797813D01*
X1253743Y797397D01*
X1254410Y797230D01*
X1255077Y797397D01*
X1255577Y797813D01*
X1255910Y798313D01*
X1256160Y798980D01*
X1256243Y799730D01*
X1256160Y800480D01*
X1255910Y801147D01*
X1255577Y801647D01*
X1255077Y802063D01*
X1254410Y802230D01*
G01X1260010Y797063D02*
X1259843Y797147D01*
Y797313D01*
X1260010Y797397D01*
X1260177Y797313D01*
Y797147D01*
X1260010Y797063D01*
G01X1265443Y797230D02*
X1265610Y798313D01*
X1265860Y799230D01*
X1266193Y800063D01*
X1266610Y800980D01*
X1267277Y802230D01*
X1263943D01*
G01X1269377Y797980D02*
X1269877Y797563D01*
X1270460Y797313D01*
X1271210Y797230D01*
X1271960Y797397D01*
X1272543Y797730D01*
X1272960Y798313D01*
X1273043Y798980D01*
X1272877Y799647D01*
X1272460Y800063D01*
X1271877Y800397D01*
X1271293Y800480D01*
X1270710Y800397D01*
X1269960Y800063D01*
X1270210Y802230D01*
X1272460D01*
G01X1275310Y797063D02*
X1278310Y802230D01*
G01X1275310D02*
X1274810Y802063D01*
X1274560Y801813D01*
X1274393Y801313D01*
X1274560Y800813D01*
X1274810Y800563D01*
X1275310Y800397D01*
X1275810Y800563D01*
X1276060Y800813D01*
X1276227Y801313D01*
X1276060Y801813D01*
X1275810Y802063D01*
X1275310Y802230D01*
G01X1278310Y798897D02*
X1277810Y798730D01*
X1277560Y798480D01*
X1277393Y797980D01*
X1277560Y797480D01*
X1277810Y797230D01*
X1278310Y797063D01*
X1278810Y797230D01*
X1279060Y797480D01*
X1279227Y797980D01*
X1279060Y798480D01*
X1278810Y798730D01*
X1278310Y798897D01*
G01X1234540Y850500D02*
Y782000D01*
G01X1343000Y850610D02*
Y782110D01*
G54D12*
G01X857602Y628479D02*
X872727D01*
G01X857602Y635354D02*
Y628479D01*
G01X865852Y635354D02*
X843852D01*
G01D02*
Y712354D01*
G01X857602Y721979D02*
Y715104D01*
G01X872727Y721979D02*
X857602D01*
G01X843852Y712354D02*
X865852D01*
G01X934602Y628479D02*
X949727D01*
G01X934602Y635354D02*
Y628479D01*
G01X942852Y635354D02*
Y712354D01*
G01X898852D02*
Y635354D01*
G01D02*
X942852D01*
G01X907102Y628479D02*
Y635354D01*
G01X891977Y628479D02*
X907102D01*
G01X891977Y721979D02*
Y628479D01*
G01X865852Y712354D02*
Y635354D01*
G01X872727Y628479D02*
Y721979D01*
G01X934602D02*
Y715104D01*
G01X949727Y721979D02*
X934602D01*
G01X942852Y712354D02*
X898852D01*
G01X907102Y715104D02*
Y721979D01*
G01D02*
X891977D01*
G01X1026727Y628479D02*
Y719229D01*
G01X1019852Y635354D02*
Y712354D01*
G01X1011602Y628479D02*
X1026727D01*
G01X1011602Y635354D02*
Y628479D01*
G01X984102D02*
Y635354D01*
G01X975852Y712354D02*
Y635354D01*
G01D02*
X1019852D01*
G01X968977Y628479D02*
X984102D01*
G01X968977Y721979D02*
Y628479D01*
G01X949727D02*
Y721979D01*
G01X1011602Y719229D02*
Y712354D01*
G01X1026727Y719229D02*
X1011602D01*
G01X984102Y715104D02*
Y721979D01*
G01X1019852Y712354D02*
X975852D01*
G01X984102Y721979D02*
X968977D01*
G01X1096852Y635354D02*
Y712354D01*
G01X1088602Y628479D02*
X1122977D01*
G01X1088602Y635354D02*
Y628479D01*
G01X1061102D02*
Y635354D01*
G01X1045977Y628479D02*
X1061102D01*
G01X1045977Y719229D02*
Y628479D01*
G01X1052852Y712354D02*
Y635354D01*
G01D02*
X1096852D01*
G01X1138102Y719229D02*
X1103727D01*
G01X1088602D02*
Y712354D01*
G01X1103727Y719229D02*
X1088602D01*
G01X1061102D02*
X1045977D01*
G01X1061102Y712354D02*
Y719229D01*
G01X1096852Y712354D02*
X1052852D01*
G01X1180727Y628479D02*
Y719229D01*
G01X1165602Y628479D02*
X1180727D01*
G01X1165602Y635354D02*
Y628479D01*
G01X1173852Y635354D02*
Y712354D01*
G01X1129852D02*
Y635354D01*
G01D02*
X1173852D01*
G01X1138102Y628479D02*
Y635354D01*
G01X1122977Y628479D02*
X1138102D01*
G01X1165602Y719229D02*
Y712354D01*
G01X1180727Y719229D02*
X1165602D01*
G01X1173852Y712354D02*
X1129852D01*
G01X1138102D02*
Y719229D01*
G01X1250852Y635354D02*
Y712354D01*
G01X1215102Y628479D02*
Y635354D01*
G01X1206852Y712354D02*
Y635354D01*
G01D02*
X1250852D01*
G01X1199977Y628479D02*
X1215102D01*
G01X1199977Y719229D02*
Y628479D01*
G01X1215102Y712354D02*
Y719229D01*
G01X1250852Y712354D02*
X1206852D01*
G01X1215102Y719229D02*
X1199977D01*
G54D13*
G01X341590Y319830D02*
Y303830D01*
G01X303090Y319830D02*
Y303830D01*
G01X352590Y340830D02*
Y357830D01*
G01X292090Y340830D02*
Y357830D01*
G01X356482Y330153D02*
X352452Y324663D01*
X356652Y324643D01*
G01X345680Y327680D02*
G02X350362Y319860I-4190J-7820D01*
G01X348190Y321780D01*
X351420Y321950D01*
X350460Y319850D01*
G01X439562Y301543D02*
X435532Y296053D01*
X439732Y296033D01*
G54D14*
G01X856340Y725829D02*
X872925D01*
G01X866485Y719229D02*
X859885Y725829D01*
G01X864151Y719229D02*
X857551Y725829D01*
G01X861818Y719229D02*
X855779Y725267D01*
G01X859485Y719229D02*
X854613Y724101D01*
G01X857327Y719053D02*
X853752Y722628D01*
G01X857327Y716720D02*
X853752Y720295D01*
G01X857327Y714387D02*
X853752Y717961D01*
G01X856750Y712629D02*
X853752Y715628D01*
G01X854417Y712629D02*
X853752Y713295D01*
G01X855058Y712629D02*
X857327Y714899D01*
G01X853752Y713657D02*
X857327Y717232D01*
G01X859323Y719229D02*
X865923Y725829D01*
G01X853752Y715991D02*
X863590Y725829D01*
G01X853752Y718324D02*
X861257Y725829D01*
G01X853752Y720657D02*
X858923Y725829D01*
G01X853752Y722991D02*
X856590Y725829D01*
G01X853752Y723240D02*
X856340Y725829D01*
G01X853752Y712629D02*
Y723240D01*
G01X857327Y712629D02*
X853752D01*
G01X857327Y719504D02*
Y712629D01*
G01X857602Y719229D02*
X857327Y719504D01*
G01X873002Y719229D02*
X857602D01*
G01X947085Y624629D02*
X943510Y628204D01*
G01X934327Y635053D02*
X934300Y635079D01*
G01X934327Y632720D02*
X931967Y635079D01*
G01X934327Y630387D02*
X930752Y633961D01*
G01X933037Y624933D02*
X936307Y628204D01*
G01X931869Y626100D02*
X934327Y628556D01*
G01X930752Y627315D02*
X934327Y630890D01*
G01X930752Y629649D02*
X934327Y633224D01*
G01X930752Y631983D02*
X933848Y635079D01*
G01X930752Y634316D02*
X931515Y635079D01*
G01X934327Y628204D02*
X950002D01*
G01X934327Y635079D02*
Y628204D01*
G01X930752Y635079D02*
X934327D01*
G01X930752Y627218D02*
Y635079D01*
G01X944750Y624629D02*
X941175Y628204D01*
G01X942417Y624629D02*
X938842Y628204D01*
G01X940084Y624629D02*
X936509Y628204D01*
G01X937750Y624629D02*
X930752Y631627D01*
G01X935417Y624629D02*
X930752Y629294D01*
G01X942066Y624629D02*
X945640Y628203D01*
G01X939733Y624629D02*
X943307Y628204D01*
G01X937399Y624629D02*
X940974Y628203D01*
G01X935066Y624629D02*
X938640Y628203D01*
G01X985362Y624629D02*
X933340D01*
G01D02*
X930752Y627218D01*
G01X891702Y675345D02*
X891096Y675951D01*
G01X890957Y676193D02*
X891702Y676936D01*
G01X889988Y677557D02*
X891702Y679270D01*
G01X888823Y678725D02*
X891702Y681604D01*
G01X887462Y679697D02*
X891702Y683937D01*
G01X885887Y680455D02*
X891702Y686270D01*
G01X884054Y680956D02*
X891702Y688604D01*
G01X881854Y681089D02*
X891702Y690937D01*
G01Y674644D02*
X891701Y674645D01*
G01X891702Y719229D02*
Y674644D01*
G01Y694013D02*
X873002Y712712D01*
G01X891702Y691679D02*
X873002Y710379D01*
G01X891702Y689346D02*
X873002Y708046D01*
G01X891702Y687012D02*
X873002Y705711D01*
G01X891702Y684678D02*
X873002Y703378D01*
G01X891702Y682345D02*
X873002Y701045D01*
G01X891702Y680012D02*
X873002Y698711D01*
G01Y690905D02*
X891702Y709604D01*
G01X873002Y693238D02*
X891702Y711938D01*
G01Y677678D02*
X873002Y696378D01*
G01X887198Y679848D02*
X873002Y694045D01*
G01X883703Y681010D02*
X873002Y691711D01*
G01X881330Y681049D02*
X873002Y689377D01*
G01X879392Y680653D02*
X873002Y687044D01*
G01X877738Y679974D02*
X873002Y684711D01*
G01X876310Y679069D02*
X873002Y682377D01*
G01X875080Y677966D02*
X873002Y680044D01*
G01X874045Y676668D02*
X873002Y677711D01*
G01X873215Y675163D02*
X873002Y675377D01*
G01X878929Y680497D02*
X891702Y693270D01*
G01X873002Y676905D02*
X891702Y695603D01*
G01X873002Y679238D02*
X891702Y697938D01*
G01X873002Y681571D02*
X891702Y700271D01*
G01X873002Y683905D02*
X891702Y702604D01*
G01X873002Y686238D02*
X891702Y704938D01*
G01X873002Y688571D02*
X891702Y707271D01*
G01X873002Y674644D02*
Y719229D01*
G01Y674645D02*
Y674644D01*
G01X891701Y674645D02*
G03X873003I-9349J-3541D01*
G01X968702Y701017D02*
X943889Y725829D01*
G01X947881Y719504D02*
X941556Y725829D01*
G01X945548Y719504D02*
X939223Y725829D01*
G01X943214Y719504D02*
X936889Y725829D01*
G01X940881Y719504D02*
X934556Y725829D01*
G01X938546Y719504D02*
X932223Y725829D01*
G01X936213Y719504D02*
X929888Y725829D01*
G01X934327Y719058D02*
X927555Y725829D01*
G01X934327Y716725D02*
X925222Y725829D01*
G01X934327Y714390D02*
X922888Y725829D01*
G01X933755Y712629D02*
X920555Y725829D01*
G01X931422Y712629D02*
X918222Y725829D01*
G01X929088Y712629D02*
X915888Y725829D01*
G01X926754Y712629D02*
X913554Y725829D01*
G01X943603Y719504D02*
X949925Y725826D01*
G01X941270Y719504D02*
X947595Y725829D01*
G01X932061Y712629D02*
X934327Y714894D01*
G01X938936Y719504D02*
X945261Y725829D01*
G01X929728Y712629D02*
X934327Y717228D01*
G01X936603Y719504D02*
X942928Y725829D01*
G01X927395Y712629D02*
X940595Y725829D01*
G01X925062Y712629D02*
X938260Y725829D01*
G01X922727Y712629D02*
X935927Y725829D01*
G01X920394Y712629D02*
X933594Y725829D01*
G01X918061Y712629D02*
X931260Y725829D01*
G01X915727Y712629D02*
X928927Y725829D01*
G01X913394Y712629D02*
X926593Y725828D01*
G01X934327Y719504D02*
Y712629D01*
G01X950002Y719504D02*
X934327D01*
G01X924420Y712629D02*
X911221Y725829D01*
G01X891779D02*
X949925D01*
G01X922087Y712629D02*
X908887Y725829D01*
G01X919754Y712629D02*
X906554Y725829D01*
G01X917420Y712629D02*
X904221Y725829D01*
G01X915087Y712629D02*
X901887Y725829D01*
G01X912754Y712629D02*
X907377Y718006D01*
G01X905840Y719543D02*
X899554Y725829D01*
G01X910421Y712629D02*
X907377Y715673D01*
G01X903507Y719543D02*
X897221Y725829D01*
G01X908086Y712629D02*
X907377Y713339D01*
G01X901173Y719543D02*
X894886Y725829D01*
G01X898840Y719543D02*
X892553Y725829D01*
G01X896507Y719543D02*
X891342Y724707D01*
G01X894172Y719543D02*
X890494Y723221D01*
G01X891927Y719455D02*
X889440Y721942D01*
G01X891702Y717347D02*
X888191Y720857D01*
G01X891702Y715014D02*
X886738Y719977D01*
G01X891702Y712680D02*
X885053Y719328D01*
G01X891702Y710347D02*
X883070Y718978D01*
G01X891702Y708014D02*
X880607Y719107D01*
G01X911061Y712629D02*
X924260Y725829D01*
G01X908727Y712629D02*
X921927Y725829D01*
G01X907377Y713613D02*
X919592Y725828D01*
G01X907377Y715946D02*
X917259Y725829D01*
G01X907377Y718280D02*
X914926Y725829D01*
G01X906307Y719543D02*
X912592Y725828D01*
G01X903972Y719543D02*
X910259Y725829D01*
G01X901639Y719543D02*
X907926Y725829D01*
G01X899306Y719543D02*
X905593Y725829D01*
G01X896972Y719543D02*
X903258Y725829D01*
G01X894639Y719543D02*
X900925Y725829D01*
G01X892306Y719543D02*
X898592Y725829D01*
G01X892015Y719543D02*
X891702Y719229D01*
G01X907157Y719543D02*
X892015D01*
G01X907377Y719504D02*
X907157Y719543D01*
G01X907377Y712629D02*
Y719504D01*
G01X934327Y712629D02*
X907377D01*
G01X891702Y705679D02*
X876553Y720829D01*
G01X874327Y723054D02*
X871552Y725829D01*
G01X891702Y703346D02*
X869219Y725829D01*
G01X891702Y701013D02*
X866886Y725829D01*
G01X891702Y698679D02*
X873002Y717379D01*
G01X871152Y719229D02*
X864552Y725829D01*
G01X891702Y696346D02*
X873002Y715046D01*
G01X868819Y719229D02*
X862219Y725829D01*
G01X873002Y695572D02*
X891702Y714272D01*
G01X873002Y697906D02*
X891702Y716605D01*
G01X873002Y700239D02*
X891702Y718939D01*
G01X873002Y702572D02*
X896258Y725829D01*
G01X873002Y704906D02*
X893925Y725829D01*
G01X873002Y707239D02*
X885106Y719344D01*
G01X873002Y709572D02*
X882382Y718952D01*
G01X873002Y711907D02*
X880270Y719174D01*
G01X873002Y714240D02*
X878496Y719734D01*
G01X873002Y716573D02*
X876971Y720542D01*
G01X873002Y718907D02*
X875655Y721560D01*
G01X870991Y719229D02*
X874536Y722775D01*
G01X868658Y719229D02*
X873618Y724189D01*
G01X866324Y719229D02*
X872924Y725829D01*
G01X863991Y719229D02*
X870591Y725829D01*
G01X861658Y719229D02*
X868258Y725829D01*
G01X872925D02*
G03X891779I9427J3024D01*
G01X987952Y632764D02*
X985637Y635078D01*
G01X987952Y630431D02*
X984377Y634006D01*
G01X987952Y628098D02*
X984377Y631673D01*
G01X987225Y626490D02*
X984377Y629338D01*
G01X986058Y625324D02*
X983178Y628204D01*
G01X984377Y629605D02*
X987952Y633180D01*
G01X984377Y631938D02*
X987517Y635079D01*
G01X984377Y634272D02*
X985184Y635079D01*
G01X987952D02*
Y627218D01*
G01X984377Y635079D02*
X987952D01*
G01X984377Y628204D02*
Y635079D01*
G01X984420Y624629D02*
X980845Y628204D01*
G01X984069Y624629D02*
X987952Y628512D01*
G01X981735Y624629D02*
X987952Y630845D01*
G01X979402Y624629D02*
X982977Y628204D01*
G01X987952Y627218D02*
X985362Y624629D01*
G01X968702Y694016D02*
X950002Y712716D01*
G01X968702Y691683D02*
X950002Y710383D01*
G01Y690901D02*
X968702Y709601D01*
G01X950002Y693234D02*
X968702Y711934D01*
G01Y689350D02*
X950002Y708049D01*
G01X968702Y687016D02*
X950002Y705716D01*
G01X968702Y684683D02*
X950002Y703383D01*
G01X968702Y682350D02*
X950002Y701048D01*
G01X968702Y680015D02*
X950002Y698715D01*
G01X968702Y677682D02*
X950002Y696382D01*
G01X968702Y675349D02*
X950002Y694048D01*
G01X968702Y673015D02*
X950002Y691715D01*
G01X968702Y670682D02*
X950002Y689382D01*
G01X968702Y668349D02*
X950002Y687048D01*
G01X968702Y666015D02*
X950002Y684715D01*
G01X968702Y663681D02*
X950002Y682381D01*
G01X968702Y661348D02*
X950002Y680047D01*
G01X968702Y659014D02*
X950002Y677714D01*
G01Y658233D02*
X968702Y676932D01*
G01X950002Y660566D02*
X968702Y679266D01*
G01X950002Y662899D02*
X968702Y681599D01*
G01X950002Y665234D02*
X968702Y683932D01*
G01X950002Y667567D02*
X968702Y686267D01*
G01X950002Y669900D02*
X968702Y688600D01*
G01X950002Y672234D02*
X968702Y690933D01*
G01X950002Y674567D02*
X968702Y693267D01*
G01X950002Y676900D02*
X968702Y695600D01*
G01X950002Y679233D02*
X968702Y697933D01*
G01X950002Y681567D02*
X968702Y700267D01*
G01X950002Y683901D02*
X968702Y702601D01*
G01X950002Y686234D02*
X968702Y704934D01*
G01X950002Y688568D02*
X968702Y707268D01*
G01Y656681D02*
X950002Y675381D01*
G01X968702Y654348D02*
X950002Y673048D01*
G01X968702Y652014D02*
X950002Y670714D01*
G01X968702Y649681D02*
X950002Y668381D01*
G01X968702Y647348D02*
X950002Y666048D01*
G01X968702Y645013D02*
X950002Y663713D01*
G01X968702Y642680D02*
X950002Y661380D01*
G01X968702Y640347D02*
X950002Y659047D01*
G01X982086Y624629D02*
X978512Y628204D01*
G01X968702Y638014D02*
X950002Y656713D01*
G01X979752Y624629D02*
X976177Y628204D01*
G01X968702Y635680D02*
X950002Y654380D01*
G01X968702Y633347D02*
X950002Y652047D01*
G01X968702Y631014D02*
X950002Y649713D01*
G01X968702Y628679D02*
X950002Y647379D01*
G01Y630232D02*
X968702Y648932D01*
G01X950002Y632565D02*
X968702Y651265D01*
G01X950002Y634898D02*
X968702Y653598D01*
G01X950002Y637232D02*
X968702Y655931D01*
G01X950002Y639565D02*
X968702Y658265D01*
G01X950002Y641898D02*
X968702Y660598D01*
G01X950002Y644232D02*
X968702Y662931D01*
G01X950002Y646565D02*
X968702Y665265D01*
G01X950002Y648899D02*
X968702Y667599D01*
G01X950002Y651233D02*
X968702Y669932D01*
G01X950002Y653566D02*
X968702Y672266D01*
G01X950002Y655899D02*
X968702Y674599D01*
G01Y628204D02*
X984377D01*
G01X968702Y719504D02*
Y628204D01*
G01X950002D02*
Y719504D01*
G01X977419Y624629D02*
X973844Y628204D01*
G01X975085Y624629D02*
X971511Y628204D01*
G01X972752Y624629D02*
X969177Y628204D01*
G01X970419Y624629D02*
X950002Y645046D01*
G01X968086Y624629D02*
X950002Y642712D01*
G01X965752Y624629D02*
X950002Y640379D01*
G01X963419Y624629D02*
X950002Y638046D01*
G01X961085Y624629D02*
X950002Y635712D01*
G01X958751Y624629D02*
X950002Y633379D01*
G01X956418Y624629D02*
X950002Y631046D01*
G01X954085Y624629D02*
X950002Y628711D01*
G01X951751Y624629D02*
X948176Y628204D01*
G01X977068Y624629D02*
X980642Y628204D01*
G01X974734Y624629D02*
X978309Y628204D01*
G01X972401Y624629D02*
X975976Y628204D01*
G01X970068Y624629D02*
X973643Y628204D01*
G01X967734Y624629D02*
X971309Y628204D01*
G01X965401Y624629D02*
X968976Y628204D01*
G01X963068Y624629D02*
X968702Y630263D01*
G01X960733Y624629D02*
X968702Y632597D01*
G01X958400Y624629D02*
X968702Y634931D01*
G01X956067Y624629D02*
X968702Y637264D01*
G01X953733Y624629D02*
X968702Y639597D01*
G01X951400Y624629D02*
X968702Y641931D01*
G01X949067Y624629D02*
X968702Y644264D01*
G01X946733Y624629D02*
X968702Y646597D01*
G01X949418Y624629D02*
X945843Y628204D01*
G01X944400Y624629D02*
X947975Y628204D01*
G01X987952Y721436D02*
X983558Y725829D01*
G01X987952Y719102D02*
X981224Y725829D01*
G01X987952Y714435D02*
X984377Y718009D01*
G01X987424Y712629D02*
X984377Y715676D01*
G01X985091Y712629D02*
X984377Y713343D01*
G01X985731Y712629D02*
X987952Y714850D01*
G01X984377Y713608D02*
X987952Y717183D01*
G01X984377Y715942D02*
X987952Y719517D01*
G01X984377Y718276D02*
X987952Y721851D01*
G01X983271Y719504D02*
X987480Y723712D01*
G01X980938Y719504D02*
X986313Y724879D01*
G01X984377Y712629D02*
Y719504D01*
G01X987952Y712629D02*
X984377D01*
G01X987952Y723240D02*
Y712629D01*
G01X985362Y725829D02*
X987952Y723240D01*
G01Y716769D02*
X978891Y725829D01*
G01X968779D02*
X985362D01*
G01X982883Y719504D02*
X976558Y725829D01*
G01X980549Y719504D02*
X974224Y725829D01*
G01X978216Y719504D02*
X971891Y725829D01*
G01X975883Y719504D02*
X969558Y725829D01*
G01X973548Y719504D02*
X968343Y724709D01*
G01X971215Y719504D02*
X967496Y723223D01*
G01X968882Y719504D02*
X966442Y721943D01*
G01X968702Y717350D02*
X965193Y720859D01*
G01X968702Y715017D02*
X963741Y719978D01*
G01X968702Y712684D02*
X962057Y719329D01*
G01X968702Y710350D02*
X960073Y718978D01*
G01X968702Y708017D02*
X957613Y719106D01*
G01X968702Y705684D02*
X953567Y720819D01*
G01X951317Y723067D02*
X948556Y725829D01*
G01X968702Y698683D02*
X950002Y717383D01*
G01X968702Y696350D02*
X950002Y715049D01*
G01X978605Y719504D02*
X984930Y725829D01*
G01X976271Y719504D02*
X982596Y725829D01*
G01X950002Y695568D02*
X968702Y714267D01*
G01X973938Y719504D02*
X980263Y725829D01*
G01X950002Y697901D02*
X968702Y716601D01*
G01X971605Y719504D02*
X977930Y725829D01*
G01X950002Y700234D02*
X968702Y718934D01*
G01X969271Y719504D02*
X975596Y725829D01*
G01X950002Y702569D02*
X973262Y725828D01*
G01X950002Y704902D02*
X970929Y725829D01*
G01X950002Y707235D02*
X962112Y719345D01*
G01X950002Y709569D02*
X959386Y718952D01*
G01X950002Y711902D02*
X957273Y719173D01*
G01X950002Y714235D02*
X955499Y719733D01*
G01X950002Y716569D02*
X953974Y720540D01*
G01X950002Y718903D02*
X952657Y721558D01*
G01X948269Y719504D02*
X951539Y722772D01*
G01X984377Y719504D02*
X968702D01*
G01X949925Y725829D02*
G03X968779I9427J3024D01*
G01X968702Y703350D02*
X946222Y725829D01*
G01X945936Y719504D02*
X950619Y724187D01*
G01X1104002Y690893D02*
X1122702Y709593D01*
G01X1104002Y693226D02*
X1122702Y711926D01*
G01Y680023D02*
X1104002Y698723D01*
G01Y658224D02*
X1122702Y676924D01*
G01X1104002Y660559D02*
X1122702Y679259D01*
G01X1104002Y662892D02*
X1122702Y681592D01*
G01X1104002Y665225D02*
X1122702Y683925D01*
G01X1104002Y667559D02*
X1122702Y686258D01*
G01X1104002Y669892D02*
X1122702Y688592D01*
G01X1104002Y672225D02*
X1122702Y690925D01*
G01X1104002Y674559D02*
X1122702Y693258D01*
G01X1104002Y676892D02*
X1122702Y695592D01*
G01X1104002Y679226D02*
X1122702Y697926D01*
G01X1104002Y681560D02*
X1122702Y700259D01*
G01X1104002Y683893D02*
X1122702Y702593D01*
G01X1104002Y686226D02*
X1122702Y704926D01*
G01X1104002Y688560D02*
X1122702Y707259D01*
G01Y677690D02*
X1104002Y696390D01*
G01X1122702Y675357D02*
X1104002Y694057D01*
G01X1122702Y673023D02*
X1104002Y691723D01*
G01X1122702Y670690D02*
X1104002Y689390D01*
G01X1122702Y668356D02*
X1104002Y687056D01*
G01X1122702Y666022D02*
X1104002Y684722D01*
G01X1122702Y663689D02*
X1104002Y682389D01*
G01X1122702Y661356D02*
X1104002Y680056D01*
G01X1122702Y659023D02*
X1104002Y677722D01*
G01X1122702Y656689D02*
X1104002Y675389D01*
G01X1122702Y654356D02*
X1104002Y673056D01*
G01X1122702Y652023D02*
X1104002Y670721D01*
G01X1122702Y649688D02*
X1104002Y668388D01*
G01X1122702Y647355D02*
X1104002Y666055D01*
G01X1108990Y632879D02*
X1122702Y646590D01*
G01X1106657Y632879D02*
X1122702Y648923D01*
G01X1104324Y632879D02*
X1122702Y651257D01*
G01X1104002Y634890D02*
X1122702Y653590D01*
G01X1104002Y637224D02*
X1122702Y655923D01*
G01X1104002Y639557D02*
X1122702Y658257D01*
G01X1104002Y641890D02*
X1122702Y660590D01*
G01X1104002Y644225D02*
X1122702Y662924D01*
G01X1104002Y646558D02*
X1122702Y665258D01*
G01X1104002Y648891D02*
X1122702Y667591D01*
G01X1104002Y651225D02*
X1122702Y669924D01*
G01X1104002Y653558D02*
X1122702Y672258D01*
G01X1104002Y655891D02*
X1122702Y674591D01*
G01Y645022D02*
X1104002Y663721D01*
G01X1122702Y642688D02*
X1104002Y661388D01*
G01X1122702Y640355D02*
X1104002Y659055D01*
G01X1122702Y638022D02*
X1104002Y656721D01*
G01X1122702Y635688D02*
X1104002Y654388D01*
G01X1122702Y633354D02*
X1104002Y652054D01*
G01X1120844Y632879D02*
X1104002Y649720D01*
G01X1118510Y632879D02*
X1104002Y647387D01*
G01X1116177Y632879D02*
X1104002Y645054D01*
G01X1113844Y632879D02*
X1104002Y642720D01*
G01X1111509Y632879D02*
X1104002Y640387D01*
G01X1109176Y632879D02*
X1104002Y638054D01*
G01X1106843Y632879D02*
X1104002Y635721D01*
G01X1104509Y632879D02*
X1104002Y633386D01*
G01X1122702Y632879D02*
X1104002D01*
G01D02*
Y714829D01*
G01Y695561D02*
X1122702Y714259D01*
G01X1104002Y697894D02*
X1120937Y714829D01*
G01X1104002Y700227D02*
X1118604Y714829D01*
G01X1104002Y702561D02*
X1116270Y714829D01*
G01X1104002Y704894D02*
X1113937Y714829D01*
G01X1104002Y707227D02*
X1111604Y714829D01*
G01X1104002Y709561D02*
X1109270Y714829D01*
G01X1104002Y711894D02*
X1106937Y714829D01*
G01X1104002Y714228D02*
X1104604Y714829D01*
G01X1122702Y701024D02*
X1108897Y714829D01*
G01X1122702Y698691D02*
X1106564Y714829D01*
G01X1122702Y696358D02*
X1104231Y714829D01*
G01X1122702Y694024D02*
X1104002Y712724D01*
G01X1122702Y691691D02*
X1104002Y710391D01*
G01X1122702Y689358D02*
X1104002Y708057D01*
G01X1122702Y687023D02*
X1104002Y705723D01*
G01X1122702Y684690D02*
X1104002Y703390D01*
G01X1122702Y682357D02*
X1104002Y701056D01*
G01Y714829D02*
X1122702D01*
G01X1181002Y690889D02*
X1199702Y709589D01*
G01X1181002Y693223D02*
X1199702Y711922D01*
G01X1181002Y658221D02*
X1199702Y676921D01*
G01X1181002Y660554D02*
X1199702Y679254D01*
G01X1181002Y662888D02*
X1199702Y681587D01*
G01X1181002Y665221D02*
X1199702Y683921D01*
G01X1181002Y667555D02*
X1199702Y686255D01*
G01X1181002Y669888D02*
X1199702Y688588D01*
G01X1181002Y672222D02*
X1199702Y690922D01*
G01X1181002Y674555D02*
X1199702Y693255D01*
G01X1181002Y676888D02*
X1199702Y695588D01*
G01X1181002Y679222D02*
X1199702Y697922D01*
G01X1181002Y681555D02*
X1199702Y700255D01*
G01X1181002Y683888D02*
X1199702Y702588D01*
G01X1181002Y686223D02*
X1199702Y704922D01*
G01X1181002Y688556D02*
X1199702Y707256D01*
G01Y684695D02*
X1181002Y703394D01*
G01X1199702Y682361D02*
X1181002Y701061D01*
G01X1199702Y680027D02*
X1181002Y698727D01*
G01X1199702Y677694D02*
X1181002Y696393D01*
G01X1199702Y675360D02*
X1181002Y694060D01*
G01X1199702Y673027D02*
X1181002Y691727D01*
G01X1199702Y670694D02*
X1181002Y689393D01*
G01X1199702Y668360D02*
X1181002Y687060D01*
G01X1199702Y666027D02*
X1181002Y684727D01*
G01X1199702Y663694D02*
X1181002Y682392D01*
G01X1199702Y661359D02*
X1181002Y680059D01*
G01X1199702Y659026D02*
X1181002Y677726D01*
G01X1190662Y632879D02*
X1199702Y641919D01*
G01X1188328Y632879D02*
X1199702Y644252D01*
G01X1185995Y632879D02*
X1199702Y646585D01*
G01X1183662Y632879D02*
X1199702Y648919D01*
G01X1181327Y632879D02*
X1199702Y651253D01*
G01X1181002Y634887D02*
X1199702Y653586D01*
G01X1181002Y637220D02*
X1199702Y655920D01*
G01X1181002Y639553D02*
X1199702Y658253D01*
G01X1181002Y641887D02*
X1199702Y660586D01*
G01X1181002Y644220D02*
X1199702Y662920D01*
G01X1181002Y646553D02*
X1199702Y665253D01*
G01X1181002Y648888D02*
X1199702Y667586D01*
G01X1181002Y651221D02*
X1199702Y669921D01*
G01X1181002Y653554D02*
X1199702Y672254D01*
G01X1181002Y655888D02*
X1199702Y674587D01*
G01Y656693D02*
X1181002Y675393D01*
G01X1199702Y654359D02*
X1181002Y673059D01*
G01X1199702Y652026D02*
X1181002Y670726D01*
G01X1199702Y649693D02*
X1181002Y668393D01*
G01X1199702Y647360D02*
X1181002Y666059D01*
G01X1199702Y645025D02*
X1181002Y663725D01*
G01X1199702Y642692D02*
X1181002Y661392D01*
G01X1199702Y640359D02*
X1181002Y659058D01*
G01X1199702Y638025D02*
X1181002Y656725D01*
G01X1199702Y635692D02*
X1181002Y654392D01*
G01X1199702Y633359D02*
X1181002Y652058D01*
G01X1197847Y632879D02*
X1181002Y649725D01*
G01X1195514Y632879D02*
X1181002Y647392D01*
G01X1193181Y632879D02*
X1181002Y645057D01*
G01X1190847Y632879D02*
X1181002Y642724D01*
G01X1188514Y632879D02*
X1181002Y640391D01*
G01X1186181Y632879D02*
X1181002Y638057D01*
G01X1183846Y632879D02*
X1181002Y635724D01*
G01X1181513Y632879D02*
X1181002Y633391D01*
G01X1199702Y632879D02*
X1181002D01*
G01D02*
Y714829D01*
G01X1120658Y632879D02*
X1122702Y634922D01*
G01X1118325Y632879D02*
X1122702Y637256D01*
G01X1115991Y632879D02*
X1122702Y639589D01*
G01X1113658Y632879D02*
X1122702Y641922D01*
G01X1111325Y632879D02*
X1122702Y644257D01*
G01Y714829D02*
Y632879D01*
G01X1181002Y695556D02*
X1199702Y714256D01*
G01X1181002Y697889D02*
X1197941Y714829D01*
G01X1181002Y700223D02*
X1195608Y714829D01*
G01X1181002Y702557D02*
X1193275Y714829D01*
G01X1181002Y704890D02*
X1190940Y714829D01*
G01X1181002Y707224D02*
X1188607Y714829D01*
G01X1181002Y709557D02*
X1186274Y714829D01*
G01X1181002Y711890D02*
X1183940Y714829D01*
G01X1181002Y714224D02*
X1181607Y714829D01*
G01X1199702Y705696D02*
X1190569Y714829D01*
G01X1199702Y703362D02*
X1188234Y714829D01*
G01X1199702Y701029D02*
X1185901Y714829D01*
G01X1199702Y698696D02*
X1183568Y714829D01*
G01X1199702Y696361D02*
X1181234Y714829D01*
G01X1199702Y694028D02*
X1181002Y712728D01*
G01X1199702Y691695D02*
X1181002Y710394D01*
G01Y714829D02*
X1199702D01*
G01Y689361D02*
X1181002Y708061D01*
G01X1199702Y687028D02*
X1181002Y705728D01*
G01X1122702Y712692D02*
X1120565Y714829D01*
G01X1122702Y710359D02*
X1118231Y714829D01*
G01X1122702Y708025D02*
X1115897Y714829D01*
G01X1122702Y705692D02*
X1113564Y714829D01*
G01X1122702Y703358D02*
X1111231Y714829D01*
G01X1197662Y632879D02*
X1199702Y634919D01*
G01X1195328Y632879D02*
X1199702Y637252D01*
G01X1192995Y632879D02*
X1199702Y639586D01*
G01Y714829D02*
Y632879D01*
G01Y712695D02*
X1197568Y714829D01*
G01X1199702Y710362D02*
X1195235Y714829D01*
G01X1199702Y708029D02*
X1192902Y714829D01*
M02*
